LOGICAL PART CROSS REFERENCE - 05-Sep-2022 AT 15:23:30

DRAWING: @TIMECARD_LIB.TIMECARD(SCH_1):PAGE3 

CAPACITOR-G105-0B104-CK,0.1UF,A  I4  C37
   1 XP3R3V_FPGA      1 @TIMECARD_LIB.TIMECARD(SCH_1):XP3R3V_FPGA
   2     SG      2 @TIMECARD_LIB.TIMECARD(SCH_1):SG

RESISTOR-G155-100R0-J0,0OHM,-  I15  R23
   2 UNNAMED_3_CONN64PGF_I61_PRSNT22      2 @TIMECARD_LIB.TIMECARD(SCH_1):UNNAMED_3_CONN64PGF_I61_PRSNT22
   1 CARD_PRESENT      1 @TIMECARD_LIB.TIMECARD(SCH_1):CARD_PRESENT

RESISTOR-G155-100R0-J0,0OHM,-  I16  R22
   2 UNNAMED_3_CONN64PGF_I61_PRSNT21      2 @TIMECARD_LIB.TIMECARD(SCH_1):UNNAMED_3_CONN64PGF_I61_PRSNT21
   1 CARD_PRESENT      1 @TIMECARD_LIB.TIMECARD(SCH_1):CARD_PRESENT

CAPACITOR-G105-0B104-CK,0.1UF,A  I35  C24
   1 C_CPU_RX_PCIE_MGT0_TXP      1 @TIMECARD_LIB.TIMECARD(SCH_1):C_CPU_RX_PCIE_MGT0_TXP
   2 CPU_RX_PCIE_MGT0_TXP      2 @TIMECARD_LIB.TIMECARD(SCH_1):CPU_RX_PCIE_MGT0_TXP

CAPACITOR-G105-0B104-CK,0.1UF,A  I36  C19
   1 C_PCIEREFCLKP      1 @TIMECARD_LIB.TIMECARD(SCH_1):C_PCIEREFCLKP
   2 PCIE_REFCLKP      2 @TIMECARD_LIB.TIMECARD(SCH_1):PCIE_REFCLKP

CAPACITOR-G105-0B104-CK,0.1UF,A  I37  C23
   1 C_PCIEREFCLKN      1 @TIMECARD_LIB.TIMECARD(SCH_1):C_PCIEREFCLKN
   2 PCIE_REFCLKN      2 @TIMECARD_LIB.TIMECARD(SCH_1):PCIE_REFCLKN

RESISTOR-G155-100R0-J0,0OHM,-  I51  R43
   2 FPGA_TMS      2 @TIMECARD_LIB.TIMECARD(SCH_1):FPGA_TMS
   1 PCIE_CONN_TMS      1 @TIMECARD_LIB.TIMECARD(SCH_1):PCIE_CONN_TMS

RESISTOR-G155-100R0-J0,0OHM,-  I52  R42
   2 FPGA_TDO      2 @TIMECARD_LIB.TIMECARD(SCH_1):FPGA_TDO
   1 PCIE_CONN_TDO      1 @TIMECARD_LIB.TIMECARD(SCH_1):PCIE_CONN_TDO

RESISTOR-G155-100R0-J0,0OHM,-  I53  R41
   2 FPGA_TDI      2 @TIMECARD_LIB.TIMECARD(SCH_1):FPGA_TDI
   1 PCIE_CONN_TDI      1 @TIMECARD_LIB.TIMECARD(SCH_1):PCIE_CONN_TDI

RESISTOR-G155-100R0-J0,0OHM,-  I54  R28
   2 FPGA_TCK      2 @TIMECARD_LIB.TIMECARD(SCH_1):FPGA_TCK
   1 PCIE_CONN_TCK      1 @TIMECARD_LIB.TIMECARD(SCH_1):PCIE_CONN_TCK

CONN_64P_GF-S_M_EF64_PCIE_P039A  I61  GF1
  B1 XP12R0V_PCIE P_12V1 @TIMECARD_LIB.TIMECARD(SCH_1):XP12R0V_PCIE
  B2 XP12R0V_PCIE P_12V2 @TIMECARD_LIB.TIMECARD(SCH_1):XP12R0V_PCIE
  B3 XP12R0V_PCIE P_12V4 @TIMECARD_LIB.TIMECARD(SCH_1):XP12R0V_PCIE
  B4     SG   GND1 @TIMECARD_LIB.TIMECARD(SCH_1):SG
  B5 PCIE_CONN_SMCLK  SMCLK @TIMECARD_LIB.TIMECARD(SCH_1):PCIE_CONN_SMCLK
  B6 PCIE_CONN_SMDAT  SMDAT @TIMECARD_LIB.TIMECARD(SCH_1):PCIE_CONN_SMDAT
  B7     SG   GND3 @TIMECARD_LIB.TIMECARD(SCH_1):SG
  B8 XP3R3V_PCIE P_3V3_1 @TIMECARD_LIB.TIMECARD(SCH_1):XP3R3V_PCIE
  B9     NC  JTAG1     NC
 B10 XP3R3V_AUX_PCIE P_3V3AUX @TIMECARD_LIB.TIMECARD(SCH_1):XP3R3V_AUX_PCIE
 B11     NC  WAKE*     NC
 B12     NC  RSVD1     NC
 B13     SG   GND5 @TIMECARD_LIB.TIMECARD(SCH_1):SG
 B14 CPU_TX_PCIE_MGT_0_RXP  PETP0 @TIMECARD_LIB.TIMECARD(SCH_1):CPU_TX_PCIE_MGT_0_RXP
 B15 CPU_TX_PCIE_MGT_0_RXN  PETN0 @TIMECARD_LIB.TIMECARD(SCH_1):CPU_TX_PCIE_MGT_0_RXN
 B16     SG   GND7 @TIMECARD_LIB.TIMECARD(SCH_1):SG
 B17 UNNAMED_3_CONN64PGF_I61_PRSNT21 PRSNT2_1* @TIMECARD_LIB.TIMECARD(SCH_1):UNNAMED_3_CONN64PGF_I61_PRSNT21
 B18     SG   GND9 @TIMECARD_LIB.TIMECARD(SCH_1):SG
 B19 CPU_TX_PCIE_MGT_1_RXP  PETP1 @TIMECARD_LIB.TIMECARD(SCH_1):CPU_TX_PCIE_MGT_1_RXP
 B20 CPU_TX_PCIE_MGT_1_RXN  PETN1 @TIMECARD_LIB.TIMECARD(SCH_1):CPU_TX_PCIE_MGT_1_RXN
 B21     SG  GND11 @TIMECARD_LIB.TIMECARD(SCH_1):SG
 B22     SG  GND12 @TIMECARD_LIB.TIMECARD(SCH_1):SG
 B23 CPU_TX_PCIE_MGT_2_RXP  PETP2 @TIMECARD_LIB.TIMECARD(SCH_1):CPU_TX_PCIE_MGT_2_RXP
 B24 CPU_TX_PCIE_MGT_2_RXN  PETN2 @TIMECARD_LIB.TIMECARD(SCH_1):CPU_TX_PCIE_MGT_2_RXN
 B25     SG  GND15 @TIMECARD_LIB.TIMECARD(SCH_1):SG
 B26     SG  GND17 @TIMECARD_LIB.TIMECARD(SCH_1):SG
 B27 CPU_TX_PCIE_MGT_3_RXP  PETP3 @TIMECARD_LIB.TIMECARD(SCH_1):CPU_TX_PCIE_MGT_3_RXP
 B28 CPU_TX_PCIE_MGT_3_RXN  PETN3 @TIMECARD_LIB.TIMECARD(SCH_1):CPU_TX_PCIE_MGT_3_RXN
 B29     SG  GND20 @TIMECARD_LIB.TIMECARD(SCH_1):SG
 B30     NC  RSVD3     NC
 B31 UNNAMED_3_CONN64PGF_I61_PRSNT22 PRSNT2_2* @TIMECARD_LIB.TIMECARD(SCH_1):UNNAMED_3_CONN64PGF_I61_PRSNT22
 B32     SG  GND22 @TIMECARD_LIB.TIMECARD(SCH_1):SG
  A1 CARD_PRESENT PRSNT1* @TIMECARD_LIB.TIMECARD(SCH_1):CARD_PRESENT
  A2 XP12R0V_PCIE P_12V3 @TIMECARD_LIB.TIMECARD(SCH_1):XP12R0V_PCIE
  A3 XP12R0V_PCIE P_12V5 @TIMECARD_LIB.TIMECARD(SCH_1):XP12R0V_PCIE
  A4     SG   GND2 @TIMECARD_LIB.TIMECARD(SCH_1):SG
  A5 PCIE_CONN_TCK  JTAG2 @TIMECARD_LIB.TIMECARD(SCH_1):PCIE_CONN_TCK
  A6 PCIE_CONN_TDI  JTAG3 @TIMECARD_LIB.TIMECARD(SCH_1):PCIE_CONN_TDI
  A7 PCIE_CONN_TDO  JTAG4 @TIMECARD_LIB.TIMECARD(SCH_1):PCIE_CONN_TDO
  A8 PCIE_CONN_TMS  JTAG5 @TIMECARD_LIB.TIMECARD(SCH_1):PCIE_CONN_TMS
  A9 XP3R3V_PCIE P_3V3_2 @TIMECARD_LIB.TIMECARD(SCH_1):XP3R3V_PCIE
 A10 XP3R3V_PCIE P_3V3_3 @TIMECARD_LIB.TIMECARD(SCH_1):XP3R3V_PCIE
 A11 PCIE_CONN_PERST_N PERST* @TIMECARD_LIB.TIMECARD(SCH_1):PCIE_CONN_PERST_N
 A12     SG   GND4 @TIMECARD_LIB.TIMECARD(SCH_1):SG
 A13 C_PCIEREFCLKP REFCLK_P @TIMECARD_LIB.TIMECARD(SCH_1):C_PCIEREFCLKP
 A14 C_PCIEREFCLKN REFCLK_N @TIMECARD_LIB.TIMECARD(SCH_1):C_PCIEREFCLKN
 A15     SG   GND6 @TIMECARD_LIB.TIMECARD(SCH_1):SG
 A16 C_CPU_RX_PCIE_MGT0_TXP  PERP0 @TIMECARD_LIB.TIMECARD(SCH_1):C_CPU_RX_PCIE_MGT0_TXP
 A17 C_CPU_RX_PCIE_MGT0_TXN  PERN0 @TIMECARD_LIB.TIMECARD(SCH_1):C_CPU_RX_PCIE_MGT0_TXN
 A18     SG   GND8 @TIMECARD_LIB.TIMECARD(SCH_1):SG
 A19     NC  RSVD2     NC
 A20     SG  GND10 @TIMECARD_LIB.TIMECARD(SCH_1):SG
 A21 C_CPU_RX_PCIE_MGT1_TXP  PERP1 @TIMECARD_LIB.TIMECARD(SCH_1):C_CPU_RX_PCIE_MGT1_TXP
 A22 C_CPU_RX_PCIE_MGT1_TXN  PERN1 @TIMECARD_LIB.TIMECARD(SCH_1):C_CPU_RX_PCIE_MGT1_TXN
 A23     SG  GND13 @TIMECARD_LIB.TIMECARD(SCH_1):SG
 A24     SG  GND14 @TIMECARD_LIB.TIMECARD(SCH_1):SG
 A25 C_CPU_RX_PCIE_MGT2_TXP  PERP2 @TIMECARD_LIB.TIMECARD(SCH_1):C_CPU_RX_PCIE_MGT2_TXP
 A26 C_CPU_RX_PCIE_MGT2_TXN  PERN2 @TIMECARD_LIB.TIMECARD(SCH_1):C_CPU_RX_PCIE_MGT2_TXN
 A27     SG  GND18 @TIMECARD_LIB.TIMECARD(SCH_1):SG
 A28     SG  GND19 @TIMECARD_LIB.TIMECARD(SCH_1):SG
 A29 C_CPU_RX_PCIE_MGT3_TXP  PERP3 @TIMECARD_LIB.TIMECARD(SCH_1):C_CPU_RX_PCIE_MGT3_TXP
 A30 C_CPU_RX_PCIE_MGT3_TXN  PERN3 @TIMECARD_LIB.TIMECARD(SCH_1):C_CPU_RX_PCIE_MGT3_TXN
 A31     SG  GND21 @TIMECARD_LIB.TIMECARD(SCH_1):SG
 A32     NC  RSVD4     NC

RESISTOR-G155-14701-01,4.7KOHMA  I62  R55
   2     SG      2 @TIMECARD_LIB.TIMECARD(SCH_1):SG
   1 PCIE_CONN_PERST_N      1 @TIMECARD_LIB.TIMECARD(SCH_1):PCIE_CONN_PERST_N

RESISTOR-G155-14701-01,4.7KOHMA  I63  R56
   2 PCIE_CONN_PERST_N      2 @TIMECARD_LIB.TIMECARD(SCH_1):PCIE_CONN_PERST_N
   1 XP3R3V      1 @TIMECARD_LIB.TIMECARD(SCH_1):XP3R3V

CAPACITOR-G105-0B104-CK,0.1UF,A  I92  C17
   1 XP3R3V_FPGA      1 @TIMECARD_LIB.TIMECARD(SCH_1):XP3R3V_FPGA
   2     SG      2 @TIMECARD_LIB.TIMECARD(SCH_1):SG

G220_10198_01-G223-10197-01  I100  U2
   1 UNNAMED_3_G2201019801_I100_EN     EN @TIMECARD_LIB.TIMECARD(SCH_1):UNNAMED_3_G2201019801_I100_EN
   2 PCIE_SMCLK SCLOUT @TIMECARD_LIB.TIMECARD(SCH_1):PCIE_SMCLK
   3 PCIE_CONN_SMCLK  SCLIN @TIMECARD_LIB.TIMECARD(SCH_1):PCIE_CONN_SMCLK
   4     SG    GND @TIMECARD_LIB.TIMECARD(SCH_1):SG
   5     NC  READY     NC
   6 PCIE_CONN_SMDAT  SDAIN @TIMECARD_LIB.TIMECARD(SCH_1):PCIE_CONN_SMDAT
   7 PCIE_SMDAT SDAOUT @TIMECARD_LIB.TIMECARD(SCH_1):PCIE_SMDAT
   8 XP3R3V_FPGA    VCC @TIMECARD_LIB.TIMECARD(SCH_1):XP3R3V_FPGA

RESISTOR-G155-14701-01,4.7KOHMA  I103  R25
   2 UNNAMED_3_G2201019801_I100_EN      2 @TIMECARD_LIB.TIMECARD(SCH_1):UNNAMED_3_G2201019801_I100_EN
   1 XP3R3V_FPGA      1 @TIMECARD_LIB.TIMECARD(SCH_1):XP3R3V_FPGA

RESISTOR-G155-133R0-01,33OHM,1%  I114  R354
   2 UNNAMED_3_G2201019801_I100_EN      2 @TIMECARD_LIB.TIMECARD(SCH_1):UNNAMED_3_G2201019801_I100_EN
   1 FPGA_OUT_I2C_BUFFER_EN      1 @TIMECARD_LIB.TIMECARD(SCH_1):FPGA_OUT_I2C_BUFFER_EN

CAPACITOR-G105-0B104-CK,0.1UF,A  I115  C25
   1 C_CPU_RX_PCIE_MGT0_TXN      1 @TIMECARD_LIB.TIMECARD(SCH_1):C_CPU_RX_PCIE_MGT0_TXN
   2 CPU_RX_PCIE_MGT0_TXN      2 @TIMECARD_LIB.TIMECARD(SCH_1):CPU_RX_PCIE_MGT0_TXN

CAPACITOR-G105-0B104-CK,0.1UF,A  I116  C26
   1 C_CPU_RX_PCIE_MGT1_TXP      1 @TIMECARD_LIB.TIMECARD(SCH_1):C_CPU_RX_PCIE_MGT1_TXP
   2 CPU_RX_PCIE_MGT1_TXP      2 @TIMECARD_LIB.TIMECARD(SCH_1):CPU_RX_PCIE_MGT1_TXP

CAPACITOR-G105-0B104-CK,0.1UF,A  I117  C27
   1 C_CPU_RX_PCIE_MGT1_TXN      1 @TIMECARD_LIB.TIMECARD(SCH_1):C_CPU_RX_PCIE_MGT1_TXN
   2 CPU_RX_PCIE_MGT1_TXN      2 @TIMECARD_LIB.TIMECARD(SCH_1):CPU_RX_PCIE_MGT1_TXN

CAPACITOR-G105-0B104-CK,0.1UF,A  I118  C28
   1 C_CPU_RX_PCIE_MGT2_TXP      1 @TIMECARD_LIB.TIMECARD(SCH_1):C_CPU_RX_PCIE_MGT2_TXP
   2 CPU_RX_PCIE_MGT2_TXP      2 @TIMECARD_LIB.TIMECARD(SCH_1):CPU_RX_PCIE_MGT2_TXP

CAPACITOR-G105-0B104-CK,0.1UF,A  I119  C34
   1 C_CPU_RX_PCIE_MGT2_TXN      1 @TIMECARD_LIB.TIMECARD(SCH_1):C_CPU_RX_PCIE_MGT2_TXN
   2 CPU_RX_PCIE_MGT2_TXN      2 @TIMECARD_LIB.TIMECARD(SCH_1):CPU_RX_PCIE_MGT2_TXN

CAPACITOR-G105-0B104-CK,0.1UF,A  I120  C35
   1 C_CPU_RX_PCIE_MGT3_TXP      1 @TIMECARD_LIB.TIMECARD(SCH_1):C_CPU_RX_PCIE_MGT3_TXP
   2 CPU_RX_PCIE_MGT3_TXP      2 @TIMECARD_LIB.TIMECARD(SCH_1):CPU_RX_PCIE_MGT3_TXP

CAPACITOR-G105-0B104-CK,0.1UF,A  I121  C36
   1 C_CPU_RX_PCIE_MGT3_TXN      1 @TIMECARD_LIB.TIMECARD(SCH_1):C_CPU_RX_PCIE_MGT3_TXN
   2 CPU_RX_PCIE_MGT3_TXN      2 @TIMECARD_LIB.TIMECARD(SCH_1):CPU_RX_PCIE_MGT3_TXN

RESISTOR-G155-100R0-J0,0OHM,-  I122  R356
   2 FPGA_PROGRAM_N      2 @TIMECARD_LIB.TIMECARD(SCH_1):FPGA_PROGRAM_N
   1 BF_PCIE_PERST_N      1 @TIMECARD_LIB.TIMECARD(SCH_1):BF_PCIE_PERST_N

CAPACITOR-G105-0C106-BM,10UF,2A  I124  C289
   1 XP3R3V_PCIE      1 @TIMECARD_LIB.TIMECARD(SCH_1):XP3R3V_PCIE
   2     SG      2 @TIMECARD_LIB.TIMECARD(SCH_1):SG

CAPACITOR-G105-0B104-EK,0.1UF,A  I126  C290
   1 XP3R3V_PCIE      1 @TIMECARD_LIB.TIMECARD(SCH_1):XP3R3V_PCIE
   2     SG      2 @TIMECARD_LIB.TIMECARD(SCH_1):SG

CAPACITOR-G105-0B104-EK,0.1UF,A  I127  C288
   1 XP3R3V_AUX_PCIE      1 @TIMECARD_LIB.TIMECARD(SCH_1):XP3R3V_AUX_PCIE
   2     SG      2 @TIMECARD_LIB.TIMECARD(SCH_1):SG

CAPACITOR-G105-0C106-BM,10UF,2A  I129  C287
   1 XP3R3V_AUX_PCIE      1 @TIMECARD_LIB.TIMECARD(SCH_1):XP3R3V_AUX_PCIE
   2     SG      2 @TIMECARD_LIB.TIMECARD(SCH_1):SG

FERRITEBEAD-G191-10101-01,26OHA  I132  L21
   1 XP3R3V_PCIE      1 @TIMECARD_LIB.TIMECARD(SCH_1):XP3R3V_PCIE
   2 XP3R3V      2 @TIMECARD_LIB.TIMECARD(SCH_1):XP3R3V

74LVC1G07_SC70_5-G220-10017-01  I134  U3
   2 PCIE_CONN_PERST_N      A @TIMECARD_LIB.TIMECARD(SCH_1):PCIE_CONN_PERST_N
   1     NC     NC     NC
   4 BF_PCIE_PERST_N      Y @TIMECARD_LIB.TIMECARD(SCH_1):BF_PCIE_PERST_N

74LVC1G07_SC70_5-G220-10017-01  I135  U3
   3     SG    GND @TIMECARD_LIB.TIMECARD(SCH_1):SG
   5 XP3R3V_FPGA    VCC @TIMECARD_LIB.TIMECARD(SCH_1):XP3R3V_FPGA

TPS3808G18DBVR_SOT23_6-G222-00A  I139  U34
   1 FPGA_IN_RST_DLY_N RESET* @TIMECARD_LIB.TIMECARD(SCH_1):FPGA_IN_RST_DLY_N
   2     SG    GND @TIMECARD_LIB.TIMECARD(SCH_1):SG
   3 PCIE_PERST_N    MR* @TIMECARD_LIB.TIMECARD(SCH_1):PCIE_PERST_N
   4 UNNAMED_3_RESISTOR_I151_2     CT @TIMECARD_LIB.TIMECARD(SCH_1):UNNAMED_3_RESISTOR_I151_2
   5 XP3R3V_FPGA  SENSE @TIMECARD_LIB.TIMECARD(SCH_1):XP3R3V_FPGA
   6 XP3R3V_FPGA    VDD @TIMECARD_LIB.TIMECARD(SCH_1):XP3R3V_FPGA

RESISTOR-G155-14701-01,4.7KOHMA  I144  R63
   2 PCIE_PERST_N      2 @TIMECARD_LIB.TIMECARD(SCH_1):PCIE_PERST_N
   1 XP3R3V_FPGA      1 @TIMECARD_LIB.TIMECARD(SCH_1):XP3R3V_FPGA

RESISTOR-G155-11002-01,10KOHM,A  I148  R167
   2 FPGA_IN_RST_DLY_N      2 @TIMECARD_LIB.TIMECARD(SCH_1):FPGA_IN_RST_DLY_N
   1 XP3R3V_FPGA      1 @TIMECARD_LIB.TIMECARD(SCH_1):XP3R3V_FPGA

RESISTOR-G155-11003-01,100KOHMA  I151  R164
   2 UNNAMED_3_RESISTOR_I151_2      2 @TIMECARD_LIB.TIMECARD(SCH_1):UNNAMED_3_RESISTOR_I151_2
   1 XP3R3V_FPGA      1 @TIMECARD_LIB.TIMECARD(SCH_1):XP3R3V_FPGA

CAPACITOR-G105-0B104-EK,0.1UF,A  I152  C250
   1 UNNAMED_3_RESISTOR_I151_2      1 @TIMECARD_LIB.TIMECARD(SCH_1):UNNAMED_3_RESISTOR_I151_2
   2     SG      2 @TIMECARD_LIB.TIMECARD(SCH_1):SG

RESISTOR-G155-133R0-01,33OHM,1%  I153  R57
   2 PCIE_PERST_N      2 @TIMECARD_LIB.TIMECARD(SCH_1):PCIE_PERST_N
   1 BF_PCIE_PERST_N      1 @TIMECARD_LIB.TIMECARD(SCH_1):BF_PCIE_PERST_N


DRAWING: @TIMECARD_LIB.TIMECARD(SCH_1):PAGE5 

RESISTOR-G155-133R0-01,33OHM,1%  I4  R59
   2 R_PCA9546_I2C_SCL      2 @TIMECARD_LIB.TIMECARD(SCH_1):R_PCA9546_I2C_SCL
   1 UNNAMED_5_CONNHDR2X2MSSMT_I12_1      1 @TIMECARD_LIB.TIMECARD(SCH_1):UNNAMED_5_CONNHDR2X2MSSMT_I126_3

PCA9546APW_TSSOP16-G223-10280-A  I33  U4
   1 UNNAMED_5_PCA9546APWTSSOP16_I33     A0 @TIMECARD_LIB.TIMECARD(SCH_1):UNNAMED_5_PCA9546APWTSSOP16_I33_A0
   2 UNNAMED_5_PCA9546APWTSSOP16_I_1     A1 @TIMECARD_LIB.TIMECARD(SCH_1):UNNAMED_5_PCA9546APWTSSOP16_I33_A1
   3 PCA9546_RST_N RESET* @TIMECARD_LIB.TIMECARD(SCH_1):PCA9546_RST_N
   4 LM75B_I2C_SDA    SD0 @TIMECARD_LIB.TIMECARD(SCH_1):LM75B_I2C_SDA
   5 LM75B_I2C_SCL    SC0 @TIMECARD_LIB.TIMECARD(SCH_1):LM75B_I2C_SCL
   6 SHT3X_I2C_SDA    SD1 @TIMECARD_LIB.TIMECARD(SCH_1):SHT3X_I2C_SDA
   7 SHT3X_I2C_SCL    SC1 @TIMECARD_LIB.TIMECARD(SCH_1):SHT3X_I2C_SCL
   9 ICP10100_I2C_SDA    SD2 @TIMECARD_LIB.TIMECARD(SCH_1):ICP10100_I2C_SDA
  10 ICP10100_I2C_SCL    SC2 @TIMECARD_LIB.TIMECARD(SCH_1):ICP10100_I2C_SCL
  11 BNO080_I2C_SDA    SD3 @TIMECARD_LIB.TIMECARD(SCH_1):BNO080_I2C_SDA
  12 BNO080_I2C_SCL    SC3 @TIMECARD_LIB.TIMECARD(SCH_1):BNO080_I2C_SCL
  13 UNNAMED_5_PCA9546APWTSSOP16_I_2     A2 @TIMECARD_LIB.TIMECARD(SCH_1):UNNAMED_5_PCA9546APWTSSOP16_I33_A2
  14 R_PCA9546_I2C_SCL    SCL @TIMECARD_LIB.TIMECARD(SCH_1):R_PCA9546_I2C_SCL
  15 R_PCA9546_I2C_SDA    SDA @TIMECARD_LIB.TIMECARD(SCH_1):R_PCA9546_I2C_SDA

CAPACITOR-G105-0B104-CK,0.1UF,A  I45  C38
   1 VDD_PCA9546A      1 @TIMECARD_LIB.TIMECARD(SCH_1):VDD_PCA9546A
   2     SG      2 @TIMECARD_LIB.TIMECARD(SCH_1):SG

RESISTOR-G155-100R0-J0,0OHM,-  I52  R61
   2 XP2R5V_FPGA      2 @TIMECARD_LIB.TIMECARD(SCH_1):XP2R5V_FPGA
   1 VDD_PCA9546A      1 @TIMECARD_LIB.TIMECARD(SCH_1):VDD_PCA9546A

PCA9546APW_TSSOP16-G223-10280-A  I54  U4
   8     SG    VSS @TIMECARD_LIB.TIMECARD(SCH_1):SG
  16 VDD_PCA9546A    VDD @TIMECARD_LIB.TIMECARD(SCH_1):VDD_PCA9546A

RESISTOR-G155-100R0-J0,0OHM,-  I55  R62
   2 XP3R3V_FPGA      2 @TIMECARD_LIB.TIMECARD(SCH_1):XP3R3V_FPGA
   1 VDD_PCA9546A      1 @TIMECARD_LIB.TIMECARD(SCH_1):VDD_PCA9546A

RESISTOR-G155-11002-01,10KOHM,A  I60  R146
   2 PCA9546_RST_N      2 @TIMECARD_LIB.TIMECARD(SCH_1):PCA9546_RST_N
   1 XP3R3V_FPGA      1 @TIMECARD_LIB.TIMECARD(SCH_1):XP3R3V_FPGA

RESISTOR-G155-14701-01,4.7KOHMA  I66  R155
   2 PCA9546_RST_N      2 @TIMECARD_LIB.TIMECARD(SCH_1):PCA9546_RST_N
   1     SG      1 @TIMECARD_LIB.TIMECARD(SCH_1):SG

RESISTOR-G155-133R0-01,33OHM,1%  I67  R145
   2 R_PCA9546_I2C_SCL      2 @TIMECARD_LIB.TIMECARD(SCH_1):R_PCA9546_I2C_SCL
   1 PCA9546_I2C_SCL      1 @TIMECARD_LIB.TIMECARD(SCH_1):PCA9546_I2C_SCL

RESISTOR-G155-133R0-01,33OHM,1%  I68  R144
   2 R_PCA9546_I2C_SDA      2 @TIMECARD_LIB.TIMECARD(SCH_1):R_PCA9546_I2C_SDA
   1 PCA9546_I2C_SDA      1 @TIMECARD_LIB.TIMECARD(SCH_1):PCA9546_I2C_SDA

RESISTOR-G155-133R0-01,33OHM,1%  I69  R26
   2 R_PCA9546_I2C_SDA      2 @TIMECARD_LIB.TIMECARD(SCH_1):R_PCA9546_I2C_SDA
   1 PCIE_SMDAT      1 @TIMECARD_LIB.TIMECARD(SCH_1):PCIE_SMDAT

RESISTOR-G155-133R0-01,33OHM,1%  I72  R27
   2 R_PCA9546_I2C_SCL      2 @TIMECARD_LIB.TIMECARD(SCH_1):R_PCA9546_I2C_SCL
   1 PCIE_SMCLK      1 @TIMECARD_LIB.TIMECARD(SCH_1):PCIE_SMCLK

RESISTOR-G155-11002-01,10KOHM,A  I80  R147
   2 R_PCA9546_I2C_SDA      2 @TIMECARD_LIB.TIMECARD(SCH_1):R_PCA9546_I2C_SDA
   1 XP3R3V_FPGA      1 @TIMECARD_LIB.TIMECARD(SCH_1):XP3R3V_FPGA

RESISTOR-G155-11002-01,10KOHM,A  I81  R148
   2 R_PCA9546_I2C_SCL      2 @TIMECARD_LIB.TIMECARD(SCH_1):R_PCA9546_I2C_SCL
   1 XP3R3V_FPGA      1 @TIMECARD_LIB.TIMECARD(SCH_1):XP3R3V_FPGA

RESISTOR-G155-14701-01,4.7KOHMA  I82  R149
   2 UNNAMED_5_PCA9546APWTSSOP16_I33      2 @TIMECARD_LIB.TIMECARD(SCH_1):UNNAMED_5_PCA9546APWTSSOP16_I33_A0
   1 XP3R3V_FPGA      1 @TIMECARD_LIB.TIMECARD(SCH_1):XP3R3V_FPGA

RESISTOR-G155-14701-01,4.7KOHMA  I83  R150
   2 UNNAMED_5_PCA9546APWTSSOP16_I_1      2 @TIMECARD_LIB.TIMECARD(SCH_1):UNNAMED_5_PCA9546APWTSSOP16_I33_A1
   1 XP3R3V_FPGA      1 @TIMECARD_LIB.TIMECARD(SCH_1):XP3R3V_FPGA

RESISTOR-G155-14701-01,4.7KOHMA  I84  R151
   2 UNNAMED_5_PCA9546APWTSSOP16_I_2      2 @TIMECARD_LIB.TIMECARD(SCH_1):UNNAMED_5_PCA9546APWTSSOP16_I33_A2
   1 XP3R3V_FPGA      1 @TIMECARD_LIB.TIMECARD(SCH_1):XP3R3V_FPGA

RESISTOR-G155-14701-01,4.7KOHMA  I85  R152
   2 UNNAMED_5_PCA9546APWTSSOP16_I33      2 @TIMECARD_LIB.TIMECARD(SCH_1):UNNAMED_5_PCA9546APWTSSOP16_I33_A0
   1     SG      1 @TIMECARD_LIB.TIMECARD(SCH_1):SG

RESISTOR-G155-14701-01,4.7KOHMA  I86  R153
   2 UNNAMED_5_PCA9546APWTSSOP16_I_1      2 @TIMECARD_LIB.TIMECARD(SCH_1):UNNAMED_5_PCA9546APWTSSOP16_I33_A1
   1     SG      1 @TIMECARD_LIB.TIMECARD(SCH_1):SG

RESISTOR-G155-14701-01,4.7KOHMA  I87  R154
   2 UNNAMED_5_PCA9546APWTSSOP16_I_2      2 @TIMECARD_LIB.TIMECARD(SCH_1):UNNAMED_5_PCA9546APWTSSOP16_I33_A2
   1     SG      1 @TIMECARD_LIB.TIMECARD(SCH_1):SG

RESISTOR-G155-133R0-01,33OHM,1%  I88  R58
   2 R_PCA9546_I2C_SDA      2 @TIMECARD_LIB.TIMECARD(SCH_1):R_PCA9546_I2C_SDA
   1 UNNAMED_5_CONNHDR2X2MSSMT_I126_      1 @TIMECARD_LIB.TIMECARD(SCH_1):UNNAMED_5_CONNHDR2X2MSSMT_I126_1

AT24MAC402_SOT23_5-A221-00002-A  I89  U7
   1 EEPROM_SCL    SCL @TIMECARD_LIB.TIMECARD(SCH_1):EEPROM_SCL
   2     SG    GND @TIMECARD_LIB.TIMECARD(SCH_1):SG
   3 PRI_EEPROM_SDA    SDA @TIMECARD_LIB.TIMECARD(SCH_1):PRI_EEPROM_SDA
   4 XP3R3V_FPGA    VCC @TIMECARD_LIB.TIMECARD(SCH_1):XP3R3V_FPGA
   5 SN_EEPROM_WP     WP @TIMECARD_LIB.TIMECARD(SCH_1):SN_EEPROM_WP

RESISTOR-G155-133R0-01,33OHM,1%  I90  R345
   2 PRI_EEPROM_SDA      2 @TIMECARD_LIB.TIMECARD(SCH_1):PRI_EEPROM_SDA
   1 EEPROM_SDA      1 @TIMECARD_LIB.TIMECARD(SCH_1):EEPROM_SDA

CAPACITOR-G105-0B104-EK,0.1UF,A  I92  C225
   1 XP3R3V_FPGA      1 @TIMECARD_LIB.TIMECARD(SCH_1):XP3R3V_FPGA
   2     SG      2 @TIMECARD_LIB.TIMECARD(SCH_1):SG

RESISTOR-G155-14701-01,4.7KOHMA  I94  R1992
   2 SN_EEPROM_WP      2 @TIMECARD_LIB.TIMECARD(SCH_1):SN_EEPROM_WP
   1 XP3R3V_FPGA      1 @TIMECARD_LIB.TIMECARD(SCH_1):XP3R3V_FPGA

RESISTOR-G155-11002-01,10KOHM,A  I95  R19
   2 EEPROM_SCL      2 @TIMECARD_LIB.TIMECARD(SCH_1):EEPROM_SCL
   1 XP3R3V_FPGA      1 @TIMECARD_LIB.TIMECARD(SCH_1):XP3R3V_FPGA

RESISTOR-G155-11002-01,10KOHM,A  I96  R1991
   2 EEPROM_SDA      2 @TIMECARD_LIB.TIMECARD(SCH_1):EEPROM_SDA
   1 XP3R3V_FPGA      1 @TIMECARD_LIB.TIMECARD(SCH_1):XP3R3V_FPGA

RESISTOR-G155-14701-01,4.7KOHMA  I97  R344
   2     SG      2 @TIMECARD_LIB.TIMECARD(SCH_1):SG
   1 SN_EEPROM_WP      1 @TIMECARD_LIB.TIMECARD(SCH_1):SN_EEPROM_WP

RESISTOR-G155-133R0-01,33OHM,1%  I100  R175
   2 EEPROM_SDA      2 @TIMECARD_LIB.TIMECARD(SCH_1):EEPROM_SDA
   1 PCIE_SMDAT      1 @TIMECARD_LIB.TIMECARD(SCH_1):PCIE_SMDAT

RESISTOR-G155-133R0-01,33OHM,1%  I101  R183
   2 EEPROM_SDA      2 @TIMECARD_LIB.TIMECARD(SCH_1):EEPROM_SDA
   1 EEPROM_I2C_SDA      1 @TIMECARD_LIB.TIMECARD(SCH_1):EEPROM_I2C_SDA

RESISTOR-G155-133R0-01,33OHM,1%  I102  R176
   2 EEPROM_SCL      2 @TIMECARD_LIB.TIMECARD(SCH_1):EEPROM_SCL
   1 PCIE_SMCLK      1 @TIMECARD_LIB.TIMECARD(SCH_1):PCIE_SMCLK

RESISTOR-G155-133R0-01,33OHM,1%  I103  R184
   2 EEPROM_SCL      2 @TIMECARD_LIB.TIMECARD(SCH_1):EEPROM_SCL
   1 EEPROM_I2C_SCL      1 @TIMECARD_LIB.TIMECARD(SCH_1):EEPROM_I2C_SCL

RESISTOR-G155-100R0-J0,0OHM,-  I111  R313
   2 EEPROM_SCL      2 @TIMECARD_LIB.TIMECARD(SCH_1):EEPROM_SCL
   1 RGB_LED_I2C_SCL      1 @TIMECARD_LIB.TIMECARD(SCH_1):RGB_LED_I2C_SCL

RESISTOR-G155-100R0-J0,0OHM,-  I112  R312
   2 EEPROM_SDA      2 @TIMECARD_LIB.TIMECARD(SCH_1):EEPROM_SDA
   1 RGB_LED_I2C_SDA      1 @TIMECARD_LIB.TIMECARD(SCH_1):RGB_LED_I2C_SDA

RESISTOR-G155-100R0-J0,0OHM,-  I115  R311
   2 R_PCA9546_I2C_SCL      2 @TIMECARD_LIB.TIMECARD(SCH_1):R_PCA9546_I2C_SCL
   1 RGB_LED_I2C_SCL      1 @TIMECARD_LIB.TIMECARD(SCH_1):RGB_LED_I2C_SCL

RESISTOR-G155-100R0-J0,0OHM,-  I116  R310
   2 R_PCA9546_I2C_SDA      2 @TIMECARD_LIB.TIMECARD(SCH_1):R_PCA9546_I2C_SDA
   1 RGB_LED_I2C_SDA      1 @TIMECARD_LIB.TIMECARD(SCH_1):RGB_LED_I2C_SDA

RESISTOR-G155-133R0-01,33OHM,1%  I125  R60
   2 PCA9546_RST_N      2 @TIMECARD_LIB.TIMECARD(SCH_1):PCA9546_RST_N
   1 FPGA_OUT_PCA9546_RST_N      1 @TIMECARD_LIB.TIMECARD(SCH_1):FPGA_OUT_PCA9546_RST_N

CONN_HDR_2X2_M_S_SMT-G200-1068A  I126  J9
   1 UNNAMED_5_CONNHDR2X2MSSMT_I126_      1 @TIMECARD_LIB.TIMECARD(SCH_1):UNNAMED_5_CONNHDR2X2MSSMT_I126_1
   2 EEPROM_SDA      2 @TIMECARD_LIB.TIMECARD(SCH_1):EEPROM_SDA
   3 UNNAMED_5_CONNHDR2X2MSSMT_I12_1      3 @TIMECARD_LIB.TIMECARD(SCH_1):UNNAMED_5_CONNHDR2X2MSSMT_I126_3
   4 EEPROM_SCL      4 @TIMECARD_LIB.TIMECARD(SCH_1):EEPROM_SCL

CONN_HDR_2X2_M_S_SMT-G200-1068A  I127  J17
   1 SN_EEPROM_WP      1 @TIMECARD_LIB.TIMECARD(SCH_1):SN_EEPROM_WP
   2     SG      2 @TIMECARD_LIB.TIMECARD(SCH_1):SG
   3 SEC_EEPROM_WP      3 @TIMECARD_LIB.TIMECARD(SCH_1):SEC_EEPROM_WP
   4     SG      4 @TIMECARD_LIB.TIMECARD(SCH_1):SG

RESISTOR-G155-13300-01,330OHM,A  I130  R1
   2 SN_EEPROM_WP      2 @TIMECARD_LIB.TIMECARD(SCH_1):SN_EEPROM_WP
   1 FPGA_OUT_SN_EEPROM_WP      1 @TIMECARD_LIB.TIMECARD(SCH_1):FPGA_OUT_SN_EEPROM_WP

24LC16BT_I_ST_TSSOP8-G221-1017A  I148  U19
   4     SG    VSS @TIMECARD_LIB.TIMECARD(SCH_1):SG
   8 XP3R3V_FPGA    VCC @TIMECARD_LIB.TIMECARD(SCH_1):XP3R3V_FPGA

24LC16BT_I_ST_TSSOP8-G221-1017A  I151  U19
   1 UNNAMED_5_24LC16BTISTTSSOP8_I15     A0 @TIMECARD_LIB.TIMECARD(SCH_1):UNNAMED_5_24LC16BTISTTSSOP8_I151_A0
   2 UNNAMED_5_24LC16BTISTTSSOP8_I_1     A1 @TIMECARD_LIB.TIMECARD(SCH_1):UNNAMED_5_24LC16BTISTTSSOP8_I151_A1
   3 UNNAMED_5_24LC16BTISTTSSOP8_I_2     A2 @TIMECARD_LIB.TIMECARD(SCH_1):UNNAMED_5_24LC16BTISTTSSOP8_I151_A2
   7 SEC_EEPROM_WP     WP @TIMECARD_LIB.TIMECARD(SCH_1):SEC_EEPROM_WP
   6 EEPROM_SCL    SCL @TIMECARD_LIB.TIMECARD(SCH_1):EEPROM_SCL
   5 SEC_EEPROM_SDA    SDA @TIMECARD_LIB.TIMECARD(SCH_1):SEC_EEPROM_SDA

RESISTOR-G155-14701-01,4.7KOHMA  I153  R158
   2 UNNAMED_5_24LC16BTISTTSSOP8_I15      2 @TIMECARD_LIB.TIMECARD(SCH_1):UNNAMED_5_24LC16BTISTTSSOP8_I151_A0
   1 XP3R3V_FPGA      1 @TIMECARD_LIB.TIMECARD(SCH_1):XP3R3V_FPGA

RESISTOR-G155-14701-01,4.7KOHMA  I156  R159
   2     SG      2 @TIMECARD_LIB.TIMECARD(SCH_1):SG
   1 UNNAMED_5_24LC16BTISTTSSOP8_I15      1 @TIMECARD_LIB.TIMECARD(SCH_1):UNNAMED_5_24LC16BTISTTSSOP8_I151_A0

RESISTOR-G155-14701-01,4.7KOHMA  I160  R160
   2 UNNAMED_5_24LC16BTISTTSSOP8_I_1      2 @TIMECARD_LIB.TIMECARD(SCH_1):UNNAMED_5_24LC16BTISTTSSOP8_I151_A1
   1 XP3R3V_FPGA      1 @TIMECARD_LIB.TIMECARD(SCH_1):XP3R3V_FPGA

RESISTOR-G155-14701-01,4.7KOHMA  I161  R162
   2 UNNAMED_5_24LC16BTISTTSSOP8_I_2      2 @TIMECARD_LIB.TIMECARD(SCH_1):UNNAMED_5_24LC16BTISTTSSOP8_I151_A2
   1 XP3R3V_FPGA      1 @TIMECARD_LIB.TIMECARD(SCH_1):XP3R3V_FPGA

RESISTOR-G155-133R0-01,33OHM,1%  I162  R45
   2 SEC_EEPROM_SDA      2 @TIMECARD_LIB.TIMECARD(SCH_1):SEC_EEPROM_SDA
   1 EEPROM_SDA      1 @TIMECARD_LIB.TIMECARD(SCH_1):EEPROM_SDA

RESISTOR-G155-14701-01,4.7KOHMA  I165  R161
   2     SG      2 @TIMECARD_LIB.TIMECARD(SCH_1):SG
   1 UNNAMED_5_24LC16BTISTTSSOP8_I_1      1 @TIMECARD_LIB.TIMECARD(SCH_1):UNNAMED_5_24LC16BTISTTSSOP8_I151_A1

RESISTOR-G155-14701-01,4.7KOHMA  I166  R163
   2     SG      2 @TIMECARD_LIB.TIMECARD(SCH_1):SG
   1 UNNAMED_5_24LC16BTISTTSSOP8_I_2      1 @TIMECARD_LIB.TIMECARD(SCH_1):UNNAMED_5_24LC16BTISTTSSOP8_I151_A2

RESISTOR-G155-14701-01,4.7KOHMA  I167  R24
   2     SG      2 @TIMECARD_LIB.TIMECARD(SCH_1):SG
   1 SEC_EEPROM_WP      1 @TIMECARD_LIB.TIMECARD(SCH_1):SEC_EEPROM_WP

RESISTOR-G155-14701-01,4.7KOHMA  I169  R3
   2 SEC_EEPROM_WP      2 @TIMECARD_LIB.TIMECARD(SCH_1):SEC_EEPROM_WP
   1 XP3R3V_FPGA      1 @TIMECARD_LIB.TIMECARD(SCH_1):XP3R3V_FPGA

CAPACITOR-G105-0B104-EK,0.1UF,A  I171  C1
   1 XP3R3V_FPGA      1 @TIMECARD_LIB.TIMECARD(SCH_1):XP3R3V_FPGA
   2     SG      2 @TIMECARD_LIB.TIMECARD(SCH_1):SG

RESISTOR-G155-13300-01,330OHM,A  I173  R2
   2 SEC_EEPROM_WP      2 @TIMECARD_LIB.TIMECARD(SCH_1):SEC_EEPROM_WP
   1 FPGA_OUT_SEC_EEPROM_WP      1 @TIMECARD_LIB.TIMECARD(SCH_1):FPGA_OUT_SEC_EEPROM_WP


DRAWING: @TIMECARD_LIB.TIMECARD(SCH_1):PAGE6 

RESISTOR-G155-14701-01,4.7KOHMA  I14  R20
   2 LM75B_I2C_SDA      2 @TIMECARD_LIB.TIMECARD(SCH_1):LM75B_I2C_SDA
   1 XP3R3V_FPGA      1 @TIMECARD_LIB.TIMECARD(SCH_1):XP3R3V_FPGA

RESISTOR-G155-133R0-01,33OHM,1%  I15  R332
   2 R_LM75B_1_I2C_SDA      2 @TIMECARD_LIB.TIMECARD(SCH_1):R_LM75B_1_I2C_SDA
   1 LM75B_I2C_SDA      1 @TIMECARD_LIB.TIMECARD(SCH_1):LM75B_I2C_SDA

RESISTOR-G155-14701-01,4.7KOHMA  I16  R21
   2 LM75B_I2C_SCL      2 @TIMECARD_LIB.TIMECARD(SCH_1):LM75B_I2C_SCL
   1 XP3R3V_FPGA      1 @TIMECARD_LIB.TIMECARD(SCH_1):XP3R3V_FPGA

RESISTOR-G155-11001-01,1KOHM,1%  I30  R334
   2     SG      2 @TIMECARD_LIB.TIMECARD(SCH_1):SG
   1 UNNAMED_6_LM75BDPTSSOP8_I34_A2      1 @TIMECARD_LIB.TIMECARD(SCH_1):UNNAMED_6_LM75BDPTSSOP8_I34_A2

RESISTOR-G155-14701-01,4.7KOHMA  I31  R333
   2 UNNAMED_6_LM75BDPTSSOP8_I34_A2      2 @TIMECARD_LIB.TIMECARD(SCH_1):UNNAMED_6_LM75BDPTSSOP8_I34_A2
   1 XP3R3V_FPGA      1 @TIMECARD_LIB.TIMECARD(SCH_1):XP3R3V_FPGA

RESISTOR-G155-11001-01,1KOHM,1%  I32  R336
   2     SG      2 @TIMECARD_LIB.TIMECARD(SCH_1):SG
   1 UNNAMED_6_LM75BDPTSSOP8_I34_A1      1 @TIMECARD_LIB.TIMECARD(SCH_1):UNNAMED_6_LM75BDPTSSOP8_I34_A1

RESISTOR-G155-11001-01,1KOHM,1%  I33  R338
   2     SG      2 @TIMECARD_LIB.TIMECARD(SCH_1):SG
   1 UNNAMED_6_LM75BDPTSSOP8_I34_A0      1 @TIMECARD_LIB.TIMECARD(SCH_1):UNNAMED_6_LM75BDPTSSOP8_I34_A0

LM75BDP_TSSOP8-G220-10215-01  I34  U8
   1 R_LM75B_1_I2C_SDA    SDA @TIMECARD_LIB.TIMECARD(SCH_1):R_LM75B_1_I2C_SDA
   2 LM75B_I2C_SCL    SCL @TIMECARD_LIB.TIMECARD(SCH_1):LM75B_I2C_SCL
   3 FPGA_IN_LM75B_INT1_N     OS @TIMECARD_LIB.TIMECARD(SCH_1):FPGA_IN_LM75B_INT1_N
   5 UNNAMED_6_LM75BDPTSSOP8_I34_A2     A2 @TIMECARD_LIB.TIMECARD(SCH_1):UNNAMED_6_LM75BDPTSSOP8_I34_A2
   6 UNNAMED_6_LM75BDPTSSOP8_I34_A1     A1 @TIMECARD_LIB.TIMECARD(SCH_1):UNNAMED_6_LM75BDPTSSOP8_I34_A1
   7 UNNAMED_6_LM75BDPTSSOP8_I34_A0     A0 @TIMECARD_LIB.TIMECARD(SCH_1):UNNAMED_6_LM75BDPTSSOP8_I34_A0

RESISTOR-G155-14701-01,4.7KOHMA  I35  R335
   2 UNNAMED_6_LM75BDPTSSOP8_I34_A1      2 @TIMECARD_LIB.TIMECARD(SCH_1):UNNAMED_6_LM75BDPTSSOP8_I34_A1
   1 XP3R3V_FPGA      1 @TIMECARD_LIB.TIMECARD(SCH_1):XP3R3V_FPGA

RESISTOR-G155-14701-01,4.7KOHMA  I36  R337
   2 UNNAMED_6_LM75BDPTSSOP8_I34_A0      2 @TIMECARD_LIB.TIMECARD(SCH_1):UNNAMED_6_LM75BDPTSSOP8_I34_A0
   1 XP3R3V_FPGA      1 @TIMECARD_LIB.TIMECARD(SCH_1):XP3R3V_FPGA

CAPACITOR-G105-0B104-EK,0.1UF,A  I37  C39
   1     SG      1 @TIMECARD_LIB.TIMECARD(SCH_1):SG
   2 XP3R3V_FPGA      2 @TIMECARD_LIB.TIMECARD(SCH_1):XP3R3V_FPGA

LM75BDP_TSSOP8-G220-10215-01  I38  U8
   8 XP3R3V_FPGA    VCC @TIMECARD_LIB.TIMECARD(SCH_1):XP3R3V_FPGA
   4     SG    GND @TIMECARD_LIB.TIMECARD(SCH_1):SG

RESISTOR-G155-14701-01,4.7KOHMA  I41  R340
   2 FPGA_IN_LM75B_INT1_N      2 @TIMECARD_LIB.TIMECARD(SCH_1):FPGA_IN_LM75B_INT1_N
   1 XP3R3V_FPGA      1 @TIMECARD_LIB.TIMECARD(SCH_1):XP3R3V_FPGA

LM75BDP_TSSOP8-G220-10215-01  I59  U35
   1 R_LM75B_2_I2C_SDA    SDA @TIMECARD_LIB.TIMECARD(SCH_1):R_LM75B_2_I2C_SDA
   2 LM75B_I2C_SCL    SCL @TIMECARD_LIB.TIMECARD(SCH_1):LM75B_I2C_SCL
   3 FPGA_IN_LM75B_INT2_N     OS @TIMECARD_LIB.TIMECARD(SCH_1):FPGA_IN_LM75B_INT2_N
   5 UNNAMED_6_LM75BDPTSSOP8_I59_A2     A2 @TIMECARD_LIB.TIMECARD(SCH_1):UNNAMED_6_LM75BDPTSSOP8_I59_A2
   6 UNNAMED_6_LM75BDPTSSOP8_I59_A1     A1 @TIMECARD_LIB.TIMECARD(SCH_1):UNNAMED_6_LM75BDPTSSOP8_I59_A1
   7 UNNAMED_6_LM75BDPTSSOP8_I59_A0     A0 @TIMECARD_LIB.TIMECARD(SCH_1):UNNAMED_6_LM75BDPTSSOP8_I59_A0

RESISTOR-G155-11001-01,1KOHM,1%  I60  R413
   2     SG      2 @TIMECARD_LIB.TIMECARD(SCH_1):SG
   1 UNNAMED_6_LM75BDPTSSOP8_I59_A1      1 @TIMECARD_LIB.TIMECARD(SCH_1):UNNAMED_6_LM75BDPTSSOP8_I59_A1

RESISTOR-G155-14701-01,4.7KOHMA  I64  R422
   2 FPGA_IN_LM75B_INT2_N      2 @TIMECARD_LIB.TIMECARD(SCH_1):FPGA_IN_LM75B_INT2_N
   1 XP3R3V_FPGA      1 @TIMECARD_LIB.TIMECARD(SCH_1):XP3R3V_FPGA

LM75BDP_TSSOP8-G220-10215-01  I66  U36
   8 XP3R3V_FPGA    VCC @TIMECARD_LIB.TIMECARD(SCH_1):XP3R3V_FPGA
   4     SG    GND @TIMECARD_LIB.TIMECARD(SCH_1):SG

CAPACITOR-G105-0B104-EK,0.1UF,A  I67  C305
   1     SG      1 @TIMECARD_LIB.TIMECARD(SCH_1):SG
   2 XP3R3V_FPGA      2 @TIMECARD_LIB.TIMECARD(SCH_1):XP3R3V_FPGA

RESISTOR-G155-14701-01,4.7KOHMA  I69  R418
   2 UNNAMED_6_LM75BDPTSSOP8_I59_A0      2 @TIMECARD_LIB.TIMECARD(SCH_1):UNNAMED_6_LM75BDPTSSOP8_I59_A0
   1 XP3R3V_FPGA      1 @TIMECARD_LIB.TIMECARD(SCH_1):XP3R3V_FPGA

RESISTOR-G155-14701-01,4.7KOHMA  I70  R412
   2 UNNAMED_6_LM75BDPTSSOP8_I59_A1      2 @TIMECARD_LIB.TIMECARD(SCH_1):UNNAMED_6_LM75BDPTSSOP8_I59_A1
   1 XP3R3V_FPGA      1 @TIMECARD_LIB.TIMECARD(SCH_1):XP3R3V_FPGA

RESISTOR-G155-14701-01,4.7KOHMA  I71  R408
   2 UNNAMED_6_LM75BDPTSSOP8_I59_A2      2 @TIMECARD_LIB.TIMECARD(SCH_1):UNNAMED_6_LM75BDPTSSOP8_I59_A2
   1 XP3R3V_FPGA      1 @TIMECARD_LIB.TIMECARD(SCH_1):XP3R3V_FPGA

RESISTOR-G155-11001-01,1KOHM,1%  I72  R416
   2     SG      2 @TIMECARD_LIB.TIMECARD(SCH_1):SG
   1 UNNAMED_6_LM75BDPTSSOP8_I59_A0      1 @TIMECARD_LIB.TIMECARD(SCH_1):UNNAMED_6_LM75BDPTSSOP8_I59_A0

RESISTOR-G155-11001-01,1KOHM,1%  I73  R409
   2     SG      2 @TIMECARD_LIB.TIMECARD(SCH_1):SG
   1 UNNAMED_6_LM75BDPTSSOP8_I59_A2      1 @TIMECARD_LIB.TIMECARD(SCH_1):UNNAMED_6_LM75BDPTSSOP8_I59_A2

RESISTOR-G155-133R0-01,33OHM,1%  I76  R406
   2 R_LM75B_2_I2C_SDA      2 @TIMECARD_LIB.TIMECARD(SCH_1):R_LM75B_2_I2C_SDA
   1 LM75B_I2C_SDA      1 @TIMECARD_LIB.TIMECARD(SCH_1):LM75B_I2C_SDA

LM75BDP_TSSOP8-G220-10215-01  I81  U36
   1 R_LM75B_3_I2C_SDA    SDA @TIMECARD_LIB.TIMECARD(SCH_1):R_LM75B_3_I2C_SDA
   2 LM75B_I2C_SCL    SCL @TIMECARD_LIB.TIMECARD(SCH_1):LM75B_I2C_SCL
   3 FPGA_IN_LM75B_INT3_N     OS @TIMECARD_LIB.TIMECARD(SCH_1):FPGA_IN_LM75B_INT3_N
   5 UNNAMED_6_LM75BDPTSSOP8_I81_A2     A2 @TIMECARD_LIB.TIMECARD(SCH_1):UNNAMED_6_LM75BDPTSSOP8_I81_A2
   6 UNNAMED_6_LM75BDPTSSOP8_I81_A1     A1 @TIMECARD_LIB.TIMECARD(SCH_1):UNNAMED_6_LM75BDPTSSOP8_I81_A1
   7 UNNAMED_6_LM75BDPTSSOP8_I81_A0     A0 @TIMECARD_LIB.TIMECARD(SCH_1):UNNAMED_6_LM75BDPTSSOP8_I81_A0

RESISTOR-G155-14701-01,4.7KOHMA  I84  R419
   2 UNNAMED_6_LM75BDPTSSOP8_I81_A0      2 @TIMECARD_LIB.TIMECARD(SCH_1):UNNAMED_6_LM75BDPTSSOP8_I81_A0
   1 XP3R3V_FPGA      1 @TIMECARD_LIB.TIMECARD(SCH_1):XP3R3V_FPGA

RESISTOR-G155-14701-01,4.7KOHMA  I85  R414
   2 UNNAMED_6_LM75BDPTSSOP8_I81_A1      2 @TIMECARD_LIB.TIMECARD(SCH_1):UNNAMED_6_LM75BDPTSSOP8_I81_A1
   1 XP3R3V_FPGA      1 @TIMECARD_LIB.TIMECARD(SCH_1):XP3R3V_FPGA

RESISTOR-G155-14701-01,4.7KOHMA  I86  R410
   2 UNNAMED_6_LM75BDPTSSOP8_I81_A2      2 @TIMECARD_LIB.TIMECARD(SCH_1):UNNAMED_6_LM75BDPTSSOP8_I81_A2
   1 XP3R3V_FPGA      1 @TIMECARD_LIB.TIMECARD(SCH_1):XP3R3V_FPGA

RESISTOR-G155-14701-01,4.7KOHMA  I88  R423
   2 FPGA_IN_LM75B_INT3_N      2 @TIMECARD_LIB.TIMECARD(SCH_1):FPGA_IN_LM75B_INT3_N
   1 XP3R3V_FPGA      1 @TIMECARD_LIB.TIMECARD(SCH_1):XP3R3V_FPGA

LM75BDP_TSSOP8-G220-10215-01  I90  U35
   8 XP3R3V_FPGA    VCC @TIMECARD_LIB.TIMECARD(SCH_1):XP3R3V_FPGA
   4     SG    GND @TIMECARD_LIB.TIMECARD(SCH_1):SG

CAPACITOR-G105-0B104-EK,0.1UF,A  I91  C306
   1     SG      1 @TIMECARD_LIB.TIMECARD(SCH_1):SG
   2 XP3R3V_FPGA      2 @TIMECARD_LIB.TIMECARD(SCH_1):XP3R3V_FPGA

RESISTOR-G155-11001-01,1KOHM,1%  I93  R417
   2     SG      2 @TIMECARD_LIB.TIMECARD(SCH_1):SG
   1 UNNAMED_6_LM75BDPTSSOP8_I81_A0      1 @TIMECARD_LIB.TIMECARD(SCH_1):UNNAMED_6_LM75BDPTSSOP8_I81_A0

RESISTOR-G155-11001-01,1KOHM,1%  I94  R415
   2     SG      2 @TIMECARD_LIB.TIMECARD(SCH_1):SG
   1 UNNAMED_6_LM75BDPTSSOP8_I81_A1      1 @TIMECARD_LIB.TIMECARD(SCH_1):UNNAMED_6_LM75BDPTSSOP8_I81_A1

RESISTOR-G155-11001-01,1KOHM,1%  I95  R411
   2     SG      2 @TIMECARD_LIB.TIMECARD(SCH_1):SG
   1 UNNAMED_6_LM75BDPTSSOP8_I81_A2      1 @TIMECARD_LIB.TIMECARD(SCH_1):UNNAMED_6_LM75BDPTSSOP8_I81_A2

RESISTOR-G155-133R0-01,33OHM,1%  I100  R407
   2 R_LM75B_3_I2C_SDA      2 @TIMECARD_LIB.TIMECARD(SCH_1):R_LM75B_3_I2C_SDA
   1 LM75B_I2C_SDA      1 @TIMECARD_LIB.TIMECARD(SCH_1):LM75B_I2C_SDA


DRAWING: @TIMECARD_LIB.TIMECARD(SCH_1):PAGE9 

RESISTOR-G155-14701-01,4.7KOHMA  I6  R74
   2 BNO080_I2C_SDA      2 @TIMECARD_LIB.TIMECARD(SCH_1):BNO080_I2C_SDA
   1 XP3R3V_FPGA      1 @TIMECARD_LIB.TIMECARD(SCH_1):XP3R3V_FPGA

RESISTOR-G155-14701-01,4.7KOHMA  I7  R75
   2 BNO080_I2C_SCL      2 @TIMECARD_LIB.TIMECARD(SCH_1):BNO080_I2C_SCL
   1 XP3R3V_FPGA      1 @TIMECARD_LIB.TIMECARD(SCH_1):XP3R3V_FPGA

RESISTOR-G155-133R0-01,33OHM,1%  I11  R77
   2 R_BNO080_I2C_SCL      2 @TIMECARD_LIB.TIMECARD(SCH_1):R_BNO080_I2C_SCL
   1 BNO080_I2C_SCL      1 @TIMECARD_LIB.TIMECARD(SCH_1):BNO080_I2C_SCL

RESISTOR-G155-133R0-01,33OHM,1%  I12  R76
   2 R_BNO080_I2C_SDA      2 @TIMECARD_LIB.TIMECARD(SCH_1):R_BNO080_I2C_SDA
   1 BNO080_I2C_SDA      1 @TIMECARD_LIB.TIMECARD(SCH_1):BNO080_I2C_SDA

XTAL_2-G131-10075-01  I16  Y1
   1 UNNAMED_9_BNO080LGA28_I29_XOUT3      1 @TIMECARD_LIB.TIMECARD(SCH_1):UNNAMED_9_BNO080LGA28_I29_XOUT32
   2 UNNAMED_9_CAPACITOR_I17_1      2 @TIMECARD_LIB.TIMECARD(SCH_1):UNNAMED_9_CAPACITOR_I17_1

CAPACITOR-G104-0A120-FJ,12PF,5%  I17  C51
   1 UNNAMED_9_CAPACITOR_I17_1      1 @TIMECARD_LIB.TIMECARD(SCH_1):UNNAMED_9_CAPACITOR_I17_1
   2     SG      2 @TIMECARD_LIB.TIMECARD(SCH_1):SG

FERRITEBEAD-G191-10097-01,600OA  I22  L19
   1 VDD_BNO085      1 @TIMECARD_LIB.TIMECARD(SCH_1):VDD_BNO085
   2 XP3R3V_FPGA      2 @TIMECARD_LIB.TIMECARD(SCH_1):XP3R3V_FPGA

CAPACITOR-G105-0C106-BM,10UF,2A  I23  C280
   1 VDD_BNO085      1 @TIMECARD_LIB.TIMECARD(SCH_1):VDD_BNO085
   2     SG      2 @TIMECARD_LIB.TIMECARD(SCH_1):SG

CAPACITOR-G105-0B104-EK,0.1UF,A  I21  C279
   1 XP3R3V_FPGA      1 @TIMECARD_LIB.TIMECARD(SCH_1):XP3R3V_FPGA
   2     SG      2 @TIMECARD_LIB.TIMECARD(SCH_1):SG

CAPACITOR-G105-0B104-EK,0.1UF,A  I24  C281
   1 VDD_BNO085      1 @TIMECARD_LIB.TIMECARD(SCH_1):VDD_BNO085
   2     SG      2 @TIMECARD_LIB.TIMECARD(SCH_1):SG

BNO080_LGA_28-A246-00002-FB,BNA  I29  U29
   4 R_BNO080_BOOT_N  BOOTN @TIMECARD_LIB.TIMECARD(SCH_1):R_BNO080_BOOT_N
   9 UNNAMED_9_BNO080LGA28_I29_CAP    CAP @TIMECARD_LIB.TIMECARD(SCH_1):UNNAMED_9_BNO080LGA28_I29_CAP
  10 UNNAMED_9_BNO080LGA28_I29_CLKSE CLKSEL0 @TIMECARD_LIB.TIMECARD(SCH_1):UNNAMED_9_BNO080LGA28_I29_CLKSEL0
  15 R_BNO080_EVN_SCL ENV_SCL @TIMECARD_LIB.TIMECARD(SCH_1):R_BNO080_EVN_SCL
  16 R_BNO080_EVN_SDA ENV_SDA @TIMECARD_LIB.TIMECARD(SCH_1):R_BNO080_EVN_SDA
   2     SG  GND_1 @TIMECARD_LIB.TIMECARD(SCH_1):SG
  25     SG  GND_2 @TIMECARD_LIB.TIMECARD(SCH_1):SG
  18 UNNAMED_9_BNO080LGA28_I29_HCS  H_CS* @TIMECARD_LIB.TIMECARD(SCH_1):UNNAMED_9_BNO080LGA28_I29_HCS
  14 R_BNO080_INT_N H_INTN @TIMECARD_LIB.TIMECARD(SCH_1):R_BNO080_INT_N
  19 R_BNO080_I2C_SCL H_SCL/SCK/RX @TIMECARD_LIB.TIMECARD(SCH_1):R_BNO080_I2C_SCL
  20 R_BNO080_I2C_SDA H_SDA/H_MISO/TX @TIMECARD_LIB.TIMECARD(SCH_1):R_BNO080_I2C_SDA
  11 R_BNO080_RST_N   RST* @TIMECARD_LIB.TIMECARD(SCH_1):R_BNO080_RST_N
   6 UNNAMED_9_BNO080LGA28_I29_PS0 PS0/WAKE @TIMECARD_LIB.TIMECARD(SCH_1):UNNAMED_9_BNO080LGA28_I29_PS0
   5 UNNAMED_9_BNO080LGA28_I29_PS1    PS1 @TIMECARD_LIB.TIMECARD(SCH_1):UNNAMED_9_BNO080LGA28_I29_PS1
   1     NC RESV_NC_1     NC
   7     NC RESV_NC_2     NC
   8     NC RESV_NC_3     NC
  12     NC RESV_NC_4     NC
  13     NC RESV_NC_5     NC
  21     NC RESV_NC_6     NC
  22     NC RESV_NC_7     NC
  23     NC RESV_NC_8     NC
  24     NC RESV_NC_9     NC
  17 BNO080_SA0 SA0/H_MOSI @TIMECARD_LIB.TIMECARD(SCH_1):BNO080_SA0
   3 VDD_BNO085    VDD @TIMECARD_LIB.TIMECARD(SCH_1):VDD_BNO085
  28 VDD_BNO085  VDDIO @TIMECARD_LIB.TIMECARD(SCH_1):VDD_BNO085
  27 UNNAMED_9_CAPACITOR_I17_1  XIN32 @TIMECARD_LIB.TIMECARD(SCH_1):UNNAMED_9_CAPACITOR_I17_1
  26 UNNAMED_9_BNO080LGA28_I29_XOUT3 XOUT32/CLKSEL1 @TIMECARD_LIB.TIMECARD(SCH_1):UNNAMED_9_BNO080LGA28_I29_XOUT32

RESISTOR-G155-133R0-01,33OHM,1%  I31  R79
   2 R_BNO080_INT_N      2 @TIMECARD_LIB.TIMECARD(SCH_1):R_BNO080_INT_N
   1 FPGA_IN_BNO080_INT_N      1 @TIMECARD_LIB.TIMECARD(SCH_1):FPGA_IN_BNO080_INT_N

RESISTOR-G155-133R0-01,33OHM,1%  I32  R80
   2 R_BNO080_BOOT_N      2 @TIMECARD_LIB.TIMECARD(SCH_1):R_BNO080_BOOT_N
   1 FPGA_OUT_BNO080_BOOT_N      1 @TIMECARD_LIB.TIMECARD(SCH_1):FPGA_OUT_BNO080_BOOT_N

RESISTOR-G155-14701-01,4.7KOHMA  I37  R304
   2 R_BNO080_BOOT_N      2 @TIMECARD_LIB.TIMECARD(SCH_1):R_BNO080_BOOT_N
   1 XP3R3V_FPGA      1 @TIMECARD_LIB.TIMECARD(SCH_1):XP3R3V_FPGA

RESISTOR-G155-14701-01,4.7KOHMA  I38  R289
   2 FPGA_IN_BNO080_INT_N      2 @TIMECARD_LIB.TIMECARD(SCH_1):FPGA_IN_BNO080_INT_N
   1 XP3R3V_FPGA      1 @TIMECARD_LIB.TIMECARD(SCH_1):XP3R3V_FPGA

RESISTOR-G155-133R0-01,33OHM,1%  I41  R78
   2 FPGA_OUT_BNO080_RST_N      2 @TIMECARD_LIB.TIMECARD(SCH_1):FPGA_OUT_BNO080_RST_N
   1 R_BNO080_RST_N      1 @TIMECARD_LIB.TIMECARD(SCH_1):R_BNO080_RST_N

RESISTOR-G155-14701-01,4.7KOHMA  I43  R301
   2     SG      2 @TIMECARD_LIB.TIMECARD(SCH_1):SG
   1 R_BNO080_RST_N      1 @TIMECARD_LIB.TIMECARD(SCH_1):R_BNO080_RST_N

RESISTOR-G155-14701-01,4.7KOHMA  I44  R291
   2 R_BNO080_RST_N      2 @TIMECARD_LIB.TIMECARD(SCH_1):R_BNO080_RST_N
   1 XP3R3V_FPGA      1 @TIMECARD_LIB.TIMECARD(SCH_1):XP3R3V_FPGA

RESISTOR-G155-11001-01,1KOHM,1%  I47  R307
   2     SG      2 @TIMECARD_LIB.TIMECARD(SCH_1):SG
   1 UNNAMED_9_BNO080LGA28_I29_CLKSE      1 @TIMECARD_LIB.TIMECARD(SCH_1):UNNAMED_9_BNO080LGA28_I29_CLKSEL0

RESISTOR-G155-11001-01,1KOHM,1%  I49  R305
   2     SG      2 @TIMECARD_LIB.TIMECARD(SCH_1):SG
   1 UNNAMED_9_BNO080LGA28_I29_PS0      1 @TIMECARD_LIB.TIMECARD(SCH_1):UNNAMED_9_BNO080LGA28_I29_PS0

RESISTOR-G155-11001-01,1KOHM,1%  I50  R303
   2     SG      2 @TIMECARD_LIB.TIMECARD(SCH_1):SG
   1 UNNAMED_9_BNO080LGA28_I29_PS1      1 @TIMECARD_LIB.TIMECARD(SCH_1):UNNAMED_9_BNO080LGA28_I29_PS1

RESISTOR-G155-14701-01,4.7KOHMA  I51  R290
   2 BNO080_SA0      2 @TIMECARD_LIB.TIMECARD(SCH_1):BNO080_SA0
   1 XP3R3V_FPGA      1 @TIMECARD_LIB.TIMECARD(SCH_1):XP3R3V_FPGA

RESISTOR-G155-11001-01,1KOHM,1%  I52  R302
   2     SG      2 @TIMECARD_LIB.TIMECARD(SCH_1):SG
   1 BNO080_SA0      1 @TIMECARD_LIB.TIMECARD(SCH_1):BNO080_SA0

CAPACITOR-G105-0B104-CK,0.1UF,A  I53  C285
   1 UNNAMED_9_BNO080LGA28_I29_CAP      1 @TIMECARD_LIB.TIMECARD(SCH_1):UNNAMED_9_BNO080LGA28_I29_CAP
   2     SG      2 @TIMECARD_LIB.TIMECARD(SCH_1):SG

CAPACITOR-G104-0A120-FJ,12PF,5%  I54  C47
   1 UNNAMED_9_BNO080LGA28_I29_XOUT3      1 @TIMECARD_LIB.TIMECARD(SCH_1):UNNAMED_9_BNO080LGA28_I29_XOUT32
   2     SG      2 @TIMECARD_LIB.TIMECARD(SCH_1):SG

RESISTOR-G155-14701-01,4.7KOHMA  I55  R306
   2 UNNAMED_9_BNO080LGA28_I29_CLKSE      2 @TIMECARD_LIB.TIMECARD(SCH_1):UNNAMED_9_BNO080LGA28_I29_CLKSEL0
   1 XP3R3V_FPGA      1 @TIMECARD_LIB.TIMECARD(SCH_1):XP3R3V_FPGA

TP_PIONT-TP010CT020B030_PTH-TPA  I63  TP61
   1 UNNAMED_9_BNO080LGA28_I29_HCS      1 @TIMECARD_LIB.TIMECARD(SCH_1):UNNAMED_9_BNO080LGA28_I29_HCS

RESISTOR-G155-133R0-01,33OHM,1%  I64  R330
   2 BNO080_EVN_SDA      2 @TIMECARD_LIB.TIMECARD(SCH_1):BNO080_EVN_SDA
   1 R_BNO080_EVN_SDA      1 @TIMECARD_LIB.TIMECARD(SCH_1):R_BNO080_EVN_SDA

RESISTOR-G155-14701-01,4.7KOHMA  I65  R341
   2 BNO080_EVN_SDA      2 @TIMECARD_LIB.TIMECARD(SCH_1):BNO080_EVN_SDA
   1 XP3R3V_FPGA      1 @TIMECARD_LIB.TIMECARD(SCH_1):XP3R3V_FPGA

RESISTOR-G155-14701-01,4.7KOHMA  I66  R342
   2 BNO080_EVN_SCL      2 @TIMECARD_LIB.TIMECARD(SCH_1):BNO080_EVN_SCL
   1 XP3R3V_FPGA      1 @TIMECARD_LIB.TIMECARD(SCH_1):XP3R3V_FPGA

RESISTOR-G155-133R0-01,33OHM,1%  I67  R363
   2 BNO080_EVN_SCL      2 @TIMECARD_LIB.TIMECARD(SCH_1):BNO080_EVN_SCL
   1 R_BNO080_EVN_SCL      1 @TIMECARD_LIB.TIMECARD(SCH_1):R_BNO080_EVN_SCL

RESISTOR-G155-11004-01,1MOHM,1%  I70  R168
   2 UNNAMED_9_BNO080LGA28_I29_XOUT3      2 @TIMECARD_LIB.TIMECARD(SCH_1):UNNAMED_9_BNO080LGA28_I29_XOUT32
   1 UNNAMED_9_CAPACITOR_I17_1      1 @TIMECARD_LIB.TIMECARD(SCH_1):UNNAMED_9_CAPACITOR_I17_1

TP_PIONT-TP010CT020B030_PTH-TPA  I71  TP1
   1 BNO080_EVN_SDA      1 @TIMECARD_LIB.TIMECARD(SCH_1):BNO080_EVN_SDA

TP_PIONT-TP010CT020B030_PTH-TPA  I72  TP2
   1 BNO080_EVN_SCL      1 @TIMECARD_LIB.TIMECARD(SCH_1):BNO080_EVN_SCL


DRAWING: @TIMECARD_LIB.TIMECARD(SCH_1):PAGE14 

OPTICAL-G170-10143-01  I11  DS2
   A UNNAMED_14_OPTICAL_I11_A      A @TIMECARD_LIB.TIMECARD(SCH_1):UNNAMED_14_OPTICAL_I11_A
   C LED_DATOUT2      C @TIMECARD_LIB.TIMECARD(SCH_1):LED_DATOUT2

OPTICAL-G170-10143-01  I12  DS1
   A UNNAMED_14_OPTICAL_I12_A      A @TIMECARD_LIB.TIMECARD(SCH_1):UNNAMED_14_OPTICAL_I12_A
   C LED_DATOUT3      C @TIMECARD_LIB.TIMECARD(SCH_1):LED_DATOUT3

RESISTOR-G155-11001-01,1KOHM,1%  I44  R180
   2 XP5R0V      2 @TIMECARD_LIB.TIMECARD(SCH_1):XP5R0V
   1 UNNAMED_14_OPTICAL_I142_A      1 @TIMECARD_LIB.TIMECARD(SCH_1):UNNAMED_14_OPTICAL_I142_A

RESISTOR-G155-11000-01,100OHM,A  I58  R108
   2 UNNAMED_14_RESISTOR_I58_2      2 @TIMECARD_LIB.TIMECARD(SCH_1):UNNAMED_14_RESISTOR_I58_2
   1 UNNAMED_14_OPTICAL_I141_A      1 @TIMECARD_LIB.TIMECARD(SCH_1):UNNAMED_14_OPTICAL_I141_A

RESISTOR-G155-133R0-01,33OHM,1%  I60  R139
   2 XP2R5V_FPGA      2 @TIMECARD_LIB.TIMECARD(SCH_1):XP2R5V_FPGA
   1 UNNAMED_14_RESISTOR_I58_2      1 @TIMECARD_LIB.TIMECARD(SCH_1):UNNAMED_14_RESISTOR_I58_2

RESISTOR-G155-13300-01,330OHM,A  I63  R138
   2 XP3R3V_FPGA      2 @TIMECARD_LIB.TIMECARD(SCH_1):XP3R3V_FPGA
   1 UNNAMED_14_OPTICAL_I140_A      1 @TIMECARD_LIB.TIMECARD(SCH_1):UNNAMED_14_OPTICAL_I140_A

RESISTOR-G155-11001-01,1KOHM,1%  I65  R256
   2 UNNAMED_14_RESISTOR_I65_2      2 @TIMECARD_LIB.TIMECARD(SCH_1):UNNAMED_14_RESISTOR_I65_2
   1 UNNAMED_14_OPTICAL_I143_A      1 @TIMECARD_LIB.TIMECARD(SCH_1):UNNAMED_14_OPTICAL_I143_A

RESISTOR-G155-11001-01,1KOHM,1%  I66  R262
   2 XP12R0V      2 @TIMECARD_LIB.TIMECARD(SCH_1):XP12R0V
   1 UNNAMED_14_RESISTOR_I65_2      1 @TIMECARD_LIB.TIMECARD(SCH_1):UNNAMED_14_RESISTOR_I65_2

RESISTOR-G155-13300-01,330OHM,A  I67  R257
   2 XP3R3V_FPGA      2 @TIMECARD_LIB.TIMECARD(SCH_1):XP3R3V_FPGA
   1 UNNAMED_14_OPTICAL_I12_A      1 @TIMECARD_LIB.TIMECARD(SCH_1):UNNAMED_14_OPTICAL_I12_A

RESISTOR-G155-13300-01,330OHM,A  I68  R258
   2 XP3R3V_FPGA      2 @TIMECARD_LIB.TIMECARD(SCH_1):XP3R3V_FPGA
   1 UNNAMED_14_OPTICAL_I11_A      1 @TIMECARD_LIB.TIMECARD(SCH_1):UNNAMED_14_OPTICAL_I11_A

RESISTOR-G155-13300-01,330OHM,A  I69  R259
   2 XP3R3V_FPGA      2 @TIMECARD_LIB.TIMECARD(SCH_1):XP3R3V_FPGA
   1 UNNAMED_14_OPTICAL_I136_A      1 @TIMECARD_LIB.TIMECARD(SCH_1):UNNAMED_14_OPTICAL_I136_A

RESISTOR-G155-13300-01,330OHM,A  I70  R261
   2 XP3R3V_FPGA      2 @TIMECARD_LIB.TIMECARD(SCH_1):XP3R3V_FPGA
   1 UNNAMED_14_OPTICAL_I137_A      1 @TIMECARD_LIB.TIMECARD(SCH_1):UNNAMED_14_OPTICAL_I137_A

RESISTOR-G155-13300-01,330OHM,A  I72  R279
   2 XP3R3V_FPGA      2 @TIMECARD_LIB.TIMECARD(SCH_1):XP3R3V_FPGA
   1 UNNAMED_14_OPTICAL_I138_A      1 @TIMECARD_LIB.TIMECARD(SCH_1):UNNAMED_14_OPTICAL_I138_A

RESISTOR-G155-13300-01,330OHM,A  I74  R280
   2 XP3R3V_FPGA      2 @TIMECARD_LIB.TIMECARD(SCH_1):XP3R3V_FPGA
   1 UNNAMED_14_OPTICAL_I139_A      1 @TIMECARD_LIB.TIMECARD(SCH_1):UNNAMED_14_OPTICAL_I139_A

RESISTOR-G155-133R0-01,33OHM,1%  I107  R385
   2 UNNAMED_14_LED4PV14_I265_1      2 @TIMECARD_LIB.TIMECARD(SCH_1):UNNAMED_14_LED4PV14_I265_1
   1 SMA1_LED_BLUE_N      1 @TIMECARD_LIB.TIMECARD(SCH_1):SMA1_LED_BLUE_N

RESISTOR-G155-133R0-01,33OHM,1%  I108  R386
   2 UNNAMED_14_LED4PV14_I265_4      2 @TIMECARD_LIB.TIMECARD(SCH_1):UNNAMED_14_LED4PV14_I265_4
   1 SMA1_LED_GREEN_N      1 @TIMECARD_LIB.TIMECARD(SCH_1):SMA1_LED_GREEN_N

RESISTOR-G155-133R0-01,33OHM,1%  I110  R387
   2 UNNAMED_14_LED4PV14_I265_3      2 @TIMECARD_LIB.TIMECARD(SCH_1):UNNAMED_14_LED4PV14_I265_3
   1 SMA1_LED_RED_N      1 @TIMECARD_LIB.TIMECARD(SCH_1):SMA1_LED_RED_N

OPTICAL-G170-10143-01  I136  DS3
   A UNNAMED_14_OPTICAL_I136_A      A @TIMECARD_LIB.TIMECARD(SCH_1):UNNAMED_14_OPTICAL_I136_A
   C LED_DATOUT1      C @TIMECARD_LIB.TIMECARD(SCH_1):LED_DATOUT1

OPTICAL-G170-10143-01  I137  DS4
   A UNNAMED_14_OPTICAL_I137_A      A @TIMECARD_LIB.TIMECARD(SCH_1):UNNAMED_14_OPTICAL_I137_A
   C LED_DATOUT0      C @TIMECARD_LIB.TIMECARD(SCH_1):LED_DATOUT0

OPTICAL-G170-10143-01  I138  DS10
   A UNNAMED_14_OPTICAL_I138_A      A @TIMECARD_LIB.TIMECARD(SCH_1):UNNAMED_14_OPTICAL_I138_A
   C FPGA_USR_LED1      C @TIMECARD_LIB.TIMECARD(SCH_1):FPGA_USR_LED1

OPTICAL-G170-10143-01  I139  DS11
   A UNNAMED_14_OPTICAL_I139_A      A @TIMECARD_LIB.TIMECARD(SCH_1):UNNAMED_14_OPTICAL_I139_A
   C FPGA_USR_LED0      C @TIMECARD_LIB.TIMECARD(SCH_1):FPGA_USR_LED0

OPTICAL-G170-10143-01  I140  DS6
   A UNNAMED_14_OPTICAL_I140_A      A @TIMECARD_LIB.TIMECARD(SCH_1):UNNAMED_14_OPTICAL_I140_A
   C     SG      C @TIMECARD_LIB.TIMECARD(SCH_1):SG

OPTICAL-G170-10143-01  I141  DS7
   A UNNAMED_14_OPTICAL_I141_A      A @TIMECARD_LIB.TIMECARD(SCH_1):UNNAMED_14_OPTICAL_I141_A
   C     SG      C @TIMECARD_LIB.TIMECARD(SCH_1):SG

OPTICAL-G170-10143-01  I142  DS8
   A UNNAMED_14_OPTICAL_I142_A      A @TIMECARD_LIB.TIMECARD(SCH_1):UNNAMED_14_OPTICAL_I142_A
   C     SG      C @TIMECARD_LIB.TIMECARD(SCH_1):SG

OPTICAL-G170-10143-01  I143  DS5
   A UNNAMED_14_OPTICAL_I143_A      A @TIMECARD_LIB.TIMECARD(SCH_1):UNNAMED_14_OPTICAL_I143_A
   C     SG      C @TIMECARD_LIB.TIMECARD(SCH_1):SG

RESISTOR-G155-133R0-01,33OHM,1%  I146  R390
   2 UNNAMED_14_LED4PV14_I266_3      2 @TIMECARD_LIB.TIMECARD(SCH_1):UNNAMED_14_LED4PV14_I266_3
   1 SMA2_LED_RED_N      1 @TIMECARD_LIB.TIMECARD(SCH_1):SMA2_LED_RED_N

RESISTOR-G155-133R0-01,33OHM,1%  I147  R388
   2 UNNAMED_14_LED4PV14_I266_1      2 @TIMECARD_LIB.TIMECARD(SCH_1):UNNAMED_14_LED4PV14_I266_1
   1 SMA2_LED_BLUE_N      1 @TIMECARD_LIB.TIMECARD(SCH_1):SMA2_LED_BLUE_N

RESISTOR-G155-133R0-01,33OHM,1%  I148  R389
   2 UNNAMED_14_LED4PV14_I266_4      2 @TIMECARD_LIB.TIMECARD(SCH_1):UNNAMED_14_LED4PV14_I266_4
   1 SMA2_LED_GREEN_N      1 @TIMECARD_LIB.TIMECARD(SCH_1):SMA2_LED_GREEN_N

RESISTOR-G155-133R0-01,33OHM,1%  I149  R392
   2 UNNAMED_14_LED4PV14_I267_4      2 @TIMECARD_LIB.TIMECARD(SCH_1):UNNAMED_14_LED4PV14_I267_4
   1 SMA3_LED_GREEN_N      1 @TIMECARD_LIB.TIMECARD(SCH_1):SMA3_LED_GREEN_N

RESISTOR-G155-133R0-01,33OHM,1%  I150  R391
   2 UNNAMED_14_LED4PV14_I267_1      2 @TIMECARD_LIB.TIMECARD(SCH_1):UNNAMED_14_LED4PV14_I267_1
   1 SMA3_LED_BLUE_N      1 @TIMECARD_LIB.TIMECARD(SCH_1):SMA3_LED_BLUE_N

RESISTOR-G155-133R0-01,33OHM,1%  I151  R393
   2 UNNAMED_14_LED4PV14_I267_3      2 @TIMECARD_LIB.TIMECARD(SCH_1):UNNAMED_14_LED4PV14_I267_3
   1 SMA3_LED_RED_N      1 @TIMECARD_LIB.TIMECARD(SCH_1):SMA3_LED_RED_N

RESISTOR-G155-133R0-01,33OHM,1%  I152  R395
   2 UNNAMED_14_LED4PV14_I268_4      2 @TIMECARD_LIB.TIMECARD(SCH_1):UNNAMED_14_LED4PV14_I268_4
   1 SMA4_LED_GREEN_N      1 @TIMECARD_LIB.TIMECARD(SCH_1):SMA4_LED_GREEN_N

RESISTOR-G155-133R0-01,33OHM,1%  I153  R394
   2 UNNAMED_14_LED4PV14_I268_1      2 @TIMECARD_LIB.TIMECARD(SCH_1):UNNAMED_14_LED4PV14_I268_1
   1 SMA4_LED_BLUE_N      1 @TIMECARD_LIB.TIMECARD(SCH_1):SMA4_LED_BLUE_N

RESISTOR-G155-133R0-01,33OHM,1%  I154  R396
   2 UNNAMED_14_LED4PV14_I268_3      2 @TIMECARD_LIB.TIMECARD(SCH_1):UNNAMED_14_LED4PV14_I268_3
   1 SMA4_LED_RED_N      1 @TIMECARD_LIB.TIMECARD(SCH_1):SMA4_LED_RED_N

RESISTOR-G155-133R0-01,33OHM,1%  I155  R398
   2 UNNAMED_14_LED4PV14_I269_4      2 @TIMECARD_LIB.TIMECARD(SCH_1):UNNAMED_14_LED4PV14_I269_4
   1 GPS_SMA_LED_GREEN_N      1 @TIMECARD_LIB.TIMECARD(SCH_1):GPS_SMA_LED_GREEN_N

RESISTOR-G155-133R0-01,33OHM,1%  I156  R397
   2 UNNAMED_14_LED4PV14_I269_1      2 @TIMECARD_LIB.TIMECARD(SCH_1):UNNAMED_14_LED4PV14_I269_1
   1 GPS_SMA_LED_BLUE_N      1 @TIMECARD_LIB.TIMECARD(SCH_1):GPS_SMA_LED_BLUE_N

RESISTOR-G155-133R0-01,33OHM,1%  I157  R399
   2 UNNAMED_14_LED4PV14_I269_3      2 @TIMECARD_LIB.TIMECARD(SCH_1):UNNAMED_14_LED4PV14_I269_3
   1 GPS_SMA_LED_RED_N      1 @TIMECARD_LIB.TIMECARD(SCH_1):GPS_SMA_LED_RED_N

RESISTOR-G155-11000-01,100OHM,A  I160  R124
   2 UNNAMED_14_LED4PV14_I265_1      2 @TIMECARD_LIB.TIMECARD(SCH_1):UNNAMED_14_LED4PV14_I265_1
   1 FPGA_OUT_SMA1_LED_BLUE_N      1 @TIMECARD_LIB.TIMECARD(SCH_1):FPGA_OUT_SMA1_LED_BLUE_N

RESISTOR-G155-11000-01,100OHM,A  I161  R125
   2 UNNAMED_14_LED4PV14_I265_4      2 @TIMECARD_LIB.TIMECARD(SCH_1):UNNAMED_14_LED4PV14_I265_4
   1 FPGA_OUT_SMA1_LED_GREEN_N      1 @TIMECARD_LIB.TIMECARD(SCH_1):FPGA_OUT_SMA1_LED_GREEN_N

RESISTOR-G155-11000-01,100OHM,A  I163  R272
   2 UNNAMED_14_LED4PV14_I265_3      2 @TIMECARD_LIB.TIMECARD(SCH_1):UNNAMED_14_LED4PV14_I265_3
   1 FPGA_OUT_SMA1_LED_RED_N      1 @TIMECARD_LIB.TIMECARD(SCH_1):FPGA_OUT_SMA1_LED_RED_N

RESISTOR-G155-11000-01,100OHM,A  I165  R273
   2 UNNAMED_14_LED4PV14_I266_1      2 @TIMECARD_LIB.TIMECARD(SCH_1):UNNAMED_14_LED4PV14_I266_1
   1 FPGA_OUT_SMA2_LED_BLUE_N      1 @TIMECARD_LIB.TIMECARD(SCH_1):FPGA_OUT_SMA2_LED_BLUE_N

RESISTOR-G155-11000-01,100OHM,A  I168  R374
   2 UNNAMED_14_LED4PV14_I267_1      2 @TIMECARD_LIB.TIMECARD(SCH_1):UNNAMED_14_LED4PV14_I267_1
   1 FPGA_OUT_SMA3_LED_BLUE_N      1 @TIMECARD_LIB.TIMECARD(SCH_1):FPGA_OUT_SMA3_LED_BLUE_N

RESISTOR-G155-11000-01,100OHM,A  I170  R425
   2 UNNAMED_14_LED4PV14_I269_1      2 @TIMECARD_LIB.TIMECARD(SCH_1):UNNAMED_14_LED4PV14_I269_1
   1 FPGA_OUT_GPS_LED_BLUE_N      1 @TIMECARD_LIB.TIMECARD(SCH_1):FPGA_OUT_GPS_LED_BLUE_N

RESISTOR-G155-11000-01,100OHM,A  I171  R274
   2 UNNAMED_14_LED4PV14_I266_4      2 @TIMECARD_LIB.TIMECARD(SCH_1):UNNAMED_14_LED4PV14_I266_4
   1 FPGA_OUT_SMA2_LED_GREEN_N      1 @TIMECARD_LIB.TIMECARD(SCH_1):FPGA_OUT_SMA2_LED_GREEN_N

RESISTOR-G155-11000-01,100OHM,A  I174  R375
   2 UNNAMED_14_LED4PV14_I267_4      2 @TIMECARD_LIB.TIMECARD(SCH_1):UNNAMED_14_LED4PV14_I267_4
   1 FPGA_OUT_SMA3_LED_GREEN_N      1 @TIMECARD_LIB.TIMECARD(SCH_1):FPGA_OUT_SMA3_LED_GREEN_N

RESISTOR-G155-11000-01,100OHM,A  I176  R401
   2 UNNAMED_14_LED4PV14_I268_4      2 @TIMECARD_LIB.TIMECARD(SCH_1):UNNAMED_14_LED4PV14_I268_4
   1 FPGA_OUT_SMA4_LED_GREEN_N      1 @TIMECARD_LIB.TIMECARD(SCH_1):FPGA_OUT_SMA4_LED_GREEN_N

RESISTOR-G155-11000-01,100OHM,A  I177  R400
   2 UNNAMED_14_LED4PV14_I268_1      2 @TIMECARD_LIB.TIMECARD(SCH_1):UNNAMED_14_LED4PV14_I268_1
   1 FPGA_OUT_SMA4_LED_BLUE_N      1 @TIMECARD_LIB.TIMECARD(SCH_1):FPGA_OUT_SMA4_LED_BLUE_N

RESISTOR-G155-11000-01,100OHM,A  I179  R426
   2 UNNAMED_14_LED4PV14_I269_4      2 @TIMECARD_LIB.TIMECARD(SCH_1):UNNAMED_14_LED4PV14_I269_4
   1 FPGA_OUT_GPS_LED_GREEN_N      1 @TIMECARD_LIB.TIMECARD(SCH_1):FPGA_OUT_GPS_LED_GREEN_N

RESISTOR-G155-11000-01,100OHM,A  I181  R373
   2 UNNAMED_14_LED4PV14_I266_3      2 @TIMECARD_LIB.TIMECARD(SCH_1):UNNAMED_14_LED4PV14_I266_3
   1 FPGA_OUT_SMA2_LED_RED_N      1 @TIMECARD_LIB.TIMECARD(SCH_1):FPGA_OUT_SMA2_LED_RED_N

RESISTOR-G155-11000-01,100OHM,A  I184  R376
   2 UNNAMED_14_LED4PV14_I267_3      2 @TIMECARD_LIB.TIMECARD(SCH_1):UNNAMED_14_LED4PV14_I267_3
   1 FPGA_OUT_SMA3_LED_RED_N      1 @TIMECARD_LIB.TIMECARD(SCH_1):FPGA_OUT_SMA3_LED_RED_N

RESISTOR-G155-11000-01,100OHM,A  I186  R424
   2 UNNAMED_14_LED4PV14_I268_3      2 @TIMECARD_LIB.TIMECARD(SCH_1):UNNAMED_14_LED4PV14_I268_3
   1 FPGA_OUT_SMA4_LED_RED_N      1 @TIMECARD_LIB.TIMECARD(SCH_1):FPGA_OUT_SMA4_LED_RED_N

RESISTOR-G155-11000-01,100OHM,A  I188  R427
   2 UNNAMED_14_LED4PV14_I269_3      2 @TIMECARD_LIB.TIMECARD(SCH_1):UNNAMED_14_LED4PV14_I269_3
   1 FPGA_OUT_GPS_LED_RED_N      1 @TIMECARD_LIB.TIMECARD(SCH_1):FPGA_OUT_GPS_LED_RED_N

RESISTOR-G155-13300-01,330OHM,A  I190  R118
   2 XP3R3V_PCIE      2 @TIMECARD_LIB.TIMECARD(SCH_1):XP3R3V_PCIE
   1 UNNAMED_14_OPTICAL_I191_A      1 @TIMECARD_LIB.TIMECARD(SCH_1):UNNAMED_14_OPTICAL_I191_A

OPTICAL-G170-10143-01  I191  DS19
   A UNNAMED_14_OPTICAL_I191_A      A @TIMECARD_LIB.TIMECARD(SCH_1):UNNAMED_14_OPTICAL_I191_A
   C     SG      C @TIMECARD_LIB.TIMECARD(SCH_1):SG

RESISTOR-G155-13300-01,330OHM,A  I192  R119
   2 XP3R3V_AUX_PCIE      2 @TIMECARD_LIB.TIMECARD(SCH_1):XP3R3V_AUX_PCIE
   1 UNNAMED_14_OPTICAL_I194_A      1 @TIMECARD_LIB.TIMECARD(SCH_1):UNNAMED_14_OPTICAL_I194_A

OPTICAL-G170-10143-01  I194  DS20
   A UNNAMED_14_OPTICAL_I194_A      A @TIMECARD_LIB.TIMECARD(SCH_1):UNNAMED_14_OPTICAL_I194_A
   C     SG      C @TIMECARD_LIB.TIMECARD(SCH_1):SG

IS32FL3207_QWLA3_TR_QFN29-A223A  I219  U33
   1 RGB_LED_SHUTDOWN_N   SDB* @TIMECARD_LIB.TIMECARD(SCH_1):RGB_LED_SHUTDOWN_N
   2 UNNAMED_14_IS32FL3207QWLA3TRQFN     AD @TIMECARD_LIB.TIMECARD(SCH_1):UNNAMED_14_IS32FL3207QWLA3TRQFN29_I219_AD
   3 XP3R3V_FPGA    VCC @TIMECARD_LIB.TIMECARD(SCH_1):XP3R3V_FPGA
   4     SG  GND_1 @TIMECARD_LIB.TIMECARD(SCH_1):SG
   5 UNNAMED_14_IS32FL3207QWLA3TRQ_1   ISET @TIMECARD_LIB.TIMECARD(SCH_1):UNNAMED_14_IS32FL3207QWLA3TRQFN29_I219_ISET
   6 R_RGB_LED_I2C_SDA    SDA @TIMECARD_LIB.TIMECARD(SCH_1):R_RGB_LED_I2C_SDA
   7 R_RGB_LED_I2C_SCL    SCL @TIMECARD_LIB.TIMECARD(SCH_1):R_RGB_LED_I2C_SCL
   8 SMA1_LED_GREEN_N   OUT1 @TIMECARD_LIB.TIMECARD(SCH_1):SMA1_LED_GREEN_N
   9 SMA1_LED_RED_N   OUT2 @TIMECARD_LIB.TIMECARD(SCH_1):SMA1_LED_RED_N
  10 SMA1_LED_BLUE_N   OUT3 @TIMECARD_LIB.TIMECARD(SCH_1):SMA1_LED_BLUE_N
  11     SG  GND_2 @TIMECARD_LIB.TIMECARD(SCH_1):SG
  12 SMA2_LED_GREEN_N   OUT4 @TIMECARD_LIB.TIMECARD(SCH_1):SMA2_LED_GREEN_N
  13 SMA2_LED_RED_N   OUT5 @TIMECARD_LIB.TIMECARD(SCH_1):SMA2_LED_RED_N
  14 SMA2_LED_BLUE_N   OUT6 @TIMECARD_LIB.TIMECARD(SCH_1):SMA2_LED_BLUE_N
  15 SMA3_LED_GREEN_N   OUT7 @TIMECARD_LIB.TIMECARD(SCH_1):SMA3_LED_GREEN_N
  16 SMA3_LED_RED_N   OUT8 @TIMECARD_LIB.TIMECARD(SCH_1):SMA3_LED_RED_N
  17 SMA3_LED_BLUE_N   OUT9 @TIMECARD_LIB.TIMECARD(SCH_1):SMA3_LED_BLUE_N
  18     SG  GND_3 @TIMECARD_LIB.TIMECARD(SCH_1):SG
  19 SMA4_LED_GREEN_N  OUT10 @TIMECARD_LIB.TIMECARD(SCH_1):SMA4_LED_GREEN_N
  20 SMA4_LED_RED_N  OUT11 @TIMECARD_LIB.TIMECARD(SCH_1):SMA4_LED_RED_N
  21 SMA4_LED_BLUE_N  OUT12 @TIMECARD_LIB.TIMECARD(SCH_1):SMA4_LED_BLUE_N
  22 GPS_SMA_LED_GREEN_N  OUT13 @TIMECARD_LIB.TIMECARD(SCH_1):GPS_SMA_LED_GREEN_N
  23 GPS_SMA_LED_RED_N  OUT14 @TIMECARD_LIB.TIMECARD(SCH_1):GPS_SMA_LED_RED_N
  24 GPS_SMA_LED_BLUE_N  OUT15 @TIMECARD_LIB.TIMECARD(SCH_1):GPS_SMA_LED_BLUE_N
  25     SG  GND_4 @TIMECARD_LIB.TIMECARD(SCH_1):SG
  26     NC  OUT16     NC
  27     NC  OUT17     NC
  28     NC  OUT18     NC
  29     SG THRM_PAD @TIMECARD_LIB.TIMECARD(SCH_1):SG

CAPACITOR-G105-0B104-EK,0.1UF,A  I237  C315
   1 XP3R3V_FPGA      1 @TIMECARD_LIB.TIMECARD(SCH_1):XP3R3V_FPGA
   2     SG      2 @TIMECARD_LIB.TIMECARD(SCH_1):SG

CAPACITOR-G105-0C106-BM,10UF,2A  I238  C314
   1 XP3R3V_FPGA      1 @TIMECARD_LIB.TIMECARD(SCH_1):XP3R3V_FPGA
   2     SG      2 @TIMECARD_LIB.TIMECARD(SCH_1):SG

RESISTOR-G155-14701-01,4.7KOHMA  I246  R323
   2     SG      2 @TIMECARD_LIB.TIMECARD(SCH_1):SG
   1 UNNAMED_14_IS32FL3207QWLA3TRQ_1      1 @TIMECARD_LIB.TIMECARD(SCH_1):UNNAMED_14_IS32FL3207QWLA3TRQFN29_I219_ISET

RESISTOR-G155-100R0-J0,0OHM,-  I247  R324
   2 UNNAMED_14_IS32FL3207QWLA3TRQFN      2 @TIMECARD_LIB.TIMECARD(SCH_1):UNNAMED_14_IS32FL3207QWLA3TRQFN29_I219_AD
   1     SG      1 @TIMECARD_LIB.TIMECARD(SCH_1):SG

RESISTOR-G155-133R0-01,33OHM,1%  I249  R319
   2 RGB_LED_SHUTDOWN_N      2 @TIMECARD_LIB.TIMECARD(SCH_1):RGB_LED_SHUTDOWN_N
   1 FPGA_OUT_RGB_LED_SHUTDOWN_N      1 @TIMECARD_LIB.TIMECARD(SCH_1):FPGA_OUT_RGB_LED_SHUTDOWN_N

CAPACITOR-G105-0B104-EK,0.1UF,A  I250  C316
   1 RGB_LED_SHUTDOWN_N      1 @TIMECARD_LIB.TIMECARD(SCH_1):RGB_LED_SHUTDOWN_N
   2     SG      2 @TIMECARD_LIB.TIMECARD(SCH_1):SG

RESISTOR-G155-133R0-01,33OHM,1%  I257  R322
   2 R_RGB_LED_I2C_SCL      2 @TIMECARD_LIB.TIMECARD(SCH_1):R_RGB_LED_I2C_SCL
   1 FPGA_M_RGB_LED_I2C_SCL      1 @TIMECARD_LIB.TIMECARD(SCH_1):FPGA_M_RGB_LED_I2C_SCL

RESISTOR-G155-133R0-01,33OHM,1%  I258  R321
   2 R_RGB_LED_I2C_SDA      2 @TIMECARD_LIB.TIMECARD(SCH_1):R_RGB_LED_I2C_SDA
   1 FPGA_M_RGB_LED_I2C_SDA      1 @TIMECARD_LIB.TIMECARD(SCH_1):FPGA_M_RGB_LED_I2C_SDA

RESISTOR-G155-11002-01,10KOHM,A  I259  R317
   2 R_RGB_LED_I2C_SDA      2 @TIMECARD_LIB.TIMECARD(SCH_1):R_RGB_LED_I2C_SDA
   1 XP3R3V_FPGA      1 @TIMECARD_LIB.TIMECARD(SCH_1):XP3R3V_FPGA

RESISTOR-G155-11002-01,10KOHM,A  I261  R318
   2 R_RGB_LED_I2C_SCL      2 @TIMECARD_LIB.TIMECARD(SCH_1):R_RGB_LED_I2C_SCL
   1 XP3R3V_FPGA      1 @TIMECARD_LIB.TIMECARD(SCH_1):XP3R3V_FPGA

RESISTOR-G155-14701-01,4.7KOHMA  I264  R320
   2 RGB_LED_SHUTDOWN_N      2 @TIMECARD_LIB.TIMECARD(SCH_1):RGB_LED_SHUTDOWN_N
   1 XP3R3V_FPGA      1 @TIMECARD_LIB.TIMECARD(SCH_1):XP3R3V_FPGA

LED_4P_V14-G170-10189-01  I265  DS14
   4 UNNAMED_14_LED4PV14_I265_4      4 @TIMECARD_LIB.TIMECARD(SCH_1):UNNAMED_14_LED4PV14_I265_4
   3 UNNAMED_14_LED4PV14_I265_3      3 @TIMECARD_LIB.TIMECARD(SCH_1):UNNAMED_14_LED4PV14_I265_3
   1 UNNAMED_14_LED4PV14_I265_1      1 @TIMECARD_LIB.TIMECARD(SCH_1):UNNAMED_14_LED4PV14_I265_1
   2 XP3R3V_FPGA      2 @TIMECARD_LIB.TIMECARD(SCH_1):XP3R3V_FPGA

LED_4P_V14-G170-10189-01  I266  DS15
   4 UNNAMED_14_LED4PV14_I266_4      4 @TIMECARD_LIB.TIMECARD(SCH_1):UNNAMED_14_LED4PV14_I266_4
   3 UNNAMED_14_LED4PV14_I266_3      3 @TIMECARD_LIB.TIMECARD(SCH_1):UNNAMED_14_LED4PV14_I266_3
   1 UNNAMED_14_LED4PV14_I266_1      1 @TIMECARD_LIB.TIMECARD(SCH_1):UNNAMED_14_LED4PV14_I266_1
   2 XP3R3V_FPGA      2 @TIMECARD_LIB.TIMECARD(SCH_1):XP3R3V_FPGA

LED_4P_V14-G170-10189-01  I267  DS16
   4 UNNAMED_14_LED4PV14_I267_4      4 @TIMECARD_LIB.TIMECARD(SCH_1):UNNAMED_14_LED4PV14_I267_4
   3 UNNAMED_14_LED4PV14_I267_3      3 @TIMECARD_LIB.TIMECARD(SCH_1):UNNAMED_14_LED4PV14_I267_3
   1 UNNAMED_14_LED4PV14_I267_1      1 @TIMECARD_LIB.TIMECARD(SCH_1):UNNAMED_14_LED4PV14_I267_1
   2 XP3R3V_FPGA      2 @TIMECARD_LIB.TIMECARD(SCH_1):XP3R3V_FPGA

LED_4P_V14-G170-10189-01  I268  DS17
   4 UNNAMED_14_LED4PV14_I268_4      4 @TIMECARD_LIB.TIMECARD(SCH_1):UNNAMED_14_LED4PV14_I268_4
   3 UNNAMED_14_LED4PV14_I268_3      3 @TIMECARD_LIB.TIMECARD(SCH_1):UNNAMED_14_LED4PV14_I268_3
   1 UNNAMED_14_LED4PV14_I268_1      1 @TIMECARD_LIB.TIMECARD(SCH_1):UNNAMED_14_LED4PV14_I268_1
   2 XP3R3V_FPGA      2 @TIMECARD_LIB.TIMECARD(SCH_1):XP3R3V_FPGA

LED_4P_V14-G170-10189-01  I269  DS18
   4 UNNAMED_14_LED4PV14_I269_4      4 @TIMECARD_LIB.TIMECARD(SCH_1):UNNAMED_14_LED4PV14_I269_4
   3 UNNAMED_14_LED4PV14_I269_3      3 @TIMECARD_LIB.TIMECARD(SCH_1):UNNAMED_14_LED4PV14_I269_3
   1 UNNAMED_14_LED4PV14_I269_1      1 @TIMECARD_LIB.TIMECARD(SCH_1):UNNAMED_14_LED4PV14_I269_1
   2 XP3R3V_FPGA      2 @TIMECARD_LIB.TIMECARD(SCH_1):XP3R3V_FPGA

RESISTOR-G155-13300-01,330OHM,A  I288  R169
   2 XP3R3V_FT4232      2 @TIMECARD_LIB.TIMECARD(SCH_1):XP3R3V_FT4232
   1 UNNAMED_14_OPTICAL_I289_A      1 @TIMECARD_LIB.TIMECARD(SCH_1):UNNAMED_14_OPTICAL_I289_A

OPTICAL-G170-10143-01  I289  DS12
   A UNNAMED_14_OPTICAL_I289_A      A @TIMECARD_LIB.TIMECARD(SCH_1):UNNAMED_14_OPTICAL_I289_A
   C     SG      C @TIMECARD_LIB.TIMECARD(SCH_1):SG

OPTICAL-G170-10143-01  I292  DS9
   A UNNAMED_14_OPTICAL_I292_A      A @TIMECARD_LIB.TIMECARD(SCH_1):UNNAMED_14_OPTICAL_I292_A
   C     SG      C @TIMECARD_LIB.TIMECARD(SCH_1):SG

RESISTOR-G155-13300-01,330OHM,A  I293  R208
   2 FPGA_DONE      2 @TIMECARD_LIB.TIMECARD(SCH_1):FPGA_DONE
   1 UNNAMED_14_OPTICAL_I292_A      1 @TIMECARD_LIB.TIMECARD(SCH_1):UNNAMED_14_OPTICAL_I292_A

RESISTOR-G155-133R0-01,33OHM,1%  I298  R364
   2 R_RGB_LED_I2C_SDA      2 @TIMECARD_LIB.TIMECARD(SCH_1):R_RGB_LED_I2C_SDA
   1 RGB_LED_I2C_SDA      1 @TIMECARD_LIB.TIMECARD(SCH_1):RGB_LED_I2C_SDA

RESISTOR-G155-133R0-01,33OHM,1%  I299  R366
   2 R_RGB_LED_I2C_SCL      2 @TIMECARD_LIB.TIMECARD(SCH_1):R_RGB_LED_I2C_SCL
   1 RGB_LED_I2C_SCL      1 @TIMECARD_LIB.TIMECARD(SCH_1):RGB_LED_I2C_SCL


DRAWING: @TIMECARD_LIB.TIMECARD(SCH_1):PAGE517 

CAPACITOR-G104-0B103-EK,0.01UFA  I2  C77
   1     SG      1 @TIMECARD_LIB.TIMECARD(SCH_1):SG
   2 R_XP3R3V_PG      2 @TIMECARD_LIB.TIMECARD(SCH_1):R_XP3R3V_PG

RESISTOR-G155-11002-01,10KOHM,A  I3  R51
   2 R_XP3R3V_PG      2 @TIMECARD_LIB.TIMECARD(SCH_1):R_XP3R3V_PG
   1 XP3R3V      1 @TIMECARD_LIB.TIMECARD(SCH_1):XP3R3V

CAPACITOR-G105-0B104-EK,0.1UF,A  I6  C76
   1 XP12R0V      1 @TIMECARD_LIB.TIMECARD(SCH_1):XP12R0V
   2     SG      2 @TIMECARD_LIB.TIMECARD(SCH_1):SG

FERRITEBEAD-G191-10101-01,26OHA  I7  L8
   1 XP12R0V      1 @TIMECARD_LIB.TIMECARD(SCH_1):XP12R0V
   2 VIN_XP3R3      2 @TIMECARD_LIB.TIMECARD(SCH_1):VIN_XP3R3

CAPACITOR-G105-0B223-EK,0.022UA  I9  C49
   1 XP3R3V_SS      1 @TIMECARD_LIB.TIMECARD(SCH_1):XP3R3V_SS
   2 XP3R3V_AGND      2 @TIMECARD_LIB.TIMECARD(SCH_1):XP3R3V_AGND

RESISTOR-G155-11003-01,100KOHMA  I10  R35
   2 XP3R3V_AGND      2 @TIMECARD_LIB.TIMECARD(SCH_1):XP3R3V_AGND
   1 XP3R3V_RT      1 @TIMECARD_LIB.TIMECARD(SCH_1):XP3R3V_RT

RESISTOR-G155-05101-01,5.1KOHMA  I11  R52
   2     SG      2 @TIMECARD_LIB.TIMECARD(SCH_1):SG
   1 XP3R3V_EN      1 @TIMECARD_LIB.TIMECARD(SCH_1):XP3R3V_EN

CAPACITOR-G105-0B104-CK,0.1UF,A  I12  C46
   1 XP3R3V_EN      1 @TIMECARD_LIB.TIMECARD(SCH_1):XP3R3V_EN
   2     SG      2 @TIMECARD_LIB.TIMECARD(SCH_1):SG

RESISTOR-G152-10344-01,30KOHM,A  I13  R53
   2 XP3R3V_EN      2 @TIMECARD_LIB.TIMECARD(SCH_1):XP3R3V_EN
   1 VIN_XP3R3      1 @TIMECARD_LIB.TIMECARD(SCH_1):VIN_XP3R3

CAPACITOR-G107-0F106-EM,10UF,2A  I14  C48
   1 VIN_XP3R3      1 @TIMECARD_LIB.TIMECARD(SCH_1):VIN_XP3R3
   2     SG      2 @TIMECARD_LIB.TIMECARD(SCH_1):SG

CAPACITOR-G107-0F106-EM,10UF,2A  I15  C50
   1 VIN_XP3R3      1 @TIMECARD_LIB.TIMECARD(SCH_1):VIN_XP3R3
   2     SG      2 @TIMECARD_LIB.TIMECARD(SCH_1):SG

CAPACITOR-G105-0B104-EK,0.1UF,A  I16  C52
   1 VIN_XP3R3      1 @TIMECARD_LIB.TIMECARD(SCH_1):VIN_XP3R3
   2     SG      2 @TIMECARD_LIB.TIMECARD(SCH_1):SG

CAPACITOR-G105-0B222-FK,2200PFA  I17  C54
   1 UNNAMED_517_CAPACITOR_I17_1      1 @TIMECARD_LIB.TIMECARD(SCH_1):UNNAMED_517_CAPACITOR_I17_1
   2 XP3R3V_AGND      2 @TIMECARD_LIB.TIMECARD(SCH_1):XP3R3V_AGND

RESISTOR-G155-11002-01,10KOHM,A  I18  R36
   2 UNNAMED_517_CAPACITOR_I17_1      2 @TIMECARD_LIB.TIMECARD(SCH_1):UNNAMED_517_CAPACITOR_I17_1
   1 XP3R3V_COMP      1 @TIMECARD_LIB.TIMECARD(SCH_1):XP3R3V_COMP

CAPACITOR-G104-0A180-FJ,18PF,5%  I19  C55
   1 XP3R3V_COMP      1 @TIMECARD_LIB.TIMECARD(SCH_1):XP3R3V_COMP
   2 XP3R3V_AGND      2 @TIMECARD_LIB.TIMECARD(SCH_1):XP3R3V_AGND

CAPACITOR-G105-0B104-EK,0.1UF,A  I21  C53
   1 VIN_XP3R3      1 @TIMECARD_LIB.TIMECARD(SCH_1):VIN_XP3R3
   2     SG      2 @TIMECARD_LIB.TIMECARD(SCH_1):SG

SOLDER_PREFORM-G380-10015-01  I24  SP2
   1     SG      1 @TIMECARD_LIB.TIMECARD(SCH_1):SG
   2 XP3R3V_AGND      2 @TIMECARD_LIB.TIMECARD(SCH_1):XP3R3V_AGND

RESISTOR-G155-100R0-J0,0OHM,-  I25  R37
   2 UNNAMED_517_CAPACITOR_I27_1      2 @TIMECARD_LIB.TIMECARD(SCH_1):UNNAMED_517_CAPACITOR_I27_1
   1 XP3R3V_BT      1 @TIMECARD_LIB.TIMECARD(SCH_1):XP3R3V_BT

RESISTOR-G155-04421-01,4.42KOHA  I26  R38
   2 XP3R3V_AGND      2 @TIMECARD_LIB.TIMECARD(SCH_1):XP3R3V_AGND
   1 XP3R3V_FB_R_TO_AGND      1 @TIMECARD_LIB.TIMECARD(SCH_1):XP3R3V_FB_R_TO_AGND

CAPACITOR-G105-0B104-EK,0.1UF,A  I27  C56
   1 UNNAMED_517_CAPACITOR_I27_1      1 @TIMECARD_LIB.TIMECARD(SCH_1):UNNAMED_517_CAPACITOR_I27_1
   2 XP3R3V_SW      2 @TIMECARD_LIB.TIMECARD(SCH_1):XP3R3V_SW

INDUCTOR_2-G190-10424-01,4.7UHA  I28  L2
   1 XP3R3V_SW      1 @TIMECARD_LIB.TIMECARD(SCH_1):XP3R3V_SW
   2 XP3R3V      2 @TIMECARD_LIB.TIMECARD(SCH_1):XP3R3V

CAPACITOR-G105-0A102-FJ,1000PFA  I29  C57
   1 XP3R3V_SW      1 @TIMECARD_LIB.TIMECARD(SCH_1):XP3R3V_SW
   2 UNNAMED_517_CAPACITOR_I29_2      2 @TIMECARD_LIB.TIMECARD(SCH_1):UNNAMED_517_CAPACITOR_I29_2

CAPACITOR-G104-0B101-FK,100PF,A  I30  C16
   1 UNNAMED_517_CAPACITOR_I30_1      1 @TIMECARD_LIB.TIMECARD(SCH_1):UNNAMED_517_CAPACITOR_I30_1
   2 XP3R3V_FB_R_TO_AGND      2 @TIMECARD_LIB.TIMECARD(SCH_1):XP3R3V_FB_R_TO_AGND

RESISTOR-G155-12002-01,20KOHM,A  I31  R40
   2 XP3R3V_FB_R_TO_AGND      2 @TIMECARD_LIB.TIMECARD(SCH_1):XP3R3V_FB_R_TO_AGND
   1 UNNAMED_517_CAPACITOR_I30_1      1 @TIMECARD_LIB.TIMECARD(SCH_1):UNNAMED_517_CAPACITOR_I30_1

RESISTOR-G157-12R20-01,2.2OHM,A  I32  R39
   2     SG      2 @TIMECARD_LIB.TIMECARD(SCH_1):SG
   1 UNNAMED_517_CAPACITOR_I29_2      1 @TIMECARD_LIB.TIMECARD(SCH_1):UNNAMED_517_CAPACITOR_I29_2

RESISTOR-G155-120R0-01,20OHM,1%  I33  R17
   2 UNNAMED_517_CAPACITOR_I30_1      2 @TIMECARD_LIB.TIMECARD(SCH_1):UNNAMED_517_CAPACITOR_I30_1
   1 XP3R3V      1 @TIMECARD_LIB.TIMECARD(SCH_1):XP3R3V

CAPACITOR-G105-0B104-CK,0.1UF,A  I36  C18
   1 XP3R3V      1 @TIMECARD_LIB.TIMECARD(SCH_1):XP3R3V
   2     SG      2 @TIMECARD_LIB.TIMECARD(SCH_1):SG

CAPACITOR-G107-0F226-CM,22UF,2A  I37  C20
   1 XP3R3V      1 @TIMECARD_LIB.TIMECARD(SCH_1):XP3R3V
   2     SG      2 @TIMECARD_LIB.TIMECARD(SCH_1):SG

CAPACITOR-G107-0F226-CM,22UF,2A  I38  C21
   1 XP3R3V      1 @TIMECARD_LIB.TIMECARD(SCH_1):XP3R3V
   2     SG      2 @TIMECARD_LIB.TIMECARD(SCH_1):SG

CAPACITOR-G107-0F226-CM,22UF,2A  I40  C22
   1 XP3R3V      1 @TIMECARD_LIB.TIMECARD(SCH_1):XP3R3V
   2     SG      2 @TIMECARD_LIB.TIMECARD(SCH_1):SG

RESISTOR-G156-100R0-J0,0OHM,-  I41  R54
   2 XP3R3V_FB_R_TO_AGND      2 @TIMECARD_LIB.TIMECARD(SCH_1):XP3R3V_FB_R_TO_AGND
   1 XP3R3V_AGND      1 @TIMECARD_LIB.TIMECARD(SCH_1):XP3R3V_AGND

TPS54824RNVR_VQFN18-G220-10657A  I42  U6
   1 XP3R3V_BT   BOOT @TIMECARD_LIB.TIMECARD(SCH_1):XP3R3V_BT
   2 VIN_XP3R3  VIN_1 @TIMECARD_LIB.TIMECARD(SCH_1):VIN_XP3R3
   3     SG PGND_1 @TIMECARD_LIB.TIMECARD(SCH_1):SG
   4     SG PGND_2 @TIMECARD_LIB.TIMECARD(SCH_1):SG
   5     SG PGND_3 @TIMECARD_LIB.TIMECARD(SCH_1):SG
   6 XP3R3V_SW   SW_1 @TIMECARD_LIB.TIMECARD(SCH_1):XP3R3V_SW
   7 XP3R3V_SW   SW_2 @TIMECARD_LIB.TIMECARD(SCH_1):XP3R3V_SW
   8     SG PGND_4 @TIMECARD_LIB.TIMECARD(SCH_1):SG
   9     SG PGND_5 @TIMECARD_LIB.TIMECARD(SCH_1):SG
  10     SG PGND_6 @TIMECARD_LIB.TIMECARD(SCH_1):SG
  11 VIN_XP3R3  VIN_2 @TIMECARD_LIB.TIMECARD(SCH_1):VIN_XP3R3
  12 XP3R3V_AGND   AGND @TIMECARD_LIB.TIMECARD(SCH_1):XP3R3V_AGND
  13 XP3R3V_RT RT/CLK @TIMECARD_LIB.TIMECARD(SCH_1):XP3R3V_RT
  14 XP3R3V_FB_R_TO_AGND     FB @TIMECARD_LIB.TIMECARD(SCH_1):XP3R3V_FB_R_TO_AGND
  15 XP3R3V_COMP   COMP @TIMECARD_LIB.TIMECARD(SCH_1):XP3R3V_COMP
  16 XP3R3V_SS SS/TRK @TIMECARD_LIB.TIMECARD(SCH_1):XP3R3V_SS
  17 XP3R3V_EN     EN @TIMECARD_LIB.TIMECARD(SCH_1):XP3R3V_EN
  18 R_XP3R3V_PG  PGOOD @TIMECARD_LIB.TIMECARD(SCH_1):R_XP3R3V_PG

RESISTOR-G155-100R0-J0,0OHM,-  I47  R263
   2 XP3R3V_PG      2 @TIMECARD_LIB.TIMECARD(SCH_1):XP3R3V_PG
   1 R_XP3R3V_PG      1 @TIMECARD_LIB.TIMECARD(SCH_1):R_XP3R3V_PG

CAPACITOR-G105-0B224-DK,0.22UFA  I51  C286
   1 XP3R3V_EN      1 @TIMECARD_LIB.TIMECARD(SCH_1):XP3R3V_EN
   2     SG      2 @TIMECARD_LIB.TIMECARD(SCH_1):SG


DRAWING: @TIMECARD_LIB.TIMECARD(SCH_1):PAGE516 

RESISTOR-G155-11002-01,10KOHM,A  I1  R47
   2 XP5R0V_PG      2 @TIMECARD_LIB.TIMECARD(SCH_1):XP5R0V_PG
   1 XP3R3V      1 @TIMECARD_LIB.TIMECARD(SCH_1):XP3R3V

CAPACITOR-G105-0B104-EK,0.1UF,A  I4  C74
   1 XP12R0V      1 @TIMECARD_LIB.TIMECARD(SCH_1):XP12R0V
   2     SG      2 @TIMECARD_LIB.TIMECARD(SCH_1):SG

CAPACITOR-G104-0B103-EK,0.01UFA  I7  C75
   1     SG      1 @TIMECARD_LIB.TIMECARD(SCH_1):SG
   2 XP5R0V_PG      2 @TIMECARD_LIB.TIMECARD(SCH_1):XP5R0V_PG

RESISTOR-A155-05101-DL,5.1KOHMA  I9  R48
   2     SG      2 @TIMECARD_LIB.TIMECARD(SCH_1):SG
   1 R_XP5R0V_EN      1 @TIMECARD_LIB.TIMECARD(SCH_1):R_XP5R0V_EN

CAPACITOR-G105-0B104-CK,0.1UF,A  I10  C29
   1 R_XP5R0V_EN      1 @TIMECARD_LIB.TIMECARD(SCH_1):R_XP5R0V_EN
   2     SG      2 @TIMECARD_LIB.TIMECARD(SCH_1):SG

CAPACITOR-G105-0B223-EK,0.022UA  I11  C31
   1 XP5R0V_SS      1 @TIMECARD_LIB.TIMECARD(SCH_1):XP5R0V_SS
   2 XP5R0V_AGND      2 @TIMECARD_LIB.TIMECARD(SCH_1):XP5R0V_AGND

RESISTOR-G155-11003-01,100KOHMA  I12  R29
   2 XP5R0V_AGND      2 @TIMECARD_LIB.TIMECARD(SCH_1):XP5R0V_AGND
   1 XP5R0V_RT      1 @TIMECARD_LIB.TIMECARD(SCH_1):XP5R0V_RT

CAPACITOR-G105-0B222-FK,2200PFA  I13  C42
   1 UNNAMED_516_CAPACITOR_I13_1      1 @TIMECARD_LIB.TIMECARD(SCH_1):UNNAMED_516_CAPACITOR_I13_1
   2 XP5R0V_AGND      2 @TIMECARD_LIB.TIMECARD(SCH_1):XP5R0V_AGND

RESISTOR-G155-12201-01,2.2KOHMA  I14  R30
   2 UNNAMED_516_CAPACITOR_I13_1      2 @TIMECARD_LIB.TIMECARD(SCH_1):UNNAMED_516_CAPACITOR_I13_1
   1 XP5R0V_COMP      1 @TIMECARD_LIB.TIMECARD(SCH_1):XP5R0V_COMP

CAPACITOR-G104-0A180-FJ,18PF,5%  I15  C43
   1 XP5R0V_COMP      1 @TIMECARD_LIB.TIMECARD(SCH_1):XP5R0V_COMP
   2 XP5R0V_AGND      2 @TIMECARD_LIB.TIMECARD(SCH_1):XP5R0V_AGND

RESISTOR-G155-11002-01,10KOHM,A  I16  R49
   2 R_XP5R0V_EN      2 @TIMECARD_LIB.TIMECARD(SCH_1):R_XP5R0V_EN
   1 VIN_XP5R0V      1 @TIMECARD_LIB.TIMECARD(SCH_1):VIN_XP5R0V

FERRITEBEAD-G191-10101-01,26OHA  I17  L7
   1 XP12R0V      1 @TIMECARD_LIB.TIMECARD(SCH_1):XP12R0V
   2 VIN_XP5R0V      2 @TIMECARD_LIB.TIMECARD(SCH_1):VIN_XP5R0V

CAPACITOR-G107-0F106-EM,10UF,2A  I18  C30
   1 VIN_XP5R0V      1 @TIMECARD_LIB.TIMECARD(SCH_1):VIN_XP5R0V
   2     SG      2 @TIMECARD_LIB.TIMECARD(SCH_1):SG

CAPACITOR-G107-0F106-EM,10UF,2A  I19  C32
   1 VIN_XP5R0V      1 @TIMECARD_LIB.TIMECARD(SCH_1):VIN_XP5R0V
   2     SG      2 @TIMECARD_LIB.TIMECARD(SCH_1):SG

CAPACITOR-G105-0B104-EK,0.1UF,A  I20  C33
   1 VIN_XP5R0V      1 @TIMECARD_LIB.TIMECARD(SCH_1):VIN_XP5R0V
   2     SG      2 @TIMECARD_LIB.TIMECARD(SCH_1):SG

CAPACITOR-G105-0B104-EK,0.1UF,A  I22  C41
   1 VIN_XP5R0V      1 @TIMECARD_LIB.TIMECARD(SCH_1):VIN_XP5R0V
   2     SG      2 @TIMECARD_LIB.TIMECARD(SCH_1):SG

SOLDER_PREFORM-G380-10015-01  I24  SP1
   1     SG      1 @TIMECARD_LIB.TIMECARD(SCH_1):SG
   2 XP5R0V_AGND      2 @TIMECARD_LIB.TIMECARD(SCH_1):XP5R0V_AGND

RESISTOR-G155-03241-01,3.24KOHA  I25  R32
   2 XP5R0V_AGND      2 @TIMECARD_LIB.TIMECARD(SCH_1):XP5R0V_AGND
   1 XP5R0V_FB_R_TO_AGND      1 @TIMECARD_LIB.TIMECARD(SCH_1):XP5R0V_FB_R_TO_AGND

RESISTOR-G155-100R0-J0,0OHM,-  I26  R31
   2 UNNAMED_516_CAPACITOR_I27_1      2 @TIMECARD_LIB.TIMECARD(SCH_1):UNNAMED_516_CAPACITOR_I27_1
   1 XP5R0V_BT      1 @TIMECARD_LIB.TIMECARD(SCH_1):XP5R0V_BT

CAPACITOR-G105-0B104-EK,0.1UF,A  I27  C44
   1 UNNAMED_516_CAPACITOR_I27_1      1 @TIMECARD_LIB.TIMECARD(SCH_1):UNNAMED_516_CAPACITOR_I27_1
   2 XP5R0V_SW      2 @TIMECARD_LIB.TIMECARD(SCH_1):XP5R0V_SW

RESISTOR-G156-100R0-J0,0OHM,-  I28  R50
   2 XP5R0V_FB_R_TO_AGND      2 @TIMECARD_LIB.TIMECARD(SCH_1):XP5R0V_FB_R_TO_AGND
   1 XP5R0V_AGND      1 @TIMECARD_LIB.TIMECARD(SCH_1):XP5R0V_AGND

CAPACITOR-G104-0B101-FK,100PF,A  I29  C11
   1 UNNAMED_516_CAPACITOR_I29_1      1 @TIMECARD_LIB.TIMECARD(SCH_1):UNNAMED_516_CAPACITOR_I29_1
   2 XP5R0V_FB_R_TO_AGND      2 @TIMECARD_LIB.TIMECARD(SCH_1):XP5R0V_FB_R_TO_AGND

RESISTOR-G155-02402-01,24KOHM,A  I30  R34
   2 XP5R0V_FB_R_TO_AGND      2 @TIMECARD_LIB.TIMECARD(SCH_1):XP5R0V_FB_R_TO_AGND
   1 UNNAMED_516_CAPACITOR_I29_1      1 @TIMECARD_LIB.TIMECARD(SCH_1):UNNAMED_516_CAPACITOR_I29_1

RESISTOR-G155-120R0-01,20OHM,1%  I31  R6
   2 UNNAMED_516_CAPACITOR_I29_1      2 @TIMECARD_LIB.TIMECARD(SCH_1):UNNAMED_516_CAPACITOR_I29_1
   1 XP5R0V      1 @TIMECARD_LIB.TIMECARD(SCH_1):XP5R0V

CAPACITOR-G105-0B104-CK,0.1UF,A  I32  C12
   1 XP5R0V      1 @TIMECARD_LIB.TIMECARD(SCH_1):XP5R0V
   2     SG      2 @TIMECARD_LIB.TIMECARD(SCH_1):SG

CAPACITOR-G107-0F226-CM,22UF,2A  I33  C13
   1 XP5R0V      1 @TIMECARD_LIB.TIMECARD(SCH_1):XP5R0V
   2     SG      2 @TIMECARD_LIB.TIMECARD(SCH_1):SG

CAPACITOR-G107-0F226-CM,22UF,2A  I35  C14
   1 XP5R0V      1 @TIMECARD_LIB.TIMECARD(SCH_1):XP5R0V
   2     SG      2 @TIMECARD_LIB.TIMECARD(SCH_1):SG

INDUCTOR_2-G190-10424-01,4.7UHA  I36  L1
   1 XP5R0V_SW      1 @TIMECARD_LIB.TIMECARD(SCH_1):XP5R0V_SW
   2 XP5R0V      2 @TIMECARD_LIB.TIMECARD(SCH_1):XP5R0V

CAPACITOR-G105-0A102-FJ,1000PFA  I37  C45
   1 XP5R0V_SW      1 @TIMECARD_LIB.TIMECARD(SCH_1):XP5R0V_SW
   2 UNNAMED_516_CAPACITOR_I37_2      2 @TIMECARD_LIB.TIMECARD(SCH_1):UNNAMED_516_CAPACITOR_I37_2

RESISTOR-G157-12R20-01,2.2OHM,A  I38  R33
   2     SG      2 @TIMECARD_LIB.TIMECARD(SCH_1):SG
   1 UNNAMED_516_CAPACITOR_I37_2      1 @TIMECARD_LIB.TIMECARD(SCH_1):UNNAMED_516_CAPACITOR_I37_2

CAPACITOR-G107-0F226-CM,22UF,2A  I40  C15
   1 XP5R0V      1 @TIMECARD_LIB.TIMECARD(SCH_1):XP5R0V
   2     SG      2 @TIMECARD_LIB.TIMECARD(SCH_1):SG

TPS54824RNVR_VQFN18-G220-10657A  I42  U5
   1 XP5R0V_BT   BOOT @TIMECARD_LIB.TIMECARD(SCH_1):XP5R0V_BT
   2 VIN_XP5R0V  VIN_1 @TIMECARD_LIB.TIMECARD(SCH_1):VIN_XP5R0V
   3     SG PGND_1 @TIMECARD_LIB.TIMECARD(SCH_1):SG
   4     SG PGND_2 @TIMECARD_LIB.TIMECARD(SCH_1):SG
   5     SG PGND_3 @TIMECARD_LIB.TIMECARD(SCH_1):SG
   6 XP5R0V_SW   SW_1 @TIMECARD_LIB.TIMECARD(SCH_1):XP5R0V_SW
   7 XP5R0V_SW   SW_2 @TIMECARD_LIB.TIMECARD(SCH_1):XP5R0V_SW
   8     SG PGND_4 @TIMECARD_LIB.TIMECARD(SCH_1):SG
   9     SG PGND_5 @TIMECARD_LIB.TIMECARD(SCH_1):SG
  10     SG PGND_6 @TIMECARD_LIB.TIMECARD(SCH_1):SG
  11 VIN_XP5R0V  VIN_2 @TIMECARD_LIB.TIMECARD(SCH_1):VIN_XP5R0V
  12 XP5R0V_AGND   AGND @TIMECARD_LIB.TIMECARD(SCH_1):XP5R0V_AGND
  13 XP5R0V_RT RT/CLK @TIMECARD_LIB.TIMECARD(SCH_1):XP5R0V_RT
  14 XP5R0V_FB_R_TO_AGND     FB @TIMECARD_LIB.TIMECARD(SCH_1):XP5R0V_FB_R_TO_AGND
  15 XP5R0V_COMP   COMP @TIMECARD_LIB.TIMECARD(SCH_1):XP5R0V_COMP
  16 XP5R0V_SS SS/TRK @TIMECARD_LIB.TIMECARD(SCH_1):XP5R0V_SS
  17 R_XP5R0V_EN     EN @TIMECARD_LIB.TIMECARD(SCH_1):R_XP5R0V_EN
  18 XP5R0V_PG  PGOOD @TIMECARD_LIB.TIMECARD(SCH_1):XP5R0V_PG

RESISTOR-G155-11000-01,100OHM,A  I44  R142
   2 R_XP5R0V_EN      2 @TIMECARD_LIB.TIMECARD(SCH_1):R_XP5R0V_EN
   1 XP1R8V_FPGA_PG      1 @TIMECARD_LIB.TIMECARD(SCH_1):XP1R8V_FPGA_PG

RESISTOR-G155-133R0-01,33OHM,1%  I45  R294
   2 FPGA_CFG_INIT_N      2 @TIMECARD_LIB.TIMECARD(SCH_1):FPGA_CFG_INIT_N
   1 XP5R0V_PG      1 @TIMECARD_LIB.TIMECARD(SCH_1):XP5R0V_PG


DRAWING: @TIMECARD_LIB.TIMECARD(SCH_1):PAGE15 

CAPACITOR-G105-0B104-EK,0.1UF,A  I156  C3
   1 XP12R0V_A_EN      1 @TIMECARD_LIB.TIMECARD(SCH_1):XP12R0V_A_EN
   2     SG      2 @TIMECARD_LIB.TIMECARD(SCH_1):SG

DIODE_2E-G122-10190-01  I159  CR10
   C XP12R0V_IN      C @TIMECARD_LIB.TIMECARD(SCH_1):XP12R0V_IN
   A     SG      A @TIMECARD_LIB.TIMECARD(SCH_1):SG

CAPACITOR-G105-0B104-EK,0.1UF,A  I160  C2
   1 XP12R0V_IN      1 @TIMECARD_LIB.TIMECARD(SCH_1):XP12R0V_IN
   2     SG      2 @TIMECARD_LIB.TIMECARD(SCH_1):SG

RESISTOR-G155-11002-01,10KOHM,A  I169  R5
   2     SG      2 @TIMECARD_LIB.TIMECARD(SCH_1):SG
   1 XP12R0V_A_EN      1 @TIMECARD_LIB.TIMECARD(SCH_1):XP12R0V_A_EN

RESISTOR-G155-11002-01,10KOHM,A  I170  R4
   2 XP12R0V_A_EN      2 @TIMECARD_LIB.TIMECARD(SCH_1):XP12R0V_A_EN
   1 XP12R0V_IN      1 @TIMECARD_LIB.TIMECARD(SCH_1):XP12R0V_IN

RESISTOR-G155-02672-01,26.7K,1%  I171  R46
   2 XP12R0V_A_ISET      2 @TIMECARD_LIB.TIMECARD(SCH_1):XP12R0V_A_ISET
   1     SG      1 @TIMECARD_LIB.TIMECARD(SCH_1):SG

CAPACITOR-G104-0F224-BK,0.22UFA  I172  C4
   1     SG      1 @TIMECARD_LIB.TIMECARD(SCH_1):SG
   2 XP12R0V_A_TIMER      2 @TIMECARD_LIB.TIMECARD(SCH_1):XP12R0V_A_TIMER

RESISTOR-G155-100R0-J0,0OHM,-  I173  R8
   2 UNNAMED_15_MP5022CGQVZQFN22_I21      2 @TIMECARD_LIB.TIMECARD(SCH_1):UNNAMED_15_MP5022CGQVZQFN22_I212_ENTM
   1     SG      1 @TIMECARD_LIB.TIMECARD(SCH_1):SG

RESISTOR-G155-100R0-J0,0OHM,-  I174  R7
   2 UNNAMED_15_MP5022CGQVZQFN22_I_2      2 @TIMECARD_LIB.TIMECARD(SCH_1):UNNAMED_15_MP5022CGQVZQFN22_I212_LOADEN
   1     SG      1 @TIMECARD_LIB.TIMECARD(SCH_1):SG

RESISTOR-G155-11002-01,10KOHM,A  I183  R10
   2     SG      2 @TIMECARD_LIB.TIMECARD(SCH_1):SG
   1 XP12R0V_A_IMON      1 @TIMECARD_LIB.TIMECARD(SCH_1):XP12R0V_A_IMON

CAPACITOR-G105-0B104-EK,0.1UF,A  I185  C7
   1 XP12R0V_A_IMON      1 @TIMECARD_LIB.TIMECARD(SCH_1):XP12R0V_A_IMON
   2     SG      2 @TIMECARD_LIB.TIMECARD(SCH_1):SG

RESISTOR-G155-03921-01,3.92KOHA  I186  R14
   2     SG      2 @TIMECARD_LIB.TIMECARD(SCH_1):SG
   1 XP12R0V_A_PG      1 @TIMECARD_LIB.TIMECARD(SCH_1):XP12R0V_A_PG

RESISTOR-G155-03921-01,3.92KOHA  I188  R16
   2     SG      2 @TIMECARD_LIB.TIMECARD(SCH_1):SG
   1 XP12R0V_A_FLTB      1 @TIMECARD_LIB.TIMECARD(SCH_1):XP12R0V_A_FLTB

CAPACITOR-G107-0F106-EM,10UF,2A  I196  C6
   1 XP12R0V_A_AVIN      1 @TIMECARD_LIB.TIMECARD(SCH_1):XP12R0V_A_AVIN
   2     SG      2 @TIMECARD_LIB.TIMECARD(SCH_1):SG

RESISTOR-G155-11002-01,10KOHM,A  I197  R12
   2     SG      2 @TIMECARD_LIB.TIMECARD(SCH_1):SG
   1 XP12R0V_A_OV      1 @TIMECARD_LIB.TIMECARD(SCH_1):XP12R0V_A_OV

RESISTOR-G156-049R9-01,49.9OHMA  I198  R9
   2 XP12R0V_A_AVIN      2 @TIMECARD_LIB.TIMECARD(SCH_1):XP12R0V_A_AVIN
   1 XP12R0V_IN      1 @TIMECARD_LIB.TIMECARD(SCH_1):XP12R0V_IN

RESISTOR-G155-01203-01,120KOHMA  I199  R11
   2 XP12R0V_A_OV      2 @TIMECARD_LIB.TIMECARD(SCH_1):XP12R0V_A_OV
   1 XP12R0V_IN      1 @TIMECARD_LIB.TIMECARD(SCH_1):XP12R0V_IN

CAPACITOR-G104-0B103-EK,0.01UFA  I201  C8
   1 XP12R0V_A_OV      1 @TIMECARD_LIB.TIMECARD(SCH_1):XP12R0V_A_OV
   2     SG      2 @TIMECARD_LIB.TIMECARD(SCH_1):SG

RESISTOR-G155-11002-01,10KOHM,A  I202  R13
   2 XP12R0V_A_PG      2 @TIMECARD_LIB.TIMECARD(SCH_1):XP12R0V_A_PG
   1 XP12R0V      1 @TIMECARD_LIB.TIMECARD(SCH_1):XP12R0V

RESISTOR-G155-11002-01,10KOHM,A  I203  R15
   2 XP12R0V_A_FLTB      2 @TIMECARD_LIB.TIMECARD(SCH_1):XP12R0V_A_FLTB
   1 XP12R0V      1 @TIMECARD_LIB.TIMECARD(SCH_1):XP12R0V

DIODE_2-G122-00005-01  I204  CR3
   C XP12R0V      C @TIMECARD_LIB.TIMECARD(SCH_1):XP12R0V
   A     SG      A @TIMECARD_LIB.TIMECARD(SCH_1):SG

CAPACITOR-G107-0F106-EM,10UF,2A  I206  C9
   1 XP12R0V      1 @TIMECARD_LIB.TIMECARD(SCH_1):XP12R0V
   2     SG      2 @TIMECARD_LIB.TIMECARD(SCH_1):SG

CAPACITOR-G107-0F106-EM,10UF,2A  I207  C10
   1 XP12R0V      1 @TIMECARD_LIB.TIMECARD(SCH_1):XP12R0V
   2     SG      2 @TIMECARD_LIB.TIMECARD(SCH_1):SG

CAPACITOR-G105-0B104-EK,0.1UF,A  I211  C5
   1 XP12R0V_A_SS      1 @TIMECARD_LIB.TIMECARD(SCH_1):XP12R0V_A_SS
   2     SG      2 @TIMECARD_LIB.TIMECARD(SCH_1):SG

MP5022CGQV_Z_QFN22-G220-10510-A  I212  U1
   1 XP12R0V_A_EN     EN @TIMECARD_LIB.TIMECARD(SCH_1):XP12R0V_A_EN
   2 UNNAMED_15_MP5022CGQVZQFN22_I_2 LOADEN @TIMECARD_LIB.TIMECARD(SCH_1):UNNAMED_15_MP5022CGQVZQFN22_I212_LOADEN
   3 UNNAMED_15_MP5022CGQVZQFN22_I21   ENTM @TIMECARD_LIB.TIMECARD(SCH_1):UNNAMED_15_MP5022CGQVZQFN22_I212_ENTM
   4 XP12R0V_A_TIMER  TIMER @TIMECARD_LIB.TIMECARD(SCH_1):XP12R0V_A_TIMER
   5 XP12R0V_A_ISET   ISET @TIMECARD_LIB.TIMECARD(SCH_1):XP12R0V_A_ISET
   6 XP12R0V_A_SS     SS @TIMECARD_LIB.TIMECARD(SCH_1):XP12R0V_A_SS
   7     SG    GND @TIMECARD_LIB.TIMECARD(SCH_1):SG
   8 XP12R0V_A_IMON   IMON @TIMECARD_LIB.TIMECARD(SCH_1):XP12R0V_A_IMON
   9 XP12R0V_A_FLTB   FLTB @TIMECARD_LIB.TIMECARD(SCH_1):XP12R0V_A_FLTB
  10 XP12R0V_A_PG     PG @TIMECARD_LIB.TIMECARD(SCH_1):XP12R0V_A_PG
  11 XP12R0V_A_OV     OV @TIMECARD_LIB.TIMECARD(SCH_1):XP12R0V_A_OV
  12 XP12R0V_A_AVIN   AVIN @TIMECARD_LIB.TIMECARD(SCH_1):XP12R0V_A_AVIN
  13 XP12R0V VOUT_1 @TIMECARD_LIB.TIMECARD(SCH_1):XP12R0V
  14 XP12R0V VOUT_2 @TIMECARD_LIB.TIMECARD(SCH_1):XP12R0V
  15 XP12R0V VOUT_3 @TIMECARD_LIB.TIMECARD(SCH_1):XP12R0V
  16 XP12R0V VOUT_4 @TIMECARD_LIB.TIMECARD(SCH_1):XP12R0V
  17 XP12R0V VOUT_5 @TIMECARD_LIB.TIMECARD(SCH_1):XP12R0V
  18 XP12R0V VOUT_6 @TIMECARD_LIB.TIMECARD(SCH_1):XP12R0V
  19 XP12R0V VOUT_7 @TIMECARD_LIB.TIMECARD(SCH_1):XP12R0V
  20 XP12R0V VOUT_8 @TIMECARD_LIB.TIMECARD(SCH_1):XP12R0V
  21 XP12R0V_IN  VIN_1 @TIMECARD_LIB.TIMECARD(SCH_1):XP12R0V_IN
  22 XP12R0V_IN  VIN_2 @TIMECARD_LIB.TIMECARD(SCH_1):XP12R0V_IN
  23 XP12R0V_IN  VIN_3 @TIMECARD_LIB.TIMECARD(SCH_1):XP12R0V_IN
  24 XP12R0V_IN  VIN_4 @TIMECARD_LIB.TIMECARD(SCH_1):XP12R0V_IN
  25 XP12R0V_IN  VIN_5 @TIMECARD_LIB.TIMECARD(SCH_1):XP12R0V_IN
  26 XP12R0V_IN  VIN_6 @TIMECARD_LIB.TIMECARD(SCH_1):XP12R0V_IN

FUSE-G280-10012-01,2.5A  I223  FU1
   1 XP12R0V_IN      1 @TIMECARD_LIB.TIMECARD(SCH_1):XP12R0V_IN
   2 XP12R0V      2 @TIMECARD_LIB.TIMECARD(SCH_1):XP12R0V

CAPACITOR-G107-0F106-EM,10UF,2A  I229  C297
   1 XP12R0V_IN      1 @TIMECARD_LIB.TIMECARD(SCH_1):XP12R0V_IN
   2     SG      2 @TIMECARD_LIB.TIMECARD(SCH_1):SG

CAPACITOR-G107-0F106-EM,10UF,2A  I230  C299
   1 XP12R0V_IN      1 @TIMECARD_LIB.TIMECARD(SCH_1):XP12R0V_IN
   2     SG      2 @TIMECARD_LIB.TIMECARD(SCH_1):SG

CAPACITOR-G107-0F106-EM,10UF,2A  I231  C303
   1 XP12R0V_IN      1 @TIMECARD_LIB.TIMECARD(SCH_1):XP12R0V_IN
   2     SG      2 @TIMECARD_LIB.TIMECARD(SCH_1):SG

CAPACITOR-G107-0F106-EM,10UF,2A  I232  C301
   1 XP12R0V_IN      1 @TIMECARD_LIB.TIMECARD(SCH_1):XP12R0V_IN
   2     SG      2 @TIMECARD_LIB.TIMECARD(SCH_1):SG

CONN_HDR_2X3_M_RA_TH-G200-1251A  I238  P3
   1 XP12R0V_EXT      1 @TIMECARD_LIB.TIMECARD(SCH_1):XP12R0V_EXT
   2 XP12R0V_EXT      2 @TIMECARD_LIB.TIMECARD(SCH_1):XP12R0V_EXT
   3 XP12R0V_EXT      3 @TIMECARD_LIB.TIMECARD(SCH_1):XP12R0V_EXT
   4     SG      4 @TIMECARD_LIB.TIMECARD(SCH_1):SG
   5     SG      5 @TIMECARD_LIB.TIMECARD(SCH_1):SG
   6     SG      6 @TIMECARD_LIB.TIMECARD(SCH_1):SG

DIODE_3F-G122-10080-01  I239  CR12
   1 XP12R0V_PCIE    A_1 @TIMECARD_LIB.TIMECARD(SCH_1):XP12R0V_PCIE
   2 XP12R0V_EXT    A_2 @TIMECARD_LIB.TIMECARD(SCH_1):XP12R0V_EXT
   3 XP12R0V_IN      C @TIMECARD_LIB.TIMECARD(SCH_1):XP12R0V_IN

FERRITEBEAD-G191-10101-01,26OHA  I240  L20
   1 XP12R0V_PCIE      1 @TIMECARD_LIB.TIMECARD(SCH_1):XP12R0V_PCIE
   2 XP12R0V_IN      2 @TIMECARD_LIB.TIMECARD(SCH_1):XP12R0V_IN


DRAWING: @TIMECARD_LIB.TIMECARD(SCH_1):PAGE515 

RESISTOR-G155-11002-01,10KOHM,A  I56  R237
   2     SG      2 @TIMECARD_LIB.TIMECARD(SCH_1):SG
   1 XP3R3V_FPGA_EN_R      1 @TIMECARD_LIB.TIMECARD(SCH_1):XP3R3V_FPGA_EN_R

CAPACITOR-G107-0F226-CM,22UF,2A  I61  C232
   1 XP3R3V      1 @TIMECARD_LIB.TIMECARD(SCH_1):XP3R3V
   2     SG      2 @TIMECARD_LIB.TIMECARD(SCH_1):SG

CAPACITOR-G105-0B104-CK,0.1UF,A  I63  C233
   1 XP3R3V      1 @TIMECARD_LIB.TIMECARD(SCH_1):XP3R3V
   2     SG      2 @TIMECARD_LIB.TIMECARD(SCH_1):SG

CAPACITOR-G105-0B104-CK,0.1UF,A  I64  C237
   1 XP3R3V_FPGA      1 @TIMECARD_LIB.TIMECARD(SCH_1):XP3R3V_FPGA
   2     SG      2 @TIMECARD_LIB.TIMECARD(SCH_1):SG

CAPACITOR-G105-0B104-EK,0.1UF,A  I66  C236
   1 XP3R3V_FPGA_SR      1 @TIMECARD_LIB.TIMECARD(SCH_1):XP3R3V_FPGA_SR
   2     SG      2 @TIMECARD_LIB.TIMECARD(SCH_1):SG

RESISTOR-G155-11001-01,1KOHM,1%  I67  R260
   2 XP3R3V_FPGA_EN_R      2 @TIMECARD_LIB.TIMECARD(SCH_1):XP3R3V_FPGA_EN_R
   1 XP3R3V      1 @TIMECARD_LIB.TIMECARD(SCH_1):XP3R3V

RESISTOR-G155-11002-01,10KOHM,A  I69  R295
   2 UNNAMED_515_NCP45560IMNTWGHDFN1      2 @TIMECARD_LIB.TIMECARD(SCH_1):UNNAMED_515_NCP45560IMNTWGHDFN12_I82_PG
   1 XP3R3V_FPGA      1 @TIMECARD_LIB.TIMECARD(SCH_1):XP3R3V_FPGA

CAPACITOR-G107-0F226-CM,22UF,2A  I71  C240
   1 XP3R3V_FPGA      1 @TIMECARD_LIB.TIMECARD(SCH_1):XP3R3V_FPGA
   2     SG      2 @TIMECARD_LIB.TIMECARD(SCH_1):SG

CAPACITOR-G107-0F226-CM,22UF,2A  I72  C241
   1 XP3R3V_FPGA      1 @TIMECARD_LIB.TIMECARD(SCH_1):XP3R3V_FPGA
   2     SG      2 @TIMECARD_LIB.TIMECARD(SCH_1):SG

CAPACITOR-G107-0F226-CM,22UF,2A  I74  C243
   1 XP3R3V_FPGA      1 @TIMECARD_LIB.TIMECARD(SCH_1):XP3R3V_FPGA
   2     SG      2 @TIMECARD_LIB.TIMECARD(SCH_1):SG

NCP45560IMNTWG_H_DFN12-G222-10A  I76  U22
   3 XP3R3V    VCC @TIMECARD_LIB.TIMECARD(SCH_1):XP3R3V
   4     SG    GND @TIMECARD_LIB.TIMECARD(SCH_1):SG

CAPACITOR-G105-0B104-CK,0.1UF,A  I80  C235
   1 XP3R3V      1 @TIMECARD_LIB.TIMECARD(SCH_1):XP3R3V
   2     SG      2 @TIMECARD_LIB.TIMECARD(SCH_1):SG

CAPACITOR-G107-0F226-CM,22UF,2A  I81  C238
   1 XP3R3V_FPGA      1 @TIMECARD_LIB.TIMECARD(SCH_1):XP3R3V_FPGA
   2     SG      2 @TIMECARD_LIB.TIMECARD(SCH_1):SG

NCP45560IMNTWG_H_DFN12-G222-10A  I82  U22
   1 XP3R3V  VIN_1 @TIMECARD_LIB.TIMECARD(SCH_1):XP3R3V
   2 XP3R3V_FPGA_EN_R     EN @TIMECARD_LIB.TIMECARD(SCH_1):XP3R3V_FPGA_EN_R
   5 XP3R3V_FPGA_SR     SR @TIMECARD_LIB.TIMECARD(SCH_1):XP3R3V_FPGA_SR
   6 UNNAMED_515_NCP45560IMNTWGHDFN1     PG @TIMECARD_LIB.TIMECARD(SCH_1):UNNAMED_515_NCP45560IMNTWGHDFN12_I82_PG
   7 XP3R3V_FPGA  BLEED @TIMECARD_LIB.TIMECARD(SCH_1):XP3R3V_FPGA
   8 XP3R3V_FPGA VOUT_1 @TIMECARD_LIB.TIMECARD(SCH_1):XP3R3V_FPGA
   9 XP3R3V_FPGA VOUT_2 @TIMECARD_LIB.TIMECARD(SCH_1):XP3R3V_FPGA
  10 XP3R3V_FPGA VOUT_3 @TIMECARD_LIB.TIMECARD(SCH_1):XP3R3V_FPGA
  11 XP3R3V_FPGA VOUT_4 @TIMECARD_LIB.TIMECARD(SCH_1):XP3R3V_FPGA
  12 XP3R3V_FPGA VOUT_5 @TIMECARD_LIB.TIMECARD(SCH_1):XP3R3V_FPGA
  13 XP3R3V  VIN_2 @TIMECARD_LIB.TIMECARD(SCH_1):XP3R3V

CAPACITOR-G105-0B104-CK,0.1UF,A  I87  C229
   1 XP3R3V_FPGA_EN_R      1 @TIMECARD_LIB.TIMECARD(SCH_1):XP3R3V_FPGA_EN_R
   2     SG      2 @TIMECARD_LIB.TIMECARD(SCH_1):SG

RESISTOR-G155-13300-01,330OHM,A  I122  R226
   2 XP3R3V_FPGA_EN_R      2 @TIMECARD_LIB.TIMECARD(SCH_1):XP3R3V_FPGA_EN_R
   1 XP1R8V_FPGA_PG      1 @TIMECARD_LIB.TIMECARD(SCH_1):XP1R8V_FPGA_PG

RESISTOR-G155-11002-01,10KOHM,A  I127  R227
   2     SG      2 @TIMECARD_LIB.TIMECARD(SCH_1):SG
   1 UNNAMED_515_CAPACITOR_I128_1      1 @TIMECARD_LIB.TIMECARD(SCH_1):UNNAMED_515_CAPACITOR_I128_1

CAPACITOR-G105-0B104-EK,0.1UF,A  I128  C227
   1 UNNAMED_515_CAPACITOR_I128_1      1 @TIMECARD_LIB.TIMECARD(SCH_1):UNNAMED_515_CAPACITOR_I128_1
   2     SG      2 @TIMECARD_LIB.TIMECARD(SCH_1):SG

RESISTOR-G152-00055-01,1.13KOHA  I129  R228
   2 UNNAMED_515_CAPACITOR_I128_1      2 @TIMECARD_LIB.TIMECARD(SCH_1):UNNAMED_515_CAPACITOR_I128_1
   1 UNNAMED_515_CAPACITOR_I130_1      1 @TIMECARD_LIB.TIMECARD(SCH_1):UNNAMED_515_CAPACITOR_I130_1

CAPACITOR-G107-0F106-EM,10UF,2A  I130  C228
   1 UNNAMED_515_CAPACITOR_I130_1      1 @TIMECARD_LIB.TIMECARD(SCH_1):UNNAMED_515_CAPACITOR_I130_1
   2     SG      2 @TIMECARD_LIB.TIMECARD(SCH_1):SG

CAPACITOR-G104-0B103-EK,0.01UFA  I132  C231
   1 UNNAMED_515_CAPACITOR_I132_1      1 @TIMECARD_LIB.TIMECARD(SCH_1):UNNAMED_515_CAPACITOR_I132_1
   2     SG      2 @TIMECARD_LIB.TIMECARD(SCH_1):SG

CAPACITOR-G105-0B104-EK,0.1UF,A  I134  C230
   1 UNNAMED_515_CAPACITOR_I130_1      1 @TIMECARD_LIB.TIMECARD(SCH_1):UNNAMED_515_CAPACITOR_I130_1
   2     SG      2 @TIMECARD_LIB.TIMECARD(SCH_1):SG

FERRITEBEAD-G191-10101-01,26OHA  I135  L13
   1 XP3R3V      1 @TIMECARD_LIB.TIMECARD(SCH_1):XP3R3V
   2 UNNAMED_515_CAPACITOR_I130_1      2 @TIMECARD_LIB.TIMECARD(SCH_1):UNNAMED_515_CAPACITOR_I130_1

CAPACITOR-G104-0B103-EK,0.01UFA  I138  C234
   1 UNNAMED_515_CAPACITOR_I138_1      1 @TIMECARD_LIB.TIMECARD(SCH_1):UNNAMED_515_CAPACITOR_I138_1
   2     SG      2 @TIMECARD_LIB.TIMECARD(SCH_1):SG

RESISTOR-G155-14701-01,4.7KOHMA  I139  R229
   2 UNNAMED_515_CAPACITOR_I138_1      2 @TIMECARD_LIB.TIMECARD(SCH_1):UNNAMED_515_CAPACITOR_I138_1
   1 XP3R3V_FPGA      1 @TIMECARD_LIB.TIMECARD(SCH_1):XP3R3V_FPGA

RESISTOR-G155-100R0-J0,0OHM,-  I140  R230
   2 FPGA_CFG_INIT_N      2 @TIMECARD_LIB.TIMECARD(SCH_1):FPGA_CFG_INIT_N
   1 UNNAMED_515_CAPACITOR_I138_1      1 @TIMECARD_LIB.TIMECARD(SCH_1):UNNAMED_515_CAPACITOR_I138_1

RESISTOR-G155-02101-01,2.1KOHMA  I143  R232
   2 UNNAMED_515_ISL80101IRAJZDFN10_      2 @TIMECARD_LIB.TIMECARD(SCH_1):UNNAMED_515_ISL80101IRAJZDFN10_I151_SENSE
   1     SG      1 @TIMECARD_LIB.TIMECARD(SCH_1):SG

RESISTOR-G155-02101-01,2.1KOHMA  I145  R233
   2 UNNAMED_515_ISL80101IRAJZDFN10_      2 @TIMECARD_LIB.TIMECARD(SCH_1):UNNAMED_515_ISL80101IRAJZDFN10_I151_SENSE
   1     SG      1 @TIMECARD_LIB.TIMECARD(SCH_1):SG

RESISTOR-G155-04221-01,4.22KOHA  I146  R231
   2 UNNAMED_515_ISL80101IRAJZDFN10_      2 @TIMECARD_LIB.TIMECARD(SCH_1):UNNAMED_515_ISL80101IRAJZDFN10_I151_SENSE
   1 XP2R5V_FPGA      1 @TIMECARD_LIB.TIMECARD(SCH_1):XP2R5V_FPGA

CAPACITOR-G107-0F106-EM,10UF,2A  I147  C239
   1 XP2R5V_FPGA      1 @TIMECARD_LIB.TIMECARD(SCH_1):XP2R5V_FPGA
   2     SG      2 @TIMECARD_LIB.TIMECARD(SCH_1):SG

CAPACITOR-G105-0B104-EK,0.1UF,A  I149  C242
   1 XP2R5V_FPGA      1 @TIMECARD_LIB.TIMECARD(SCH_1):XP2R5V_FPGA
   2     SG      2 @TIMECARD_LIB.TIMECARD(SCH_1):SG

ISL80101IRAJZ_DFN10-G222-10136A  I151  U25
   1 XP2R5V_FPGA VOUT_1 @TIMECARD_LIB.TIMECARD(SCH_1):XP2R5V_FPGA
   2 XP2R5V_FPGA VOUT_2 @TIMECARD_LIB.TIMECARD(SCH_1):XP2R5V_FPGA
   3 UNNAMED_515_ISL80101IRAJZDFN10_ SENSE/ADJ @TIMECARD_LIB.TIMECARD(SCH_1):UNNAMED_515_ISL80101IRAJZDFN10_I151_SENSE
   4 UNNAMED_515_CAPACITOR_I138_1     PG @TIMECARD_LIB.TIMECARD(SCH_1):UNNAMED_515_CAPACITOR_I138_1
   5     SG    GND @TIMECARD_LIB.TIMECARD(SCH_1):SG
   6 UNNAMED_515_CAPACITOR_I132_1     SS @TIMECARD_LIB.TIMECARD(SCH_1):UNNAMED_515_CAPACITOR_I132_1
   7 UNNAMED_515_CAPACITOR_I128_1 ENABLE @TIMECARD_LIB.TIMECARD(SCH_1):UNNAMED_515_CAPACITOR_I128_1
   8     NC     NC     NC
   9 UNNAMED_515_CAPACITOR_I130_1  VIN_1 @TIMECARD_LIB.TIMECARD(SCH_1):UNNAMED_515_CAPACITOR_I130_1
  10 UNNAMED_515_CAPACITOR_I130_1  VIN_2 @TIMECARD_LIB.TIMECARD(SCH_1):UNNAMED_515_CAPACITOR_I130_1
  11     SG THRM_PAD @TIMECARD_LIB.TIMECARD(SCH_1):SG

RESISTOR-G155-13300-01,330OHM,A  I152  R225
   2 UNNAMED_515_CAPACITOR_I128_1      2 @TIMECARD_LIB.TIMECARD(SCH_1):UNNAMED_515_CAPACITOR_I128_1
   1 XP1R8V_FPGA_PG      1 @TIMECARD_LIB.TIMECARD(SCH_1):XP1R8V_FPGA_PG

CAPACITOR-G107-0F226-CM,22UF,2A  I154  C224
   1 XP3R3V      1 @TIMECARD_LIB.TIMECARD(SCH_1):XP3R3V
   2     SG      2 @TIMECARD_LIB.TIMECARD(SCH_1):SG

CAPACITOR-G105-0B104-EK,0.1UF,A  I155  C226
   1 XP3R3V      1 @TIMECARD_LIB.TIMECARD(SCH_1):XP3R3V
   2     SG      2 @TIMECARD_LIB.TIMECARD(SCH_1):SG

RESISTOR-G155-133R0-01,33OHM,1%  I167  R143
   2 UNNAMED_515_NCP45560IMNTWGHDFN1      2 @TIMECARD_LIB.TIMECARD(SCH_1):UNNAMED_515_NCP45560IMNTWGHDFN12_I82_PG
   1 FPGA_CFG_INIT_N      1 @TIMECARD_LIB.TIMECARD(SCH_1):FPGA_CFG_INIT_N

CAPACITOR-G105-0B224-DK,0.22UFA  I168  C293
   1 UNNAMED_515_CAPACITOR_I128_1      1 @TIMECARD_LIB.TIMECARD(SCH_1):UNNAMED_515_CAPACITOR_I128_1
   2     SG      2 @TIMECARD_LIB.TIMECARD(SCH_1):SG

CAPACITOR-G105-0B224-DK,0.22UFA  I169  C294
   1 XP3R3V_FPGA_EN_R      1 @TIMECARD_LIB.TIMECARD(SCH_1):XP3R3V_FPGA_EN_R
   2     SG      2 @TIMECARD_LIB.TIMECARD(SCH_1):SG


DRAWING: @TIMECARD_LIB.TIMECARD(SCH_1):PAGE523 

CAPACITOR-G105-0B104-CK,0.1UF,A  I7  C256
   1 UNNAMED_523_CAPACITOR_I7_1      1 @TIMECARD_LIB.TIMECARD(SCH_1):UNNAMED_523_CAPACITOR_I7_1
   2     SG      2 @TIMECARD_LIB.TIMECARD(SCH_1):SG

CAPACITOR-G104-0B472-EK,4700PFA  I9  C263
   1 UNNAMED_523_CAPACITOR_I9_1      1 @TIMECARD_LIB.TIMECARD(SCH_1):UNNAMED_523_CAPACITOR_I9_1
   2 XP1R0V_AGND      2 @TIMECARD_LIB.TIMECARD(SCH_1):XP1R0V_AGND

CAPACITOR-G104-0A180-FJ,18PF,5%  I10  C264
   1 XP1R0V_COMP      1 @TIMECARD_LIB.TIMECARD(SCH_1):XP1R0V_COMP
   2 XP1R0V_AGND      2 @TIMECARD_LIB.TIMECARD(SCH_1):XP1R0V_AGND

TPS54824RNVR_VQFN18-G220-10657A  I11  U26
   1 XP1R0V_BT   BOOT @TIMECARD_LIB.TIMECARD(SCH_1):XP1R0V_BT
   2 VIN_XP1R0V  VIN_1 @TIMECARD_LIB.TIMECARD(SCH_1):VIN_XP1R0V
   3     SG PGND_1 @TIMECARD_LIB.TIMECARD(SCH_1):SG
   4     SG PGND_2 @TIMECARD_LIB.TIMECARD(SCH_1):SG
   5     SG PGND_3 @TIMECARD_LIB.TIMECARD(SCH_1):SG
   6 XP1R0V_SW   SW_1 @TIMECARD_LIB.TIMECARD(SCH_1):XP1R0V_SW
   7 XP1R0V_SW   SW_2 @TIMECARD_LIB.TIMECARD(SCH_1):XP1R0V_SW
   8     SG PGND_4 @TIMECARD_LIB.TIMECARD(SCH_1):SG
   9     SG PGND_5 @TIMECARD_LIB.TIMECARD(SCH_1):SG
  10     SG PGND_6 @TIMECARD_LIB.TIMECARD(SCH_1):SG
  11 VIN_XP1R0V  VIN_2 @TIMECARD_LIB.TIMECARD(SCH_1):VIN_XP1R0V
  12 XP1R0V_AGND   AGND @TIMECARD_LIB.TIMECARD(SCH_1):XP1R0V_AGND
  13 XP1R0V_RT RT/CLK @TIMECARD_LIB.TIMECARD(SCH_1):XP1R0V_RT
  14 XP1R0V_FB_R_TO_AGND     FB @TIMECARD_LIB.TIMECARD(SCH_1):XP1R0V_FB_R_TO_AGND
  15 XP1R0V_COMP   COMP @TIMECARD_LIB.TIMECARD(SCH_1):XP1R0V_COMP
  16 XP1R0V_SS SS/TRK @TIMECARD_LIB.TIMECARD(SCH_1):XP1R0V_SS
  17 UNNAMED_523_CAPACITOR_I7_1     EN @TIMECARD_LIB.TIMECARD(SCH_1):UNNAMED_523_CAPACITOR_I7_1
  18 XP1R0V_PG  PGOOD @TIMECARD_LIB.TIMECARD(SCH_1):XP1R0V_PG

CAPACITOR-G105-0B223-EK,0.022UA  I12  C259
   1 XP1R0V_SS      1 @TIMECARD_LIB.TIMECARD(SCH_1):XP1R0V_SS
   2 XP1R0V_AGND      2 @TIMECARD_LIB.TIMECARD(SCH_1):XP1R0V_AGND

CAPACITOR-G107-0F106-EM,10UF,2A  I13  C257
   1 VIN_XP1R0V      1 @TIMECARD_LIB.TIMECARD(SCH_1):VIN_XP1R0V
   2     SG      2 @TIMECARD_LIB.TIMECARD(SCH_1):SG

CAPACITOR-G107-0F106-EM,10UF,2A  I14  C260
   1 VIN_XP1R0V      1 @TIMECARD_LIB.TIMECARD(SCH_1):VIN_XP1R0V
   2     SG      2 @TIMECARD_LIB.TIMECARD(SCH_1):SG

RESISTOR-G155-11003-01,100KOHMA  I15  R248
   2 XP1R0V_AGND      2 @TIMECARD_LIB.TIMECARD(SCH_1):XP1R0V_AGND
   1 XP1R0V_RT      1 @TIMECARD_LIB.TIMECARD(SCH_1):XP1R0V_RT

RESISTOR-G155-14701-01,4.7KOHMA  I16  R249
   2 UNNAMED_523_CAPACITOR_I9_1      2 @TIMECARD_LIB.TIMECARD(SCH_1):UNNAMED_523_CAPACITOR_I9_1
   1 XP1R0V_COMP      1 @TIMECARD_LIB.TIMECARD(SCH_1):XP1R0V_COMP

CAPACITOR-G105-0B104-EK,0.1UF,A  I17  C261
   1 VIN_XP1R0V      1 @TIMECARD_LIB.TIMECARD(SCH_1):VIN_XP1R0V
   2     SG      2 @TIMECARD_LIB.TIMECARD(SCH_1):SG

CAPACITOR-G105-0B104-EK,0.1UF,A  I19  C262
   1 VIN_XP1R0V      1 @TIMECARD_LIB.TIMECARD(SCH_1):VIN_XP1R0V
   2     SG      2 @TIMECARD_LIB.TIMECARD(SCH_1):SG

RESISTOR-G155-100R0-J0,0OHM,-  I23  R250
   2 UNNAMED_523_CAPACITOR_I24_1      2 @TIMECARD_LIB.TIMECARD(SCH_1):UNNAMED_523_CAPACITOR_I24_1
   1 XP1R0V_BT      1 @TIMECARD_LIB.TIMECARD(SCH_1):XP1R0V_BT

CAPACITOR-G105-0B104-EK,0.1UF,A  I24  C265
   1 UNNAMED_523_CAPACITOR_I24_1      1 @TIMECARD_LIB.TIMECARD(SCH_1):UNNAMED_523_CAPACITOR_I24_1
   2 XP1R0V_SW      2 @TIMECARD_LIB.TIMECARD(SCH_1):XP1R0V_SW

INDUCTOR_2-G190-10418-01,1.0UHA  I25  L5
   1 XP1R0V_SW      1 @TIMECARD_LIB.TIMECARD(SCH_1):XP1R0V_SW
   2 XP1R0V_FPGA      2 @TIMECARD_LIB.TIMECARD(SCH_1):XP1R0V_FPGA

RESISTOR-G157-12R20-01,2.2OHM,A  I26  R253
   2     SG      2 @TIMECARD_LIB.TIMECARD(SCH_1):SG
   1 UNNAMED_523_CAPACITOR_I31_2      1 @TIMECARD_LIB.TIMECARD(SCH_1):UNNAMED_523_CAPACITOR_I31_2

CAPACITOR-G104-0B101-FK,100PF,A  I28  C267
   1 UNNAMED_523_CAPACITOR_I28_1      1 @TIMECARD_LIB.TIMECARD(SCH_1):UNNAMED_523_CAPACITOR_I28_1
   2 XP1R0V_FB_R_TO_AGND      2 @TIMECARD_LIB.TIMECARD(SCH_1):XP1R0V_FB_R_TO_AGND

RESISTOR-G155-02262-01,22.6K,1%  I29  R255
   2 XP1R0V_FB_R_TO_AGND      2 @TIMECARD_LIB.TIMECARD(SCH_1):XP1R0V_FB_R_TO_AGND
   1 UNNAMED_523_CAPACITOR_I28_1      1 @TIMECARD_LIB.TIMECARD(SCH_1):UNNAMED_523_CAPACITOR_I28_1

RESISTOR-G155-120R0-01,20OHM,1%  I30  R254
   2 UNNAMED_523_CAPACITOR_I28_1      2 @TIMECARD_LIB.TIMECARD(SCH_1):UNNAMED_523_CAPACITOR_I28_1
   1 XP1R0V_FPGA      1 @TIMECARD_LIB.TIMECARD(SCH_1):XP1R0V_FPGA

CAPACITOR-G105-0A102-FJ,1000PFA  I31  C266
   1 XP1R0V_SW      1 @TIMECARD_LIB.TIMECARD(SCH_1):XP1R0V_SW
   2 UNNAMED_523_CAPACITOR_I31_2      2 @TIMECARD_LIB.TIMECARD(SCH_1):UNNAMED_523_CAPACITOR_I31_2

CAPACITOR-G105-0B104-CK,0.1UF,A  I33  C268
   1 XP1R0V_FPGA      1 @TIMECARD_LIB.TIMECARD(SCH_1):XP1R0V_FPGA
   2     SG      2 @TIMECARD_LIB.TIMECARD(SCH_1):SG

CAPACITOR-G107-0F476-AM,47UF,2A  I34  C269
   1 XP1R0V_FPGA      1 @TIMECARD_LIB.TIMECARD(SCH_1):XP1R0V_FPGA
   2     SG      2 @TIMECARD_LIB.TIMECARD(SCH_1):SG

CAPACITOR-G107-0F476-AM,47UF,2A  I35  C270
   1 XP1R0V_FPGA      1 @TIMECARD_LIB.TIMECARD(SCH_1):XP1R0V_FPGA
   2     SG      2 @TIMECARD_LIB.TIMECARD(SCH_1):SG

CAPACITOR-G107-0F476-AM,47UF,2A  I37  C271
   1 XP1R0V_FPGA      1 @TIMECARD_LIB.TIMECARD(SCH_1):XP1R0V_FPGA
   2     SG      2 @TIMECARD_LIB.TIMECARD(SCH_1):SG

SOLDER_PREFORM-G380-10015-01  I39  SP3
   1     SG      1 @TIMECARD_LIB.TIMECARD(SCH_1):SG
   2 XP1R0V_AGND      2 @TIMECARD_LIB.TIMECARD(SCH_1):XP1R0V_AGND

RESISTOR-G155-14701-01,4.7KOHMA  I44  R243
   2 XP1R0V_PG      2 @TIMECARD_LIB.TIMECARD(SCH_1):XP1R0V_PG
   1 XP3R3V      1 @TIMECARD_LIB.TIMECARD(SCH_1):XP3R3V

CAPACITOR-G105-0B104-EK,0.1UF,A  I46  C255
   1 XP12R0V      1 @TIMECARD_LIB.TIMECARD(SCH_1):XP12R0V
   2     SG      2 @TIMECARD_LIB.TIMECARD(SCH_1):SG

FERRITEBEAD-G191-10101-01,26OHA  I48  L9
   1 XP12R0V      1 @TIMECARD_LIB.TIMECARD(SCH_1):XP12R0V
   2 VIN_XP1R0V      2 @TIMECARD_LIB.TIMECARD(SCH_1):VIN_XP1R0V

CAPACITOR-G104-0B103-EK,0.01UFA  I50  C258
   1     SG      1 @TIMECARD_LIB.TIMECARD(SCH_1):SG
   2 XP1R0V_PG      2 @TIMECARD_LIB.TIMECARD(SCH_1):XP1R0V_PG

RESISTOR-A155-05101-DL,5.1KOHMA  I51  R246
   2     SG      2 @TIMECARD_LIB.TIMECARD(SCH_1):SG
   1 UNNAMED_523_CAPACITOR_I7_1      1 @TIMECARD_LIB.TIMECARD(SCH_1):UNNAMED_523_CAPACITOR_I7_1

RESISTOR-G155-11002-01,10KOHM,A  I54  R247
   2 UNNAMED_523_CAPACITOR_I7_1      2 @TIMECARD_LIB.TIMECARD(SCH_1):UNNAMED_523_CAPACITOR_I7_1
   1 VIN_XP1R0V      1 @TIMECARD_LIB.TIMECARD(SCH_1):VIN_XP1R0V

RESISTOR-G155-03322-01,33.2KOHA  I56  R251
   2 XP1R0V_FB_R_TO_AGND      2 @TIMECARD_LIB.TIMECARD(SCH_1):XP1R0V_FB_R_TO_AGND
   1 XP1R0V_AGND      1 @TIMECARD_LIB.TIMECARD(SCH_1):XP1R0V_AGND

RESISTOR-G156-100R0-J0,0OHM,-  I57  R252
   2 XP1R0V_FB_R_TO_AGND      2 @TIMECARD_LIB.TIMECARD(SCH_1):XP1R0V_FB_R_TO_AGND
   1 XP1R0V_AGND      1 @TIMECARD_LIB.TIMECARD(SCH_1):XP1R0V_AGND

RESISTOR-G155-100R0-J0,0OHM,-  I104  R245
   2 XP1R0V_PG      2 @TIMECARD_LIB.TIMECARD(SCH_1):XP1R0V_PG
   1 XP1R0V_FPGA_PG      1 @TIMECARD_LIB.TIMECARD(SCH_1):XP1R0V_FPGA_PG

RESISTOR-G155-100R0-J0,0OHM,-  I109  R244
   2 UNNAMED_523_CAPACITOR_I7_1      2 @TIMECARD_LIB.TIMECARD(SCH_1):UNNAMED_523_CAPACITOR_I7_1
   1 XP3R3V_PG      1 @TIMECARD_LIB.TIMECARD(SCH_1):XP3R3V_PG


DRAWING: @TIMECARD_LIB.TIMECARD(SCH_1):PAGE8 

RESISTOR-G155-14701-01,4.7KOHMA  I3  R70
   2 BF_ICP10100_I2C_SDA      2 @TIMECARD_LIB.TIMECARD(SCH_1):BF_ICP10100_I2C_SDA
   1 XP1R8V_ICP10100      1 @TIMECARD_LIB.TIMECARD(SCH_1):XP1R8V_ICP10100

RESISTOR-G155-14701-01,4.7KOHMA  I5  R71
   2 BF_ICP10100_I2C_SCL      2 @TIMECARD_LIB.TIMECARD(SCH_1):BF_ICP10100_I2C_SCL
   1 XP1R8V_ICP10100      1 @TIMECARD_LIB.TIMECARD(SCH_1):XP1R8V_ICP10100

RESISTOR-G155-133R0-01,33OHM,1%  I6  R73
   2 R_ICP10100_I2C_SCL      2 @TIMECARD_LIB.TIMECARD(SCH_1):R_ICP10100_I2C_SCL
   1 BF_ICP10100_I2C_SCL      1 @TIMECARD_LIB.TIMECARD(SCH_1):BF_ICP10100_I2C_SCL

RESISTOR-G155-133R0-01,33OHM,1%  I7  R72
   2 R_ICP10100_I2C_SDA      2 @TIMECARD_LIB.TIMECARD(SCH_1):R_ICP10100_I2C_SDA
   1 BF_ICP10100_I2C_SDA      1 @TIMECARD_LIB.TIMECARD(SCH_1):BF_ICP10100_I2C_SDA

CAPACITOR-G105-0B104-EK,0.1UF,A  I16  C276
   1 XP1R8V_FPGA      1 @TIMECARD_LIB.TIMECARD(SCH_1):XP1R8V_FPGA
   2     SG      2 @TIMECARD_LIB.TIMECARD(SCH_1):SG

FERRITEBEAD-G191-10097-01,600OA  I18  L18
   1 XP1R8V_FPGA      1 @TIMECARD_LIB.TIMECARD(SCH_1):XP1R8V_FPGA
   2 XP1R8V_ICP10100      2 @TIMECARD_LIB.TIMECARD(SCH_1):XP1R8V_ICP10100

CAPACITOR-G105-0B104-EK,0.1UF,A  I19  C278
   1 XP1R8V_ICP10100      1 @TIMECARD_LIB.TIMECARD(SCH_1):XP1R8V_ICP10100
   2     SG      2 @TIMECARD_LIB.TIMECARD(SCH_1):SG

CAPACITOR-G105-0C106-BM,10UF,2A  I21  C277
   1 XP1R8V_ICP10100      1 @TIMECARD_LIB.TIMECARD(SCH_1):XP1R8V_ICP10100
   2     SG      2 @TIMECARD_LIB.TIMECARD(SCH_1):SG

ICP_10100_LGA10-A222-00002-FB,A  I24  U28
   1 UNNAMED_8_ICP10100LGA10_I24_RES RESV_1 @TIMECARD_LIB.TIMECARD(SCH_1):UNNAMED_8_ICP10100LGA10_I24_RESV1
   2 R_ICP10100_I2C_SCL    SCL @TIMECARD_LIB.TIMECARD(SCH_1):R_ICP10100_I2C_SCL
   3 UNNAMED_8_ICP10100LGA10_I24_R_1 RESV_2 @TIMECARD_LIB.TIMECARD(SCH_1):UNNAMED_8_ICP10100LGA10_I24_RESV2
   4 R_ICP10100_I2C_SDA    SDA @TIMECARD_LIB.TIMECARD(SCH_1):R_ICP10100_I2C_SDA
   5 UNNAMED_8_ICP10100LGA10_I24_R_2 RESV_3 @TIMECARD_LIB.TIMECARD(SCH_1):UNNAMED_8_ICP10100LGA10_I24_RESV3
   6 UNNAMED_8_ICP10100LGA10_I24_R_3 RESV_4 @TIMECARD_LIB.TIMECARD(SCH_1):UNNAMED_8_ICP10100LGA10_I24_RESV4
   7 UNNAMED_8_ICP10100LGA10_I24_R_4 RESV_5 @TIMECARD_LIB.TIMECARD(SCH_1):UNNAMED_8_ICP10100LGA10_I24_RESV5
   8     SG  GND_1 @TIMECARD_LIB.TIMECARD(SCH_1):SG
   9     SG  GND_2 @TIMECARD_LIB.TIMECARD(SCH_1):SG
  10 XP1R8V_ICP10100    VDD @TIMECARD_LIB.TIMECARD(SCH_1):XP1R8V_ICP10100

RESISTOR-G155-100R0-J0,0OHM,-  I30  R351
   2     SG      2 @TIMECARD_LIB.TIMECARD(SCH_1):SG
   1 UNNAMED_8_ICP10100LGA10_I24_R_4      1 @TIMECARD_LIB.TIMECARD(SCH_1):UNNAMED_8_ICP10100LGA10_I24_RESV5

RESISTOR-G155-100R0-J0,0OHM,-  I31  R350
   2 XP1R8V_ICP10100      2 @TIMECARD_LIB.TIMECARD(SCH_1):XP1R8V_ICP10100
   1 UNNAMED_8_ICP10100LGA10_I24_R_3      1 @TIMECARD_LIB.TIMECARD(SCH_1):UNNAMED_8_ICP10100LGA10_I24_RESV4

RESISTOR-G155-100R0-J0,0OHM,-  I32  R347
   2 XP1R8V_ICP10100      2 @TIMECARD_LIB.TIMECARD(SCH_1):XP1R8V_ICP10100
   1 UNNAMED_8_ICP10100LGA10_I24_R_2      1 @TIMECARD_LIB.TIMECARD(SCH_1):UNNAMED_8_ICP10100LGA10_I24_RESV3

RESISTOR-G155-100R0-J0,0OHM,-  I33  R346
   2     SG      2 @TIMECARD_LIB.TIMECARD(SCH_1):SG
   1 UNNAMED_8_ICP10100LGA10_I24_R_1      1 @TIMECARD_LIB.TIMECARD(SCH_1):UNNAMED_8_ICP10100LGA10_I24_RESV2

RESISTOR-G155-100R0-J0,0OHM,-  I34  R343
   2     SG      2 @TIMECARD_LIB.TIMECARD(SCH_1):SG
   1 UNNAMED_8_ICP10100LGA10_I24_RES      1 @TIMECARD_LIB.TIMECARD(SCH_1):UNNAMED_8_ICP10100LGA10_I24_RESV1

CAPACITOR-G105-0B104-CK,0.1UF,A  I39  C312
   1 XP3R3V      1 @TIMECARD_LIB.TIMECARD(SCH_1):XP3R3V
   2     SG      2 @TIMECARD_LIB.TIMECARD(SCH_1):SG

CAPACITOR-G105-0B104-CK,0.1UF,A  I41  C313
   1 XP1R8V_ICP10100      1 @TIMECARD_LIB.TIMECARD(SCH_1):XP1R8V_ICP10100
   2     SG      2 @TIMECARD_LIB.TIMECARD(SCH_1):SG

PCA9508DP_TSSOP8-G223-10278-01  I51  U32
   2 BF_ICP10100_I2C_SCL   SCLA @TIMECARD_LIB.TIMECARD(SCH_1):BF_ICP10100_I2C_SCL
   3 BF_ICP10100_I2C_SDA   SDAA @TIMECARD_LIB.TIMECARD(SCH_1):BF_ICP10100_I2C_SDA
   5 UNNAMED_8_PCA9508DPTSSOP8_I51_E     EN @TIMECARD_LIB.TIMECARD(SCH_1):UNNAMED_8_PCA9508DPTSSOP8_I51_EN
   6 ICP10100_I2C_SDA   SDAB @TIMECARD_LIB.TIMECARD(SCH_1):ICP10100_I2C_SDA
   7 ICP10100_I2C_SCL   SCLB @TIMECARD_LIB.TIMECARD(SCH_1):ICP10100_I2C_SCL

PCA9508DP_TSSOP8-G223-10278-01  I52  U32
   1 XP1R8V_ICP10100  VCC_A @TIMECARD_LIB.TIMECARD(SCH_1):XP1R8V_ICP10100
   4     SG    GND @TIMECARD_LIB.TIMECARD(SCH_1):SG
   8 XP3R3V  VCC_B @TIMECARD_LIB.TIMECARD(SCH_1):XP3R3V

RESISTOR-G155-100R0-J0,0OHM,-  I63  R315
   2 BF_ICP10100_I2C_SCL      2 @TIMECARD_LIB.TIMECARD(SCH_1):BF_ICP10100_I2C_SCL
   1 ICP10100_I2C_SCL      1 @TIMECARD_LIB.TIMECARD(SCH_1):ICP10100_I2C_SCL

RESISTOR-G155-100R0-J0,0OHM,-  I64  R316
   2 BF_ICP10100_I2C_SDA      2 @TIMECARD_LIB.TIMECARD(SCH_1):BF_ICP10100_I2C_SDA
   1 ICP10100_I2C_SDA      1 @TIMECARD_LIB.TIMECARD(SCH_1):ICP10100_I2C_SDA

RESISTOR-G155-14701-01,4.7KOHMA  I69  R282
   2 ICP10100_I2C_SCL      2 @TIMECARD_LIB.TIMECARD(SCH_1):ICP10100_I2C_SCL
   1 XP3R3V_FPGA      1 @TIMECARD_LIB.TIMECARD(SCH_1):XP3R3V_FPGA

RESISTOR-G155-14701-01,4.7KOHMA  I70  R281
   2 ICP10100_I2C_SDA      2 @TIMECARD_LIB.TIMECARD(SCH_1):ICP10100_I2C_SDA
   1 XP3R3V_FPGA      1 @TIMECARD_LIB.TIMECARD(SCH_1):XP3R3V_FPGA

RESISTOR-G155-14701-01,4.7KOHMA  I71  R314
   2 UNNAMED_8_PCA9508DPTSSOP8_I51_E      2 @TIMECARD_LIB.TIMECARD(SCH_1):UNNAMED_8_PCA9508DPTSSOP8_I51_EN
   1 XP3R3V_FPGA      1 @TIMECARD_LIB.TIMECARD(SCH_1):XP3R3V_FPGA


DRAWING: @TIMECARD_LIB.TIMECARD(SCH_1):PAGE127 

XC7A200T_2FBG484C_FBG484-G240-A  I232  U24
 L12 CCLK_0 CCLK_0 @TIMECARD_LIB.TIMECARD(SCH_1):CCLK_0
  U8 CFGBVS CFGBVS_0 @TIMECARD_LIB.TIMECARD(SCH_1):CFGBVS
 G11 FPGA_DONE DONE_0 @TIMECARD_LIB.TIMECARD(SCH_1):FPGA_DONE
  N9     SG  DXN_0 @TIMECARD_LIB.TIMECARD(SCH_1):SG
 N10     SG  DXP_0 @TIMECARD_LIB.TIMECARD(SCH_1):SG
 U12 FPGA_CFG_INIT_N INIT_0* @TIMECARD_LIB.TIMECARD(SCH_1):FPGA_CFG_INIT_N
 U11 FPGA_M0   M0_0 @TIMECARD_LIB.TIMECARD(SCH_1):FPGA_M0
 U10 FPGA_M1   M1_0 @TIMECARD_LIB.TIMECARD(SCH_1):FPGA_M1
  U9 FPGA_M2   M2_0 @TIMECARD_LIB.TIMECARD(SCH_1):FPGA_M2
  A8 CPU_TX_PCIE_MGT_0_RXN MGTPRXN0_216 @TIMECARD_LIB.TIMECARD(SCH_1):CPU_TX_PCIE_MGT_0_RXN
 C11 CPU_TX_PCIE_MGT_1_RXN MGTPRXN1_216 @TIMECARD_LIB.TIMECARD(SCH_1):CPU_TX_PCIE_MGT_1_RXN
 A10 CPU_TX_PCIE_MGT_2_RXN MGTPRXN2_216 @TIMECARD_LIB.TIMECARD(SCH_1):CPU_TX_PCIE_MGT_2_RXN
  C9 CPU_TX_PCIE_MGT_3_RXN MGTPRXN3_216 @TIMECARD_LIB.TIMECARD(SCH_1):CPU_TX_PCIE_MGT_3_RXN
  B8 CPU_TX_PCIE_MGT_0_RXP MGTPRXP0_216 @TIMECARD_LIB.TIMECARD(SCH_1):CPU_TX_PCIE_MGT_0_RXP
 D11 CPU_TX_PCIE_MGT_1_RXP MGTPRXP1_216 @TIMECARD_LIB.TIMECARD(SCH_1):CPU_TX_PCIE_MGT_1_RXP
 B10 CPU_TX_PCIE_MGT_2_RXP MGTPRXP2_216 @TIMECARD_LIB.TIMECARD(SCH_1):CPU_TX_PCIE_MGT_2_RXP
  D9 CPU_TX_PCIE_MGT_3_RXP MGTPRXP3_216 @TIMECARD_LIB.TIMECARD(SCH_1):CPU_TX_PCIE_MGT_3_RXP
  A4 CPU_RX_PCIE_MGT0_TXN MGTPTXN0_216 @TIMECARD_LIB.TIMECARD(SCH_1):CPU_RX_PCIE_MGT0_TXN
  C5 CPU_RX_PCIE_MGT1_TXN MGTPTXN1_216 @TIMECARD_LIB.TIMECARD(SCH_1):CPU_RX_PCIE_MGT1_TXN
  A6 CPU_RX_PCIE_MGT2_TXN MGTPTXN2_216 @TIMECARD_LIB.TIMECARD(SCH_1):CPU_RX_PCIE_MGT2_TXN
  C7 CPU_RX_PCIE_MGT3_TXN MGTPTXN3_216 @TIMECARD_LIB.TIMECARD(SCH_1):CPU_RX_PCIE_MGT3_TXN
  B4 CPU_RX_PCIE_MGT0_TXP MGTPTXP0_216 @TIMECARD_LIB.TIMECARD(SCH_1):CPU_RX_PCIE_MGT0_TXP
  D5 CPU_RX_PCIE_MGT1_TXP MGTPTXP1_216 @TIMECARD_LIB.TIMECARD(SCH_1):CPU_RX_PCIE_MGT1_TXP
  B6 CPU_RX_PCIE_MGT2_TXP MGTPTXP2_216 @TIMECARD_LIB.TIMECARD(SCH_1):CPU_RX_PCIE_MGT2_TXP
  D7 CPU_RX_PCIE_MGT3_TXP MGTPTXP3_216 @TIMECARD_LIB.TIMECARD(SCH_1):CPU_RX_PCIE_MGT3_TXP
  E6 MHZ125CLKN_CLKIN MGTREFCLK0N_216 @TIMECARD_LIB.TIMECARD(SCH_1):MHZ125CLKN_CLKIN
  F6 MHZ125CLKP_CLKIN MGTREFCLK0P_216 @TIMECARD_LIB.TIMECARD(SCH_1):MHZ125CLKP_CLKIN
 E10 PCIE_REFCLKN MGTREFCLK1N_216 @TIMECARD_LIB.TIMECARD(SCH_1):PCIE_REFCLKN
 F10 PCIE_REFCLKP MGTREFCLK1P_216 @TIMECARD_LIB.TIMECARD(SCH_1):PCIE_REFCLKP
  F8 FPGA_MGTRREF MGTRREF_216 @TIMECARD_LIB.TIMECARD(SCH_1):FPGA_MGTRREF
 N12 FPGA_PROGRAM_N PROGRAM_0* @TIMECARD_LIB.TIMECARD(SCH_1):FPGA_PROGRAM_N
 V12 FPGA_TCK  TCK_0 @TIMECARD_LIB.TIMECARD(SCH_1):FPGA_TCK
 R13 FPGA_TDI  TDI_0 @TIMECARD_LIB.TIMECARD(SCH_1):FPGA_TDI
 U13 R_FPGA_TDO  TDO_0 @TIMECARD_LIB.TIMECARD(SCH_1):R_FPGA_TDO
 T13 FPGA_TMS  TMS_0 @TIMECARD_LIB.TIMECARD(SCH_1):FPGA_TMS
  M9     SG   VN_0 @TIMECARD_LIB.TIMECARD(SCH_1):SG
 L10     SG   VP_0 @TIMECARD_LIB.TIMECARD(SCH_1):SG
  L9     SG VREFN_0 @TIMECARD_LIB.TIMECARD(SCH_1):SG
 M10     SG VREFP_0 @TIMECARD_LIB.TIMECARD(SCH_1):SG

RESISTOR-G155-14701-01,4.7KOHMA  I329  R194
   2 CFGBVS      2 @TIMECARD_LIB.TIMECARD(SCH_1):CFGBVS
   1 XP3R3V_FPGA      1 @TIMECARD_LIB.TIMECARD(SCH_1):XP3R3V_FPGA

RESISTOR-G155-14701-01,4.7KOHMA  I330  R193
   2 FPGA_PROGRAM_N      2 @TIMECARD_LIB.TIMECARD(SCH_1):FPGA_PROGRAM_N
   1 XP3R3V_FPGA      1 @TIMECARD_LIB.TIMECARD(SCH_1):XP3R3V_FPGA

RESISTOR-G155-133R0-01,33OHM,1%  I331  R195
   2 R_FPGA_TDO      2 @TIMECARD_LIB.TIMECARD(SCH_1):R_FPGA_TDO
   1 FPGA_TDO      1 @TIMECARD_LIB.TIMECARD(SCH_1):FPGA_TDO

RESISTOR-G155-11000-01,100OHM,A  I332  R196
   2 FPGA_MGTRREF      2 @TIMECARD_LIB.TIMECARD(SCH_1):FPGA_MGTRREF
   1 FPGA_MGTAVTT      1 @TIMECARD_LIB.TIMECARD(SCH_1):FPGA_MGTAVTT

RESISTOR-G155-11000-01,100OHM,A  I333  R197
   2 MHZ125CLKN_CLKIN      2 @TIMECARD_LIB.TIMECARD(SCH_1):MHZ125CLKN_CLKIN
   1 MHZ125CLKP_CLKIN      1 @TIMECARD_LIB.TIMECARD(SCH_1):MHZ125CLKP_CLKIN

RESISTOR-G155-11000-01,100OHM,A  I334  R198
   2 PCIE_REFCLKN      2 @TIMECARD_LIB.TIMECARD(SCH_1):PCIE_REFCLKN
   1 PCIE_REFCLKP      1 @TIMECARD_LIB.TIMECARD(SCH_1):PCIE_REFCLKP

RESISTOR-G155-100R0-J0,0OHM,-  I337  R207
   2 FPGA_FLASH_CLK      2 @TIMECARD_LIB.TIMECARD(SCH_1):FPGA_FLASH_CLK
   1 CCLK_0      1 @TIMECARD_LIB.TIMECARD(SCH_1):CCLK_0

RESISTOR-G155-13300-01,330OHM,A  I338  R210
   2 XP3R3V_FPGA      2 @TIMECARD_LIB.TIMECARD(SCH_1):XP3R3V_FPGA
   1 FPGA_DONE      1 @TIMECARD_LIB.TIMECARD(SCH_1):FPGA_DONE

RESISTOR-G155-14701-01,4.7KOHMA  I339  R209
   2 XP3R3V_FPGA      2 @TIMECARD_LIB.TIMECARD(SCH_1):XP3R3V_FPGA
   1 FPGA_CFG_INIT_N      1 @TIMECARD_LIB.TIMECARD(SCH_1):FPGA_CFG_INIT_N

RESISTOR-G155-11001-01,1KOHM,1%  I391  R216
   2     SG      2 @TIMECARD_LIB.TIMECARD(SCH_1):SG
   1 FPGA_BRD_REV1      1 @TIMECARD_LIB.TIMECARD(SCH_1):FPGA_BRD_REV1

RESISTOR-G155-11002-01,10KOHM,A  I392  R219
   2 FPGA_BRD_REV0      2 @TIMECARD_LIB.TIMECARD(SCH_1):FPGA_BRD_REV0
   1 XP3R3V_FPGA      1 @TIMECARD_LIB.TIMECARD(SCH_1):XP3R3V_FPGA

RESISTOR-G155-11001-01,1KOHM,1%  I393  R220
   2     SG      2 @TIMECARD_LIB.TIMECARD(SCH_1):SG
   1 FPGA_BRD_REV0      1 @TIMECARD_LIB.TIMECARD(SCH_1):FPGA_BRD_REV0

RESISTOR-G155-11002-01,10KOHM,A  I394  R215
   2 FPGA_BRD_REV1      2 @TIMECARD_LIB.TIMECARD(SCH_1):FPGA_BRD_REV1
   1 XP3R3V_FPGA      1 @TIMECARD_LIB.TIMECARD(SCH_1):XP3R3V_FPGA

RESISTOR-G155-11002-01,10KOHM,A  I396  R213
   2 FPGA_BRD_REV2      2 @TIMECARD_LIB.TIMECARD(SCH_1):FPGA_BRD_REV2
   1 XP3R3V_FPGA      1 @TIMECARD_LIB.TIMECARD(SCH_1):XP3R3V_FPGA

RESISTOR-G155-11001-01,1KOHM,1%  I397  R214
   2     SG      2 @TIMECARD_LIB.TIMECARD(SCH_1):SG
   1 FPGA_BRD_REV2      1 @TIMECARD_LIB.TIMECARD(SCH_1):FPGA_BRD_REV2

RESISTOR-G155-11000-01,100OHM,A  I402  R217
   2 FPGA_M1      2 @TIMECARD_LIB.TIMECARD(SCH_1):FPGA_M1
   1 XP3R3V_FPGA      1 @TIMECARD_LIB.TIMECARD(SCH_1):XP3R3V_FPGA

RESISTOR-G155-11000-01,100OHM,A  I403  R221
   2 FPGA_M2      2 @TIMECARD_LIB.TIMECARD(SCH_1):FPGA_M2
   1 XP3R3V_FPGA      1 @TIMECARD_LIB.TIMECARD(SCH_1):XP3R3V_FPGA

RESISTOR-G155-11000-01,100OHM,A  I404  R211
   2 FPGA_M0      2 @TIMECARD_LIB.TIMECARD(SCH_1):FPGA_M0
   1 XP3R3V_FPGA      1 @TIMECARD_LIB.TIMECARD(SCH_1):XP3R3V_FPGA

RESISTOR-G155-11000-01,100OHM,A  I405  R222
   2     SG      2 @TIMECARD_LIB.TIMECARD(SCH_1):SG
   1 FPGA_M2      1 @TIMECARD_LIB.TIMECARD(SCH_1):FPGA_M2

RESISTOR-G155-11000-01,100OHM,A  I406  R218
   2     SG      2 @TIMECARD_LIB.TIMECARD(SCH_1):SG
   1 FPGA_M1      1 @TIMECARD_LIB.TIMECARD(SCH_1):FPGA_M1

RESISTOR-G155-11000-01,100OHM,A  I407  R212
   2     SG      2 @TIMECARD_LIB.TIMECARD(SCH_1):SG
   1 FPGA_M0      1 @TIMECARD_LIB.TIMECARD(SCH_1):FPGA_M0

G200_10283_01-G200-10283-01  I427  J14
   1 FT4232_FPGA_TCK      1 @TIMECARD_LIB.TIMECARD(SCH_1):FT4232_FPGA_TCK
   2     SG      2 @TIMECARD_LIB.TIMECARD(SCH_1):SG
   3 FT4232_FPGA_TDO      3 @TIMECARD_LIB.TIMECARD(SCH_1):FT4232_FPGA_TDO
   4 UNNAMED_127_G2001028301_I427_4      4 @TIMECARD_LIB.TIMECARD(SCH_1):UNNAMED_127_G2001028301_I427_4
   5 FT4232_FPGA_TMS      5 @TIMECARD_LIB.TIMECARD(SCH_1):FT4232_FPGA_TMS
   6     NC      6     NC
   7     NC      7     NC
   8     NC      8     NC
   9 FT4232_FPGA_TDI      9 @TIMECARD_LIB.TIMECARD(SCH_1):FT4232_FPGA_TDI
  10     SG     10 @TIMECARD_LIB.TIMECARD(SCH_1):SG

RESISTOR-G155-11002-01,10KOHM,A  I432  R405
   2 FPGA_TDI      2 @TIMECARD_LIB.TIMECARD(SCH_1):FPGA_TDI
   1 XP3R3V_FPGA      1 @TIMECARD_LIB.TIMECARD(SCH_1):XP3R3V_FPGA

RESISTOR-G155-11002-01,10KOHM,A  I434  R404
   2 FPGA_TMS      2 @TIMECARD_LIB.TIMECARD(SCH_1):FPGA_TMS
   1 XP3R3V_FPGA      1 @TIMECARD_LIB.TIMECARD(SCH_1):XP3R3V_FPGA

RESISTOR-G155-11002-01,10KOHM,A  I435  R403
   2 FPGA_TDO      2 @TIMECARD_LIB.TIMECARD(SCH_1):FPGA_TDO
   1 XP3R3V_FPGA      1 @TIMECARD_LIB.TIMECARD(SCH_1):XP3R3V_FPGA

RESISTOR-G155-133R0-01,33OHM,1%  I436  R134
   2 FPGA_TCK      2 @TIMECARD_LIB.TIMECARD(SCH_1):FPGA_TCK
   1 FT4232_FPGA_TCK      1 @TIMECARD_LIB.TIMECARD(SCH_1):FT4232_FPGA_TCK

RESISTOR-G155-133R0-01,33OHM,1%  I437  R136
   2 FPGA_TMS      2 @TIMECARD_LIB.TIMECARD(SCH_1):FPGA_TMS
   1 FT4232_FPGA_TMS      1 @TIMECARD_LIB.TIMECARD(SCH_1):FT4232_FPGA_TMS

RESISTOR-G155-100R0-J0,0OHM,-  I438  R135
   2 FPGA_TDO      2 @TIMECARD_LIB.TIMECARD(SCH_1):FPGA_TDO
   1 FT4232_FPGA_TDO      1 @TIMECARD_LIB.TIMECARD(SCH_1):FT4232_FPGA_TDO

RESISTOR-G155-133R0-01,33OHM,1%  I439  R137
   2 FPGA_TDI      2 @TIMECARD_LIB.TIMECARD(SCH_1):FPGA_TDI
   1 FT4232_FPGA_TDI      1 @TIMECARD_LIB.TIMECARD(SCH_1):FT4232_FPGA_TDI

RESISTOR-G155-12201-01,2.2KOHMA  I440  R402
   2     SG      2 @TIMECARD_LIB.TIMECARD(SCH_1):SG
   1 FPGA_TCK      1 @TIMECARD_LIB.TIMECARD(SCH_1):FPGA_TCK

DIODE_4_V1-G122-10123-01  I442  CR7
   1     SG    GND @TIMECARD_LIB.TIMECARD(SCH_1):SG
   2 FT4232_FPGA_TCK    IO1 @TIMECARD_LIB.TIMECARD(SCH_1):FT4232_FPGA_TCK
   3 FT4232_FPGA_TDO    IO2 @TIMECARD_LIB.TIMECARD(SCH_1):FT4232_FPGA_TDO
   4     NC    VDD     NC

DIODE_4_V1-G122-10123-01  I443  CR6
   1     SG    GND @TIMECARD_LIB.TIMECARD(SCH_1):SG
   2 FT4232_FPGA_TMS    IO1 @TIMECARD_LIB.TIMECARD(SCH_1):FT4232_FPGA_TMS
   3 FT4232_FPGA_TDI    IO2 @TIMECARD_LIB.TIMECARD(SCH_1):FT4232_FPGA_TDI
   4     NC    VDD     NC

RESISTOR-G155-133R0-01,33OHM,1%  I446  R133
   2 UNNAMED_127_G2001028301_I427_4      2 @TIMECARD_LIB.TIMECARD(SCH_1):UNNAMED_127_G2001028301_I427_4
   1 XP3R3V_FPGA      1 @TIMECARD_LIB.TIMECARD(SCH_1):XP3R3V_FPGA

MT25QL128ABA1ESE_SOP8-G221-102A  I456  U23
   1 FLASH_CS_N     S* @TIMECARD_LIB.TIMECARD(SCH_1):FLASH_CS_N
   2 UNNAMED_127_MT25QL128ABA1ESES_1    DQ1 @TIMECARD_LIB.TIMECARD(SCH_1):UNNAMED_127_MT25QL128ABA1ESESOP8_I456_DQ1
   3 UNNAMED_127_MT25QL128ABA1ESES_3 W/DQ2* @TIMECARD_LIB.TIMECARD(SCH_1):UNNAMED_127_MT25QL128ABA1ESESOP8_I456_W
   4     SG    VSS @TIMECARD_LIB.TIMECARD(SCH_1):SG
   5 UNNAMED_127_MT25QL128ABA1ESESOP    DQ0 @TIMECARD_LIB.TIMECARD(SCH_1):UNNAMED_127_MT25QL128ABA1ESESOP8_I456_DQ0
   6 FLASH_CLK      C @TIMECARD_LIB.TIMECARD(SCH_1):FLASH_CLK
   7 UNNAMED_127_MT25QL128ABA1ESES_2 HOLD/DQ3* @TIMECARD_LIB.TIMECARD(SCH_1):UNNAMED_127_MT25QL128ABA1ESESOP8_I456_HOLD
   8 XP3R3V_FPGA    VCC @TIMECARD_LIB.TIMECARD(SCH_1):XP3R3V_FPGA

RESISTOR-G155-14701-01,4.7KOHMA  I462  R199
   2 XP3R3V_FPGA      2 @TIMECARD_LIB.TIMECARD(SCH_1):XP3R3V_FPGA
   1 UNNAMED_127_MT25QL128ABA1ESESOP      1 @TIMECARD_LIB.TIMECARD(SCH_1):UNNAMED_127_MT25QL128ABA1ESESOP8_I456_DQ0

RESISTOR-G155-14701-01,4.7KOHMA  I463  R201
   2 XP3R3V_FPGA      2 @TIMECARD_LIB.TIMECARD(SCH_1):XP3R3V_FPGA
   1 UNNAMED_127_MT25QL128ABA1ESES_3      1 @TIMECARD_LIB.TIMECARD(SCH_1):UNNAMED_127_MT25QL128ABA1ESESOP8_I456_W

RESISTOR-G155-14701-01,4.7KOHMA  I464  R202
   2 XP3R3V_FPGA      2 @TIMECARD_LIB.TIMECARD(SCH_1):XP3R3V_FPGA
   1 UNNAMED_127_MT25QL128ABA1ESES_2      1 @TIMECARD_LIB.TIMECARD(SCH_1):UNNAMED_127_MT25QL128ABA1ESESOP8_I456_HOLD

RESISTOR-G155-14701-01,4.7KOHMA  I465  R200
   2 XP3R3V_FPGA      2 @TIMECARD_LIB.TIMECARD(SCH_1):XP3R3V_FPGA
   1 UNNAMED_127_MT25QL128ABA1ESES_1      1 @TIMECARD_LIB.TIMECARD(SCH_1):UNNAMED_127_MT25QL128ABA1ESESOP8_I456_DQ1

RESISTOR-G155-133R0-01,33OHM,1%  I466  R204
   2 FLASH_DQ1_MISO      2 @TIMECARD_LIB.TIMECARD(SCH_1):FLASH_DQ1_MISO
   1 UNNAMED_127_MT25QL128ABA1ESES_1      1 @TIMECARD_LIB.TIMECARD(SCH_1):UNNAMED_127_MT25QL128ABA1ESESOP8_I456_DQ1

RESISTOR-G155-133R0-01,33OHM,1%  I467  R203
   2 FLASH_DQ0_MOSI      2 @TIMECARD_LIB.TIMECARD(SCH_1):FLASH_DQ0_MOSI
   1 UNNAMED_127_MT25QL128ABA1ESESOP      1 @TIMECARD_LIB.TIMECARD(SCH_1):UNNAMED_127_MT25QL128ABA1ESESOP8_I456_DQ0

RESISTOR-G155-133R0-01,33OHM,1%  I468  R205
   2 FLASH_DQ2      2 @TIMECARD_LIB.TIMECARD(SCH_1):FLASH_DQ2
   1 UNNAMED_127_MT25QL128ABA1ESES_3      1 @TIMECARD_LIB.TIMECARD(SCH_1):UNNAMED_127_MT25QL128ABA1ESESOP8_I456_W

RESISTOR-G155-133R0-01,33OHM,1%  I469  R206
   2 FLASH_DQ3      2 @TIMECARD_LIB.TIMECARD(SCH_1):FLASH_DQ3
   1 UNNAMED_127_MT25QL128ABA1ESES_2      1 @TIMECARD_LIB.TIMECARD(SCH_1):UNNAMED_127_MT25QL128ABA1ESESOP8_I456_HOLD

RESISTOR-G155-14701-01,4.7KOHMA  I470  R192
   2     SG      2 @TIMECARD_LIB.TIMECARD(SCH_1):SG
   1 FLASH_CLK      1 @TIMECARD_LIB.TIMECARD(SCH_1):FLASH_CLK

RESISTOR-G155-14701-01,4.7KOHMA  I471  R191
   2 FLASH_CS_N      2 @TIMECARD_LIB.TIMECARD(SCH_1):FLASH_CS_N
   1 XP3R3V_FPGA      1 @TIMECARD_LIB.TIMECARD(SCH_1):XP3R3V_FPGA

CAPACITOR-G105-0B104-CK,0.1UF,A  I472  C199
   1 XP3R3V_FPGA      1 @TIMECARD_LIB.TIMECARD(SCH_1):XP3R3V_FPGA
   2     SG      2 @TIMECARD_LIB.TIMECARD(SCH_1):SG

CAPACITOR-G105-0F475-BM,4.7UF,A  I473  C198
   1 XP3R3V_FPGA      1 @TIMECARD_LIB.TIMECARD(SCH_1):XP3R3V_FPGA
   2     SG      2 @TIMECARD_LIB.TIMECARD(SCH_1):SG


DRAWING: @TIMECARD_LIB.TIMECARD(SCH_1):PAGE12 

DIODE_4_V1-G122-10123-01  I42  CR5
   1     SG    GND @TIMECARD_LIB.TIMECARD(SCH_1):SG
   2 SMA4_SIG_IO_CONN    IO1 @TIMECARD_LIB.TIMECARD(SCH_1):SMA4_SIG_IO_CONN
   3 SMA3_SIG_IO_CONN    IO2 @TIMECARD_LIB.TIMECARD(SCH_1):SMA3_SIG_IO_CONN
   4     NC    VDD     NC

RESISTOR-G155-11000-01,100OHM,A  I63  R156
   2 UNNAMED_12_74HCT2G125DPTSSOP8_I      2 @TIMECARD_LIB.TIMECARD(SCH_1):UNNAMED_12_74HCT2G125DPTSSOP8_I204_1A
   1 ANT3_OUT      1 @TIMECARD_LIB.TIMECARD(SCH_1):ANT3_OUT

RESISTOR-G155-14701-01,4.7KOHMA  I88  R365
   2 SMA3_SIG_OUT_BF_EN_N      2 @TIMECARD_LIB.TIMECARD(SCH_1):SMA3_SIG_OUT_BF_EN_N
   1 XP3R3V_FPGA      1 @TIMECARD_LIB.TIMECARD(SCH_1):XP3R3V_FPGA

DIODE_4_V1-G122-10123-01  I179  CR4
   1     SG    GND @TIMECARD_LIB.TIMECARD(SCH_1):SG
   2 SMA2_SIG_IO_CONN    IO1 @TIMECARD_LIB.TIMECARD(SCH_1):SMA2_SIG_IO_CONN
   3 SMA1_SIG_IO_CONN    IO2 @TIMECARD_LIB.TIMECARD(SCH_1):SMA1_SIG_IO_CONN
   4     NC    VDD     NC

RESISTOR-G155-149R9-01,49.9OHMA  I197  R122
   2 SMA3_SIG_IO_CONN      2 @TIMECARD_LIB.TIMECARD(SCH_1):SMA3_SIG_IO_CONN
   1 BF_SMA3_SIG_IO_CONN      1 @TIMECARD_LIB.TIMECARD(SCH_1):BF_SMA3_SIG_IO_CONN

74HCT2G125DP_TSSOP8-G220-00055A  I204  U13
   1 SMA3_SIG_OUT_BF_EN_N   1OE* @TIMECARD_LIB.TIMECARD(SCH_1):SMA3_SIG_OUT_BF_EN_N
   2 UNNAMED_12_74HCT2G125DPTSSOP8_I     1A @TIMECARD_LIB.TIMECARD(SCH_1):UNNAMED_12_74HCT2G125DPTSSOP8_I204_1A
   3 BF_ANT3_IN     2Y @TIMECARD_LIB.TIMECARD(SCH_1):BF_ANT3_IN
   4     SG    GND @TIMECARD_LIB.TIMECARD(SCH_1):SG
   5 BF_SMA3_SIG_IO_CONN     2A @TIMECARD_LIB.TIMECARD(SCH_1):BF_SMA3_SIG_IO_CONN
   6 BF_SMA3_SIG_IO_CONN     1Y @TIMECARD_LIB.TIMECARD(SCH_1):BF_SMA3_SIG_IO_CONN
   7 SMA3_SIG_IN_BF_EN_N   2OE* @TIMECARD_LIB.TIMECARD(SCH_1):SMA3_SIG_IN_BF_EN_N
   8 XP3R3V_FPGA    VCC @TIMECARD_LIB.TIMECARD(SCH_1):XP3R3V_FPGA

RESISTOR-G155-14701-01,4.7KOHMA  I206  R377
   2 SMA3_SIG_IN_BF_EN_N      2 @TIMECARD_LIB.TIMECARD(SCH_1):SMA3_SIG_IN_BF_EN_N
   1 XP3R3V_FPGA      1 @TIMECARD_LIB.TIMECARD(SCH_1):XP3R3V_FPGA

CAPACITOR-G105-0B104-CK,0.1UF,A  I207  C83
   1 XP3R3V_FPGA      1 @TIMECARD_LIB.TIMECARD(SCH_1):XP3R3V_FPGA
   2     SG      2 @TIMECARD_LIB.TIMECARD(SCH_1):SG

RESISTOR-G155-149R9-01,49.9OHMA  I209  R367
   2 ANT3_IN      2 @TIMECARD_LIB.TIMECARD(SCH_1):ANT3_IN
   1 BF_ANT3_IN      1 @TIMECARD_LIB.TIMECARD(SCH_1):BF_ANT3_IN

74HCT2G125DP_TSSOP8-G220-00055A  I226  U14
   1 SMA4_SIG_OUT_BF_EN_N   1OE* @TIMECARD_LIB.TIMECARD(SCH_1):SMA4_SIG_OUT_BF_EN_N
   2 UNNAMED_12_74HCT2G125DPTSSOP8_3     1A @TIMECARD_LIB.TIMECARD(SCH_1):UNNAMED_12_74HCT2G125DPTSSOP8_I226_1A
   3 BF_ANT4_IN     2Y @TIMECARD_LIB.TIMECARD(SCH_1):BF_ANT4_IN
   4     SG    GND @TIMECARD_LIB.TIMECARD(SCH_1):SG
   5 BF_SMA4_SIG_IO_CONN     2A @TIMECARD_LIB.TIMECARD(SCH_1):BF_SMA4_SIG_IO_CONN
   6 BF_SMA4_SIG_IO_CONN     1Y @TIMECARD_LIB.TIMECARD(SCH_1):BF_SMA4_SIG_IO_CONN
   7 SMA4_SIG_IN_BF_EN_N   2OE* @TIMECARD_LIB.TIMECARD(SCH_1):SMA4_SIG_IN_BF_EN_N
   8 XP3R3V_FPGA    VCC @TIMECARD_LIB.TIMECARD(SCH_1):XP3R3V_FPGA

RESISTOR-G155-149R9-01,49.9OHMA  I228  R123
   2 SMA4_SIG_IO_CONN      2 @TIMECARD_LIB.TIMECARD(SCH_1):SMA4_SIG_IO_CONN
   1 BF_SMA4_SIG_IO_CONN      1 @TIMECARD_LIB.TIMECARD(SCH_1):BF_SMA4_SIG_IO_CONN

RESISTOR-G155-149R9-01,49.9OHMA  I229  R370
   2 ANT4_IN      2 @TIMECARD_LIB.TIMECARD(SCH_1):ANT4_IN
   1 BF_ANT4_IN      1 @TIMECARD_LIB.TIMECARD(SCH_1):BF_ANT4_IN

CAPACITOR-G105-0B104-CK,0.1UF,A  I231  C82
   1 XP3R3V_FPGA      1 @TIMECARD_LIB.TIMECARD(SCH_1):XP3R3V_FPGA
   2     SG      2 @TIMECARD_LIB.TIMECARD(SCH_1):SG

RESISTOR-G155-14701-01,4.7KOHMA  I233  R368
   2 SMA4_SIG_OUT_BF_EN_N      2 @TIMECARD_LIB.TIMECARD(SCH_1):SMA4_SIG_OUT_BF_EN_N
   1 XP3R3V_FPGA      1 @TIMECARD_LIB.TIMECARD(SCH_1):XP3R3V_FPGA

RESISTOR-G155-14701-01,4.7KOHMA  I234  R379
   2 SMA4_SIG_IN_BF_EN_N      2 @TIMECARD_LIB.TIMECARD(SCH_1):SMA4_SIG_IN_BF_EN_N
   1 XP3R3V_FPGA      1 @TIMECARD_LIB.TIMECARD(SCH_1):XP3R3V_FPGA

RESISTOR-G155-11000-01,100OHM,A  I237  R157
   2 UNNAMED_12_74HCT2G125DPTSSOP8_3      2 @TIMECARD_LIB.TIMECARD(SCH_1):UNNAMED_12_74HCT2G125DPTSSOP8_I226_1A
   1 ANT4_OUT      1 @TIMECARD_LIB.TIMECARD(SCH_1):ANT4_OUT

74HCT2G125DP_TSSOP8-G220-00055A  I255  U15
   1 SMA1_SIG_OUT_BF_EN_N   1OE* @TIMECARD_LIB.TIMECARD(SCH_1):SMA1_SIG_OUT_BF_EN_N
   2 UNNAMED_12_74HCT2G125DPTSSOP8_6     1A @TIMECARD_LIB.TIMECARD(SCH_1):UNNAMED_12_74HCT2G125DPTSSOP8_I255_1A
   3 BF_ANT1_IN     2Y @TIMECARD_LIB.TIMECARD(SCH_1):BF_ANT1_IN
   4     SG    GND @TIMECARD_LIB.TIMECARD(SCH_1):SG
   5 BF_SMA1_SIG_IO_CONN     2A @TIMECARD_LIB.TIMECARD(SCH_1):BF_SMA1_SIG_IO_CONN
   6 BF_SMA1_SIG_IO_CONN     1Y @TIMECARD_LIB.TIMECARD(SCH_1):BF_SMA1_SIG_IO_CONN
   7 SMA1_SIG_IN_BF_EN_N   2OE* @TIMECARD_LIB.TIMECARD(SCH_1):SMA1_SIG_IN_BF_EN_N
   8 XP3R3V_FPGA    VCC @TIMECARD_LIB.TIMECARD(SCH_1):XP3R3V_FPGA

RESISTOR-G155-149R9-01,49.9OHMA  I257  R127
   2 SMA1_SIG_IO_CONN      2 @TIMECARD_LIB.TIMECARD(SCH_1):SMA1_SIG_IO_CONN
   1 BF_SMA1_SIG_IO_CONN      1 @TIMECARD_LIB.TIMECARD(SCH_1):BF_SMA1_SIG_IO_CONN

RESISTOR-G155-149R9-01,49.9OHMA  I258  R371
   2 ANT1_IN      2 @TIMECARD_LIB.TIMECARD(SCH_1):ANT1_IN
   1 BF_ANT1_IN      1 @TIMECARD_LIB.TIMECARD(SCH_1):BF_ANT1_IN

RESISTOR-G155-14701-01,4.7KOHMA  I261  R361
   2 SMA1_SIG_OUT_BF_EN_N      2 @TIMECARD_LIB.TIMECARD(SCH_1):SMA1_SIG_OUT_BF_EN_N
   1 XP3R3V_FPGA      1 @TIMECARD_LIB.TIMECARD(SCH_1):XP3R3V_FPGA

RESISTOR-G155-14701-01,4.7KOHMA  I262  R381
   2 SMA1_SIG_IN_BF_EN_N      2 @TIMECARD_LIB.TIMECARD(SCH_1):SMA1_SIG_IN_BF_EN_N
   1 XP3R3V_FPGA      1 @TIMECARD_LIB.TIMECARD(SCH_1):XP3R3V_FPGA

RESISTOR-G155-11000-01,100OHM,A  I265  R120
   2 UNNAMED_12_74HCT2G125DPTSSOP8_6      2 @TIMECARD_LIB.TIMECARD(SCH_1):UNNAMED_12_74HCT2G125DPTSSOP8_I255_1A
   1 ANT1_OUT      1 @TIMECARD_LIB.TIMECARD(SCH_1):ANT1_OUT

CAPACITOR-G105-0B104-CK,0.1UF,A  I272  C85
   1 XP3R3V_FPGA      1 @TIMECARD_LIB.TIMECARD(SCH_1):XP3R3V_FPGA
   2     SG      2 @TIMECARD_LIB.TIMECARD(SCH_1):SG

74HCT2G125DP_TSSOP8-G220-00055A  I273  U16
   1 SMA2_SIG_OUT_BF_EN_N   1OE* @TIMECARD_LIB.TIMECARD(SCH_1):SMA2_SIG_OUT_BF_EN_N
   2 UNNAMED_12_74HCT2G125DPTSSOP8_9     1A @TIMECARD_LIB.TIMECARD(SCH_1):UNNAMED_12_74HCT2G125DPTSSOP8_I273_1A
   3 BF_ANT2_IN     2Y @TIMECARD_LIB.TIMECARD(SCH_1):BF_ANT2_IN
   4     SG    GND @TIMECARD_LIB.TIMECARD(SCH_1):SG
   5 BF_SMA2_SIG_IO_CONN     2A @TIMECARD_LIB.TIMECARD(SCH_1):BF_SMA2_SIG_IO_CONN
   6 BF_SMA2_SIG_IO_CONN     1Y @TIMECARD_LIB.TIMECARD(SCH_1):BF_SMA2_SIG_IO_CONN
   7 SMA2_SIG_IN_BF_EN_N   2OE* @TIMECARD_LIB.TIMECARD(SCH_1):SMA2_SIG_IN_BF_EN_N
   8 XP3R3V_FPGA    VCC @TIMECARD_LIB.TIMECARD(SCH_1):XP3R3V_FPGA

RESISTOR-G155-149R9-01,49.9OHMA  I275  R372
   2 ANT2_IN      2 @TIMECARD_LIB.TIMECARD(SCH_1):ANT2_IN
   1 BF_ANT2_IN      1 @TIMECARD_LIB.TIMECARD(SCH_1):BF_ANT2_IN

RESISTOR-G155-149R9-01,49.9OHMA  I276  R126
   2 SMA2_SIG_IO_CONN      2 @TIMECARD_LIB.TIMECARD(SCH_1):SMA2_SIG_IO_CONN
   1 BF_SMA2_SIG_IO_CONN      1 @TIMECARD_LIB.TIMECARD(SCH_1):BF_SMA2_SIG_IO_CONN

RESISTOR-G155-14701-01,4.7KOHMA  I280  R331
   2 SMA2_SIG_OUT_BF_EN_N      2 @TIMECARD_LIB.TIMECARD(SCH_1):SMA2_SIG_OUT_BF_EN_N
   1 XP3R3V_FPGA      1 @TIMECARD_LIB.TIMECARD(SCH_1):XP3R3V_FPGA

RESISTOR-G155-14701-01,4.7KOHMA  I281  R383
   2 SMA2_SIG_IN_BF_EN_N      2 @TIMECARD_LIB.TIMECARD(SCH_1):SMA2_SIG_IN_BF_EN_N
   1 XP3R3V_FPGA      1 @TIMECARD_LIB.TIMECARD(SCH_1):XP3R3V_FPGA

RESISTOR-G155-11000-01,100OHM,A  I284  R121
   2 UNNAMED_12_74HCT2G125DPTSSOP8_9      2 @TIMECARD_LIB.TIMECARD(SCH_1):UNNAMED_12_74HCT2G125DPTSSOP8_I273_1A
   1 ANT2_OUT      1 @TIMECARD_LIB.TIMECARD(SCH_1):ANT2_OUT

CAPACITOR-G105-0B104-CK,0.1UF,A  I289  C84
   1 XP3R3V_FPGA      1 @TIMECARD_LIB.TIMECARD(SCH_1):XP3R3V_FPGA
   2     SG      2 @TIMECARD_LIB.TIMECARD(SCH_1):SG

CONN_JACK_1P_GH4_S_TH-G200-130A  I290  J1
   1 SMA3_SIG_IO_CONN      1 @TIMECARD_LIB.TIMECARD(SCH_1):SMA3_SIG_IO_CONN
 GH1     SG    GH1 @TIMECARD_LIB.TIMECARD(SCH_1):SG
 GH2     SG    GH2 @TIMECARD_LIB.TIMECARD(SCH_1):SG
 GH3     SG    GH3 @TIMECARD_LIB.TIMECARD(SCH_1):SG
 GH4     SG    GH4 @TIMECARD_LIB.TIMECARD(SCH_1):SG

CONN_JACK_1P_GH4_S_TH-G200-130A  I294  J2
   1 SMA4_SIG_IO_CONN      1 @TIMECARD_LIB.TIMECARD(SCH_1):SMA4_SIG_IO_CONN
 GH1     SG    GH1 @TIMECARD_LIB.TIMECARD(SCH_1):SG
 GH2     SG    GH2 @TIMECARD_LIB.TIMECARD(SCH_1):SG
 GH3     SG    GH3 @TIMECARD_LIB.TIMECARD(SCH_1):SG
 GH4     SG    GH4 @TIMECARD_LIB.TIMECARD(SCH_1):SG

CONN_JACK_1P_GH4_S_TH-G200-130A  I297  J3
   1 SMA1_SIG_IO_CONN      1 @TIMECARD_LIB.TIMECARD(SCH_1):SMA1_SIG_IO_CONN
 GH1     SG    GH1 @TIMECARD_LIB.TIMECARD(SCH_1):SG
 GH2     SG    GH2 @TIMECARD_LIB.TIMECARD(SCH_1):SG
 GH3     SG    GH3 @TIMECARD_LIB.TIMECARD(SCH_1):SG
 GH4     SG    GH4 @TIMECARD_LIB.TIMECARD(SCH_1):SG

CONN_JACK_1P_GH4_S_TH-G200-130A  I300  J4
   1 SMA2_SIG_IO_CONN      1 @TIMECARD_LIB.TIMECARD(SCH_1):SMA2_SIG_IO_CONN
 GH1     SG    GH1 @TIMECARD_LIB.TIMECARD(SCH_1):SG
 GH2     SG    GH2 @TIMECARD_LIB.TIMECARD(SCH_1):SG
 GH3     SG    GH3 @TIMECARD_LIB.TIMECARD(SCH_1):SG
 GH4     SG    GH4 @TIMECARD_LIB.TIMECARD(SCH_1):SG

CAPACITOR-G104-0A180-FJ,18PF,5%  I318  C310
   1     SG      1 @TIMECARD_LIB.TIMECARD(SCH_1):SG
   2 UNNAMED_12_CAPACITOR_I318_2      2 @TIMECARD_LIB.TIMECARD(SCH_1):UNNAMED_12_CAPACITOR_I318_2

RESISTOR-G155-100R0-J0,0OHM,-  I319  R492
   2 UNNAMED_12_74HCT2G125DPTSSOP8_I      2 @TIMECARD_LIB.TIMECARD(SCH_1):UNNAMED_12_74HCT2G125DPTSSOP8_I204_1A
   1 UNNAMED_12_CAPACITOR_I318_2      1 @TIMECARD_LIB.TIMECARD(SCH_1):UNNAMED_12_CAPACITOR_I318_2

RESISTOR-G155-11004-01,1MOHM,1%  I320  R496
   2 BF_SMA3_SIG_IO_CONN      2 @TIMECARD_LIB.TIMECARD(SCH_1):BF_SMA3_SIG_IO_CONN
   1     SG      1 @TIMECARD_LIB.TIMECARD(SCH_1):SG

RESISTOR-G155-11004-01,1MOHM,1%  I322  R497
   2 BF_SMA4_SIG_IO_CONN      2 @TIMECARD_LIB.TIMECARD(SCH_1):BF_SMA4_SIG_IO_CONN
   1     SG      1 @TIMECARD_LIB.TIMECARD(SCH_1):SG

RESISTOR-G155-100R0-J0,0OHM,-  I323  R493
   2 UNNAMED_12_74HCT2G125DPTSSOP8_3      2 @TIMECARD_LIB.TIMECARD(SCH_1):UNNAMED_12_74HCT2G125DPTSSOP8_I226_1A
   1 UNNAMED_12_CAPACITOR_I321_2      1 @TIMECARD_LIB.TIMECARD(SCH_1):UNNAMED_12_CAPACITOR_I321_2

RESISTOR-G155-100R0-J0,0OHM,-  I326  R494
   2 UNNAMED_12_74HCT2G125DPTSSOP8_6      2 @TIMECARD_LIB.TIMECARD(SCH_1):UNNAMED_12_74HCT2G125DPTSSOP8_I255_1A
   1 UNNAMED_12_CAPACITOR_I328_2      1 @TIMECARD_LIB.TIMECARD(SCH_1):UNNAMED_12_CAPACITOR_I328_2

RESISTOR-G155-11004-01,1MOHM,1%  I327  R498
   2 BF_SMA1_SIG_IO_CONN      2 @TIMECARD_LIB.TIMECARD(SCH_1):BF_SMA1_SIG_IO_CONN
   1     SG      1 @TIMECARD_LIB.TIMECARD(SCH_1):SG

CAPACITOR-G104-0A180-FJ,18PF,5%  I328  C317
   1     SG      1 @TIMECARD_LIB.TIMECARD(SCH_1):SG
   2 UNNAMED_12_CAPACITOR_I328_2      2 @TIMECARD_LIB.TIMECARD(SCH_1):UNNAMED_12_CAPACITOR_I328_2

CAPACITOR-G104-0A180-FJ,18PF,5%  I321  C311
   1     SG      1 @TIMECARD_LIB.TIMECARD(SCH_1):SG
   2 UNNAMED_12_CAPACITOR_I321_2      2 @TIMECARD_LIB.TIMECARD(SCH_1):UNNAMED_12_CAPACITOR_I321_2

RESISTOR-G155-100R0-J0,0OHM,-  I330  R495
   2 UNNAMED_12_74HCT2G125DPTSSOP8_9      2 @TIMECARD_LIB.TIMECARD(SCH_1):UNNAMED_12_74HCT2G125DPTSSOP8_I273_1A
   1 UNNAMED_12_CAPACITOR_I332_2      1 @TIMECARD_LIB.TIMECARD(SCH_1):UNNAMED_12_CAPACITOR_I332_2

RESISTOR-G155-11004-01,1MOHM,1%  I331  R499
   2 BF_SMA2_SIG_IO_CONN      2 @TIMECARD_LIB.TIMECARD(SCH_1):BF_SMA2_SIG_IO_CONN
   1     SG      1 @TIMECARD_LIB.TIMECARD(SCH_1):SG

CAPACITOR-G104-0A180-FJ,18PF,5%  I332  C318
   1     SG      1 @TIMECARD_LIB.TIMECARD(SCH_1):SG
   2 UNNAMED_12_CAPACITOR_I332_2      2 @TIMECARD_LIB.TIMECARD(SCH_1):UNNAMED_12_CAPACITOR_I332_2


DRAWING: @TIMECARD_LIB.TIMECARD(SCH_1):PAGE524 

CL1001485A-G122-00019-01  I3  U17
   1     NC      1     NC
   2     SG      2 @TIMECARD_LIB.TIMECARD(SCH_1):SG
   3     NC      3     NC
   4 FT_USB_DM      4 @TIMECARD_LIB.TIMECARD(SCH_1):FT_USB_DM
   5 XP5R0V_FT4232      5 @TIMECARD_LIB.TIMECARD(SCH_1):XP5R0V_FT4232
   6 FT_USB_DP      6 @TIMECARD_LIB.TIMECARD(SCH_1):FT_USB_DP

CAPACITOR-G104-0A180-FJ,18PF,5%  I7  C86
   1     SG      1 @TIMECARD_LIB.TIMECARD(SCH_1):SG
   2 UNNAMED_524_CAPACITOR_I7_2      2 @TIMECARD_LIB.TIMECARD(SCH_1):UNNAMED_524_CAPACITOR_I7_2

XTAL_4-G131-10038-02  I8  Y2
   1 UNNAMED_524_CAPACITOR_I7_2      1 @TIMECARD_LIB.TIMECARD(SCH_1):UNNAMED_524_CAPACITOR_I7_2
   2     SG      2 @TIMECARD_LIB.TIMECARD(SCH_1):SG
   3 UNNAMED_524_CAPACITOR_I10_2      3 @TIMECARD_LIB.TIMECARD(SCH_1):UNNAMED_524_CAPACITOR_I10_2
   4     SG      4 @TIMECARD_LIB.TIMECARD(SCH_1):SG

CAPACITOR-G104-0A180-FJ,18PF,5%  I10  C87
   1     SG      1 @TIMECARD_LIB.TIMECARD(SCH_1):SG
   2 UNNAMED_524_CAPACITOR_I10_2      2 @TIMECARD_LIB.TIMECARD(SCH_1):UNNAMED_524_CAPACITOR_I10_2

RESISTOR-G155-11002-01,10KOHM,A  I23  R130
   2     SG      2 @TIMECARD_LIB.TIMECARD(SCH_1):SG
   1 FT_USB_DETECT      1 @TIMECARD_LIB.TIMECARD(SCH_1):FT_USB_DETECT

RESISTOR-G155-100R0-J0,0OHM,-  I26  R129
   2 R_FT_USB_DP      2 @TIMECARD_LIB.TIMECARD(SCH_1):R_FT_USB_DP
   1 FT_USB_DP      1 @TIMECARD_LIB.TIMECARD(SCH_1):FT_USB_DP

RESISTOR-G155-14701-01,4.7KOHMA  I27  R18
   2 FT_USB_DETECT      2 @TIMECARD_LIB.TIMECARD(SCH_1):FT_USB_DETECT
   1 XP5R0V_FT4232      1 @TIMECARD_LIB.TIMECARD(SCH_1):XP5R0V_FT4232

RESISTOR-G155-100R0-J0,0OHM,-  I28  R128
   2 R_FT_USB_DM      2 @TIMECARD_LIB.TIMECARD(SCH_1):R_FT_USB_DM
   1 FT_USB_DM      1 @TIMECARD_LIB.TIMECARD(SCH_1):FT_USB_DM

FT4232HL_REEL_QFP64-G223-10282A  I64  U18
  16 R_FT4232_TCK ADBUS0 @TIMECARD_LIB.TIMECARD(SCH_1):R_FT4232_TCK
  17 R_FT4232_TDI ADBUS1 @TIMECARD_LIB.TIMECARD(SCH_1):R_FT4232_TDI
  18 R_FT4232_TDO ADBUS2 @TIMECARD_LIB.TIMECARD(SCH_1):R_FT4232_TDO
  19 R_FT4232_TMS ADBUS3 @TIMECARD_LIB.TIMECARD(SCH_1):R_FT4232_TMS
  21 FT4232_MUX1_SEL ADBUS4 @TIMECARD_LIB.TIMECARD(SCH_1):FT4232_MUX1_SEL
  22 FT4232_MUX2_SEL ADBUS5 @TIMECARD_LIB.TIMECARD(SCH_1):FT4232_MUX2_SEL
  23 FT4232_MUX3_SEL ADBUS6 @TIMECARD_LIB.TIMECARD(SCH_1):FT4232_MUX3_SEL
  24 UNNAMED_524_FT4232HLREELQFP64_I ADBUS7 @TIMECARD_LIB.TIMECARD(SCH_1):UNNAMED_524_FT4232HLREELQFP64_I64_ADBUS7
  26 R_FT4232_I2C_SCL BDBUS0 @TIMECARD_LIB.TIMECARD(SCH_1):R_FT4232_I2C_SCL
  27 R_FT4232_I2C_SDA_OUT BDBUS1 @TIMECARD_LIB.TIMECARD(SCH_1):R_FT4232_I2C_SDA_OUT
  28 R_FT4232_I2C_SDA_IN BDBUS2 @TIMECARD_LIB.TIMECARD(SCH_1):R_FT4232_I2C_SDA_IN
  29 UNNAMED_524_FT4232HLREELQFP64_1 BDBUS3 @TIMECARD_LIB.TIMECARD(SCH_1):UNNAMED_524_FT4232HLREELQFP64_I64_BDBUS3
  30 UNNAMED_524_FT4232HLREELQFP64_2 BDBUS4 @TIMECARD_LIB.TIMECARD(SCH_1):UNNAMED_524_FT4232HLREELQFP64_I64_BDBUS4
  32 UNNAMED_524_FT4232HLREELQFP64_3 BDBUS5 @TIMECARD_LIB.TIMECARD(SCH_1):UNNAMED_524_FT4232HLREELQFP64_I64_BDBUS5
  33 UNNAMED_524_FT4232HLREELQFP64_4 BDBUS6 @TIMECARD_LIB.TIMECARD(SCH_1):UNNAMED_524_FT4232HLREELQFP64_I64_BDBUS6
  34 UNNAMED_524_FT4232HLREELQFP64_5 BDBUS7 @TIMECARD_LIB.TIMECARD(SCH_1):UNNAMED_524_FT4232HLREELQFP64_I64_BDBUS7
  38 R_FT4232_CHC_TX CDBUS0 @TIMECARD_LIB.TIMECARD(SCH_1):R_FT4232_CHC_TX
  39 R_FT4232_CHC_RX CDBUS1 @TIMECARD_LIB.TIMECARD(SCH_1):R_FT4232_CHC_RX
  40     NC CDBUS2     NC
  41     NC CDBUS3     NC
  43     NC CDBUS4     NC
  44     NC CDBUS5     NC
  45     NC CDBUS6     NC
  46     NC CDBUS7     NC
  48 R_FT4232_CHD_TX DDBUS0 @TIMECARD_LIB.TIMECARD(SCH_1):R_FT4232_CHD_TX
  52 R_FT4232_CHD_RX DDBUS1 @TIMECARD_LIB.TIMECARD(SCH_1):R_FT4232_CHD_RX
  53     NC DDBUS2     NC
  54     NC DDBUS3     NC
  55     NC DDBUS4     NC
  57     NC DDBUS5     NC
  58     NC DDBUS6     NC
  59     NC DDBUS7     NC
  60     NC PWREN*     NC
  36     NC SUSPEND*     NC
  50 XP3R3V_FT4232 VREGIN @TIMECARD_LIB.TIMECARD(SCH_1):XP3R3V_FT4232
  49 FT4232_VREGOUT VREGOUT @TIMECARD_LIB.TIMECARD(SCH_1):FT4232_VREGOUT
  56 XP3R3V_FT4232 VCCIO_1 @TIMECARD_LIB.TIMECARD(SCH_1):XP3R3V_FT4232
  42 XP3R3V_FT4232 VCCIO_2 @TIMECARD_LIB.TIMECARD(SCH_1):XP3R3V_FT4232
  31 XP3R3V_FT4232 VCCIO_3 @TIMECARD_LIB.TIMECARD(SCH_1):XP3R3V_FT4232
  20 XP3R3V_FT4232 VCCIO_4 @TIMECARD_LIB.TIMECARD(SCH_1):XP3R3V_FT4232
  64 FT4232_VREGOUT VCORE_1 @TIMECARD_LIB.TIMECARD(SCH_1):FT4232_VREGOUT
  37 FT4232_VREGOUT VCORE_2 @TIMECARD_LIB.TIMECARD(SCH_1):FT4232_VREGOUT
  12 FT4232_VREGOUT VCORE_3 @TIMECARD_LIB.TIMECARD(SCH_1):FT4232_VREGOUT
   9 XP3R3V_VPLL   VPLL @TIMECARD_LIB.TIMECARD(SCH_1):XP3R3V_VPLL
   4 XP3R3V_VPHY   VPHY @TIMECARD_LIB.TIMECARD(SCH_1):XP3R3V_VPHY
  10     SG   AGND @TIMECARD_LIB.TIMECARD(SCH_1):SG
  51     SG  GND_1 @TIMECARD_LIB.TIMECARD(SCH_1):SG
  47     SG  GND_2 @TIMECARD_LIB.TIMECARD(SCH_1):SG
  35     SG  GND_3 @TIMECARD_LIB.TIMECARD(SCH_1):SG
  25     SG  GND_4 @TIMECARD_LIB.TIMECARD(SCH_1):SG
  15     SG  GND_5 @TIMECARD_LIB.TIMECARD(SCH_1):SG
  11     SG  GND_6 @TIMECARD_LIB.TIMECARD(SCH_1):SG
   5     SG  GND_7 @TIMECARD_LIB.TIMECARD(SCH_1):SG
   1     SG  GND_8 @TIMECARD_LIB.TIMECARD(SCH_1):SG
   7 R_FT_USB_DM     DM @TIMECARD_LIB.TIMECARD(SCH_1):R_FT_USB_DM
   8 R_FT_USB_DP     DP @TIMECARD_LIB.TIMECARD(SCH_1):R_FT_USB_DP
   6 UNNAMED_524_FT4232HLREELQFP64_6    REF @TIMECARD_LIB.TIMECARD(SCH_1):UNNAMED_524_FT4232HLREELQFP64_I64_REF
  14 UNNAMED_524_FT4232HLREELQFP64_7 RESET* @TIMECARD_LIB.TIMECARD(SCH_1):UNNAMED_524_FT4232HLREELQFP64_I64_RESET
  63 FTDI_EE_CS   EECS @TIMECARD_LIB.TIMECARD(SCH_1):FTDI_EE_CS
  62 FTDI_EE_CLK  EECLK @TIMECARD_LIB.TIMECARD(SCH_1):FTDI_EE_CLK
  61 FTDI_EE_DAT EEDATA @TIMECARD_LIB.TIMECARD(SCH_1):FTDI_EE_DAT
   2 UNNAMED_524_CAPACITOR_I7_2   OSCI @TIMECARD_LIB.TIMECARD(SCH_1):UNNAMED_524_CAPACITOR_I7_2
   3 UNNAMED_524_CAPACITOR_I10_2   OSCO @TIMECARD_LIB.TIMECARD(SCH_1):UNNAMED_524_CAPACITOR_I10_2
  13     SG   TEST @TIMECARD_LIB.TIMECARD(SCH_1):SG

RESISTOR-G155-01202-01,12KOHM,A  I106  R463
   2     SG      2 @TIMECARD_LIB.TIMECARD(SCH_1):SG
   1 UNNAMED_524_FT4232HLREELQFP64_6      1 @TIMECARD_LIB.TIMECARD(SCH_1):UNNAMED_524_FT4232HLREELQFP64_I64_REF

FERRITEBEAD-G191-10097-01,600OA  I118  L22
   1 XP3R3V_FT4232      1 @TIMECARD_LIB.TIMECARD(SCH_1):XP3R3V_FT4232
   2 XP3R3V_VPHY      2 @TIMECARD_LIB.TIMECARD(SCH_1):XP3R3V_VPHY

RESISTOR-G155-11001-01,1KOHM,1%  I121  R460
   2 UNNAMED_524_FT4232HLREELQFP64_7      2 @TIMECARD_LIB.TIMECARD(SCH_1):UNNAMED_524_FT4232HLREELQFP64_I64_RESET
   1 FT_USB_DETECT      1 @TIMECARD_LIB.TIMECARD(SCH_1):FT_USB_DETECT

CAPACITOR-G105-0F475-BM,4.7UF,A  I123  C90
   1 FT4232_VREGOUT      1 @TIMECARD_LIB.TIMECARD(SCH_1):FT4232_VREGOUT
   2     SG      2 @TIMECARD_LIB.TIMECARD(SCH_1):SG

FERRITEBEAD-G191-10097-01,600OA  I127  L4
   1 XP3R3V_FT4232      1 @TIMECARD_LIB.TIMECARD(SCH_1):XP3R3V_FT4232
   2 XP3R3V_VPLL      2 @TIMECARD_LIB.TIMECARD(SCH_1):XP3R3V_VPLL

CAPACITOR-G105-0F475-BM,4.7UF,A  I128  C91
   1 XP3R3V_FT4232      1 @TIMECARD_LIB.TIMECARD(SCH_1):XP3R3V_FT4232
   2     SG      2 @TIMECARD_LIB.TIMECARD(SCH_1):SG

RESISTOR-G155-133R0-01,33OHM,1%  I139  R470
   2 FT4232_TMS_SPICS_N      2 @TIMECARD_LIB.TIMECARD(SCH_1):FT4232_TMS_SPICS_N
   1 R_FT4232_TMS      1 @TIMECARD_LIB.TIMECARD(SCH_1):R_FT4232_TMS

RESISTOR-G155-133R0-01,33OHM,1%  I140  R468
   2 FT4232_TDI_MOSI      2 @TIMECARD_LIB.TIMECARD(SCH_1):FT4232_TDI_MOSI
   1 R_FT4232_TDI      1 @TIMECARD_LIB.TIMECARD(SCH_1):R_FT4232_TDI

RESISTOR-G155-133R0-01,33OHM,1%  I141  R467
   2 FT4232_TCK_SCLK      2 @TIMECARD_LIB.TIMECARD(SCH_1):FT4232_TCK_SCLK
   1 R_FT4232_TCK      1 @TIMECARD_LIB.TIMECARD(SCH_1):R_FT4232_TCK

RESISTOR-G155-133R0-01,33OHM,1%  I142  R469
   2 FT4232_TDO_MISO      2 @TIMECARD_LIB.TIMECARD(SCH_1):FT4232_TDO_MISO
   1 R_FT4232_TDO      1 @TIMECARD_LIB.TIMECARD(SCH_1):R_FT4232_TDO

RESISTOR-G155-11003-01,100KOHMA  I149  R480
   2 XP3R3V_FT4232      2 @TIMECARD_LIB.TIMECARD(SCH_1):XP3R3V_FT4232
   1 UART_FT4232_TX_FPGA_RX      1 @TIMECARD_LIB.TIMECARD(SCH_1):UART_FT4232_TX_FPGA_RX

RESISTOR-G155-11003-01,100KOHMA  I150  R481
   2 XP3R3V_FT4232      2 @TIMECARD_LIB.TIMECARD(SCH_1):XP3R3V_FT4232
   1 R_FT4232_CHC_RX      1 @TIMECARD_LIB.TIMECARD(SCH_1):R_FT4232_CHC_RX

RESISTOR-G155-11000-01,100OHM,A  I153  R353
   2 UART_FT4232_TX_FPGA_RX      2 @TIMECARD_LIB.TIMECARD(SCH_1):UART_FT4232_TX_FPGA_RX
   1 R_FT4232_CHC_TX      1 @TIMECARD_LIB.TIMECARD(SCH_1):R_FT4232_CHC_TX

RESISTOR-G155-11000-01,100OHM,A  I154  R352
   2 UART_FT4232_RX_FPGA_TX      2 @TIMECARD_LIB.TIMECARD(SCH_1):UART_FT4232_RX_FPGA_TX
   1 R_FT4232_CHC_RX      1 @TIMECARD_LIB.TIMECARD(SCH_1):R_FT4232_CHC_RX

RESISTOR-G155-100R0-J0,0OHM,-  I166  R472
   2 FT4232_I2C_SDA      2 @TIMECARD_LIB.TIMECARD(SCH_1):FT4232_I2C_SDA
   1 R_FT4232_I2C_SDA_OUT      1 @TIMECARD_LIB.TIMECARD(SCH_1):R_FT4232_I2C_SDA_OUT

RESISTOR-G155-100R0-J0,0OHM,-  I169  R471
   2 FT4232_I2C_SCL      2 @TIMECARD_LIB.TIMECARD(SCH_1):FT4232_I2C_SCL
   1 R_FT4232_I2C_SCL      1 @TIMECARD_LIB.TIMECARD(SCH_1):R_FT4232_I2C_SCL

RESISTOR-G155-100R0-J0,0OHM,-  I170  R473
   2 FT4232_I2C_SDA      2 @TIMECARD_LIB.TIMECARD(SCH_1):FT4232_I2C_SDA
   1 R_FT4232_I2C_SDA_IN      1 @TIMECARD_LIB.TIMECARD(SCH_1):R_FT4232_I2C_SDA_IN

G200_10283_01-G200-10283-01  I173  J10
   1 FT4232_CHD_TX      1 @TIMECARD_LIB.TIMECARD(SCH_1):FT4232_CHD_TX
   2 DBG_UART_MAC_RX      2 @TIMECARD_LIB.TIMECARD(SCH_1):DBG_UART_MAC_RX
   3 FT4232_CHD_TX      3 @TIMECARD_LIB.TIMECARD(SCH_1):FT4232_CHD_TX
   4 DBG_UART_GPS_RXD      4 @TIMECARD_LIB.TIMECARD(SCH_1):DBG_UART_GPS_RXD
   5 FT4232_CHD_RX      5 @TIMECARD_LIB.TIMECARD(SCH_1):FT4232_CHD_RX
   6 DBG_UART_MAC_TX      6 @TIMECARD_LIB.TIMECARD(SCH_1):DBG_UART_MAC_TX
   7 FT4232_CHD_RX      7 @TIMECARD_LIB.TIMECARD(SCH_1):FT4232_CHD_RX
   8 DBG_UART_GPS_TXD      8 @TIMECARD_LIB.TIMECARD(SCH_1):DBG_UART_GPS_TXD
   9     SG      9 @TIMECARD_LIB.TIMECARD(SCH_1):SG
  10 FPGA_CFG_INIT_N     10 @TIMECARD_LIB.TIMECARD(SCH_1):FPGA_CFG_INIT_N

RESISTOR-G155-11003-01,100KOHMA  I184  R349
   2 XP3R3V_FT4232      2 @TIMECARD_LIB.TIMECARD(SCH_1):XP3R3V_FT4232
   1 R_FT4232_CHD_RX      1 @TIMECARD_LIB.TIMECARD(SCH_1):R_FT4232_CHD_RX

RESISTOR-G155-11000-01,100OHM,A  I187  R131
   2 FT4232_CHD_TX      2 @TIMECARD_LIB.TIMECARD(SCH_1):FT4232_CHD_TX
   1 R_FT4232_CHD_TX      1 @TIMECARD_LIB.TIMECARD(SCH_1):R_FT4232_CHD_TX

RESISTOR-G155-11000-01,100OHM,A  I188  R132
   2 FT4232_CHD_RX      2 @TIMECARD_LIB.TIMECARD(SCH_1):FT4232_CHD_RX
   1 R_FT4232_CHD_RX      1 @TIMECARD_LIB.TIMECARD(SCH_1):R_FT4232_CHD_RX

RESISTOR-G155-11003-01,100KOHMA  I190  R478
   2 XP3R3V_FT4232      2 @TIMECARD_LIB.TIMECARD(SCH_1):XP3R3V_FT4232
   1 FT4232_I2C_SCL      1 @TIMECARD_LIB.TIMECARD(SCH_1):FT4232_I2C_SCL

RESISTOR-G155-11003-01,100KOHMA  I191  R479
   2 XP3R3V_FT4232      2 @TIMECARD_LIB.TIMECARD(SCH_1):XP3R3V_FT4232
   1 FT4232_I2C_SDA      1 @TIMECARD_LIB.TIMECARD(SCH_1):FT4232_I2C_SDA

RESISTOR-G155-11003-01,100KOHMA  I198  R466
   2 XP3R3V_FT4232      2 @TIMECARD_LIB.TIMECARD(SCH_1):XP3R3V_FT4232
   1 R_FT4232_TDO      1 @TIMECARD_LIB.TIMECARD(SCH_1):R_FT4232_TDO

CAT93C46VI_GT3_SOIC8-G221-1007A  I200  U31
   1 FTDI_EE_CS     CS @TIMECARD_LIB.TIMECARD(SCH_1):FTDI_EE_CS
   2 FTDI_EE_CLK     SK @TIMECARD_LIB.TIMECARD(SCH_1):FTDI_EE_CLK
   3 FTDI_EE_DAT     DI @TIMECARD_LIB.TIMECARD(SCH_1):FTDI_EE_DAT
   4 FTDI_EE_DO     DO @TIMECARD_LIB.TIMECARD(SCH_1):FTDI_EE_DO
   6 XP3R3V_FT4232    ORG @TIMECARD_LIB.TIMECARD(SCH_1):XP3R3V_FT4232
   7     NC     NC     NC

CAT93C46VI_GT3_SOIC8-G221-1007A  I201  U31
   8 XP3R3V_FT4232    VCC @TIMECARD_LIB.TIMECARD(SCH_1):XP3R3V_FT4232
   5     SG    GND @TIMECARD_LIB.TIMECARD(SCH_1):SG

RESISTOR-G155-11002-01,10KOHM,A  I206  R447
   2 FTDI_EE_CLK      2 @TIMECARD_LIB.TIMECARD(SCH_1):FTDI_EE_CLK
   1 XP3R3V_FT4232      1 @TIMECARD_LIB.TIMECARD(SCH_1):XP3R3V_FT4232

RESISTOR-G155-11002-01,10KOHM,A  I207  R446
   2 FTDI_EE_CS      2 @TIMECARD_LIB.TIMECARD(SCH_1):FTDI_EE_CS
   1 XP3R3V_FT4232      1 @TIMECARD_LIB.TIMECARD(SCH_1):XP3R3V_FT4232

RESISTOR-G155-11002-01,10KOHM,A  I208  R444
   2 FTDI_EE_DO      2 @TIMECARD_LIB.TIMECARD(SCH_1):FTDI_EE_DO
   1 XP3R3V_FT4232      1 @TIMECARD_LIB.TIMECARD(SCH_1):XP3R3V_FT4232

RESISTOR-G155-11004-01,1MOHM,1%  I287  R455
   2 UNNAMED_524_CAPACITOR_I10_2      2 @TIMECARD_LIB.TIMECARD(SCH_1):UNNAMED_524_CAPACITOR_I10_2
   1 UNNAMED_524_CAPACITOR_I7_2      1 @TIMECARD_LIB.TIMECARD(SCH_1):UNNAMED_524_CAPACITOR_I7_2

RESISTOR-G155-12201-01,2.2KOHMA  I310  R454
   2 FTDI_EE_DO      2 @TIMECARD_LIB.TIMECARD(SCH_1):FTDI_EE_DO
   1 FTDI_EE_DAT      1 @TIMECARD_LIB.TIMECARD(SCH_1):FTDI_EE_DAT

TP_PIONT-TP010CT020B030_PTH-TPA  I311  TP5
   1 UNNAMED_524_FT4232HLREELQFP64_I      1 @TIMECARD_LIB.TIMECARD(SCH_1):UNNAMED_524_FT4232HLREELQFP64_I64_ADBUS7

TP_PIONT-TP010CT020B030_PTH-TPA  I312  TP6
   1 UNNAMED_524_FT4232HLREELQFP64_1      1 @TIMECARD_LIB.TIMECARD(SCH_1):UNNAMED_524_FT4232HLREELQFP64_I64_BDBUS3

TP_PIONT-TP010CT020B030_PTH-TPA  I313  TP7
   1 UNNAMED_524_FT4232HLREELQFP64_2      1 @TIMECARD_LIB.TIMECARD(SCH_1):UNNAMED_524_FT4232HLREELQFP64_I64_BDBUS4

TP_PIONT-TP010CT020B030_PTH-TPA  I314  TP9
   1 UNNAMED_524_FT4232HLREELQFP64_4      1 @TIMECARD_LIB.TIMECARD(SCH_1):UNNAMED_524_FT4232HLREELQFP64_I64_BDBUS6

TP_PIONT-TP010CT020B030_PTH-TPA  I315  TP8
   1 UNNAMED_524_FT4232HLREELQFP64_3      1 @TIMECARD_LIB.TIMECARD(SCH_1):UNNAMED_524_FT4232HLREELQFP64_I64_BDBUS5

TP_PIONT-TP010CT020B030_PTH-TPA  I316  TP10
   1 UNNAMED_524_FT4232HLREELQFP64_5      1 @TIMECARD_LIB.TIMECARD(SCH_1):UNNAMED_524_FT4232HLREELQFP64_I64_BDBUS7

RESISTOR-G155-11000-01,100OHM,A  I368  R456
   2 FT_USB_DETECT      2 @TIMECARD_LIB.TIMECARD(SCH_1):FT_USB_DETECT
   1 XP3R3V_FT_PG      1 @TIMECARD_LIB.TIMECARD(SCH_1):XP3R3V_FT_PG

CAPACITOR-G105-0B104-EK,0.1UF,A  I373  C101
   1 XP3R3V_VPHY      1 @TIMECARD_LIB.TIMECARD(SCH_1):XP3R3V_VPHY
   2     SG      2 @TIMECARD_LIB.TIMECARD(SCH_1):SG

CAPACITOR-G105-0B104-EK,0.1UF,A  I374  C100
   1 XP3R3V_VPLL      1 @TIMECARD_LIB.TIMECARD(SCH_1):XP3R3V_VPLL
   2     SG      2 @TIMECARD_LIB.TIMECARD(SCH_1):SG

CAPACITOR-G105-0B104-EK,0.1UF,A  I375  C95
   1 XP3R3V_FT4232      1 @TIMECARD_LIB.TIMECARD(SCH_1):XP3R3V_FT4232
   2     SG      2 @TIMECARD_LIB.TIMECARD(SCH_1):SG

CAPACITOR-G105-0B104-EK,0.1UF,A  I376  C96
   1 FT4232_VREGOUT      1 @TIMECARD_LIB.TIMECARD(SCH_1):FT4232_VREGOUT
   2     SG      2 @TIMECARD_LIB.TIMECARD(SCH_1):SG

CAPACITOR-G105-0B104-EK,0.1UF,A  I377  C94
   1 XP5R0V_FT4232      1 @TIMECARD_LIB.TIMECARD(SCH_1):XP5R0V_FT4232
   2     SG      2 @TIMECARD_LIB.TIMECARD(SCH_1):SG

CAPACITOR-G105-0B104-EK,0.1UF,A  I378  C88
   1 XP3R3V_FT4232      1 @TIMECARD_LIB.TIMECARD(SCH_1):XP3R3V_FT4232
   2     SG      2 @TIMECARD_LIB.TIMECARD(SCH_1):SG

CAPACITOR-G105-0F475-BM,4.7UF,A  I379  C98
   1 XP3R3V_VPLL      1 @TIMECARD_LIB.TIMECARD(SCH_1):XP3R3V_VPLL
   2     SG      2 @TIMECARD_LIB.TIMECARD(SCH_1):SG

CAPACITOR-G105-0F475-BM,4.7UF,A  I380  C99
   1 XP3R3V_VPHY      1 @TIMECARD_LIB.TIMECARD(SCH_1):XP3R3V_VPHY
   2     SG      2 @TIMECARD_LIB.TIMECARD(SCH_1):SG

RESISTOR-G155-05101-01,5.1KOHMA  I395  R445
   2     SG      2 @TIMECARD_LIB.TIMECARD(SCH_1):SG
   1 UNNAMED_524_CONNUSB14PGH4FRAT_1      1 @TIMECARD_LIB.TIMECARD(SCH_1):UNNAMED_524_CONNUSB14PGH4FRATH_I495_CC2

TS3A5018PWR_TSSOP16-G220-10324A  I400  U38
   4 FLASH_CLK   COM1 @TIMECARD_LIB.TIMECARD(SCH_1):FLASH_CLK
   7 FLASH_DQ0_MOSI   COM2 @TIMECARD_LIB.TIMECARD(SCH_1):FLASH_DQ0_MOSI
   9 FLASH_DQ1_MISO   COM3 @TIMECARD_LIB.TIMECARD(SCH_1):FLASH_DQ1_MISO
  12 FLASH_CS_N   COM4 @TIMECARD_LIB.TIMECARD(SCH_1):FLASH_CS_N
  15 UNNAMED_524_RESISTOR_I432_2    EN* @TIMECARD_LIB.TIMECARD(SCH_1):UNNAMED_524_RESISTOR_I432_2
   1 MUX2_SEL     IN @TIMECARD_LIB.TIMECARD(SCH_1):MUX2_SEL
   2 FPGA_FLASH_CLK    NC1 @TIMECARD_LIB.TIMECARD(SCH_1):FPGA_FLASH_CLK
   5 FPGA_FLASH_DQ0_MOSI    NC2 @TIMECARD_LIB.TIMECARD(SCH_1):FPGA_FLASH_DQ0_MOSI
  11 FPGA_FLASH_DQ1_MISO    NC3 @TIMECARD_LIB.TIMECARD(SCH_1):FPGA_FLASH_DQ1_MISO
  14 FPGA_FLASH_CS_N    NC4 @TIMECARD_LIB.TIMECARD(SCH_1):FPGA_FLASH_CS_N
   3 FT4232_SPI_CLK    NO1 @TIMECARD_LIB.TIMECARD(SCH_1):FT4232_SPI_CLK
   6 FT4232_SPI_MOSI    NO2 @TIMECARD_LIB.TIMECARD(SCH_1):FT4232_SPI_MOSI
  10 FT4232_SPI_MISO    NO3 @TIMECARD_LIB.TIMECARD(SCH_1):FT4232_SPI_MISO
  13 FT4232_SPI_CS_N    NO4 @TIMECARD_LIB.TIMECARD(SCH_1):FT4232_SPI_CS_N

NLASB3157DFT2G_SC88-G223-10187A  I407  U39
   1     NC     B1     NC
   3 FLASH_DQ2     B0 @TIMECARD_LIB.TIMECARD(SCH_1):FLASH_DQ2
   4 FPGA_FLASH_DQ2      A @TIMECARD_LIB.TIMECARD(SCH_1):FPGA_FLASH_DQ2
   6 MUX2_SEL SELECT @TIMECARD_LIB.TIMECARD(SCH_1):MUX2_SEL

NLASB3157DFT2G_SC88-G223-10187A  I408  U40
   1     NC     B1     NC
   3 FLASH_DQ3     B0 @TIMECARD_LIB.TIMECARD(SCH_1):FLASH_DQ3
   4 FPGA_FLASH_DQ3      A @TIMECARD_LIB.TIMECARD(SCH_1):FPGA_FLASH_DQ3
   6 MUX2_SEL SELECT @TIMECARD_LIB.TIMECARD(SCH_1):MUX2_SEL

RESISTOR-G155-133R0-01,33OHM,1%  I411  R461
   2 MUX2_SEL      2 @TIMECARD_LIB.TIMECARD(SCH_1):MUX2_SEL
   1 FPGA_OUT_MUX2_SEL      1 @TIMECARD_LIB.TIMECARD(SCH_1):FPGA_OUT_MUX2_SEL

RESISTOR-G155-133R0-01,33OHM,1%  I412  R462
   2 MUX2_SEL      2 @TIMECARD_LIB.TIMECARD(SCH_1):MUX2_SEL
   1 FT4232_MUX2_SEL      1 @TIMECARD_LIB.TIMECARD(SCH_1):FT4232_MUX2_SEL

RESISTOR-G155-133R0-01,33OHM,1%  I423  R448
   2 FPGA_OUT_MUX1_SEL      2 @TIMECARD_LIB.TIMECARD(SCH_1):FPGA_OUT_MUX1_SEL
   1 MUX1_SEL      1 @TIMECARD_LIB.TIMECARD(SCH_1):MUX1_SEL

RESISTOR-G155-133R0-01,33OHM,1%  I424  R449
   2 FT4232_MUX1_SEL      2 @TIMECARD_LIB.TIMECARD(SCH_1):FT4232_MUX1_SEL
   1 MUX1_SEL      1 @TIMECARD_LIB.TIMECARD(SCH_1):MUX1_SEL

TS3A5018PWR_TSSOP16-G220-10324A  I425  U30
   4 FT4232_TCK_SCLK   COM1 @TIMECARD_LIB.TIMECARD(SCH_1):FT4232_TCK_SCLK
   7 FT4232_TDI_MOSI   COM2 @TIMECARD_LIB.TIMECARD(SCH_1):FT4232_TDI_MOSI
   9 FT4232_TDO_MISO   COM3 @TIMECARD_LIB.TIMECARD(SCH_1):FT4232_TDO_MISO
  12 FT4232_TMS_SPICS_N   COM4 @TIMECARD_LIB.TIMECARD(SCH_1):FT4232_TMS_SPICS_N
  15 UNNAMED_524_POWERMOS3PNCHV1_I44    EN* @TIMECARD_LIB.TIMECARD(SCH_1):UNNAMED_524_POWERMOS3PNCHV1_I445_D
   1 MUX1_SEL     IN @TIMECARD_LIB.TIMECARD(SCH_1):MUX1_SEL
   2 FT4232_FPGA_TCK    NC1 @TIMECARD_LIB.TIMECARD(SCH_1):FT4232_FPGA_TCK
   5 FT4232_FPGA_TDI    NC2 @TIMECARD_LIB.TIMECARD(SCH_1):FT4232_FPGA_TDI
  11 FT4232_FPGA_TDO    NC3 @TIMECARD_LIB.TIMECARD(SCH_1):FT4232_FPGA_TDO
  14 FT4232_FPGA_TMS    NC4 @TIMECARD_LIB.TIMECARD(SCH_1):FT4232_FPGA_TMS
   3 FT4232_SPI_CLK    NO1 @TIMECARD_LIB.TIMECARD(SCH_1):FT4232_SPI_CLK
   6 FT4232_SPI_MOSI    NO2 @TIMECARD_LIB.TIMECARD(SCH_1):FT4232_SPI_MOSI
  10 FT4232_SPI_MISO    NO3 @TIMECARD_LIB.TIMECARD(SCH_1):FT4232_SPI_MISO
  13 FT4232_SPI_CS_N    NO4 @TIMECARD_LIB.TIMECARD(SCH_1):FT4232_SPI_CS_N

RESISTOR-G155-11001-01,1KOHM,1%  I430  R458
   2 MUX2_SEL      2 @TIMECARD_LIB.TIMECARD(SCH_1):MUX2_SEL
   1     SG      1 @TIMECARD_LIB.TIMECARD(SCH_1):SG

RESISTOR-G155-14701-01,4.7KOHMA  I431  R457
   2 MUX2_SEL      2 @TIMECARD_LIB.TIMECARD(SCH_1):MUX2_SEL
   1 XP3R3V_FPGA      1 @TIMECARD_LIB.TIMECARD(SCH_1):XP3R3V_FPGA

RESISTOR-G155-11001-01,1KOHM,1%  I432  R459
   2 UNNAMED_524_RESISTOR_I432_2      2 @TIMECARD_LIB.TIMECARD(SCH_1):UNNAMED_524_RESISTOR_I432_2
   1     SG      1 @TIMECARD_LIB.TIMECARD(SCH_1):SG

RESISTOR-G155-14701-01,4.7KOHMA  I440  R450
   2 XP3R3V_FPGA      2 @TIMECARD_LIB.TIMECARD(SCH_1):XP3R3V_FPGA
   1 MUX1_SEL      1 @TIMECARD_LIB.TIMECARD(SCH_1):MUX1_SEL

RESISTOR-G155-11001-01,1KOHM,1%  I441  R451
   2     SG      2 @TIMECARD_LIB.TIMECARD(SCH_1):SG
   1 MUX1_SEL      1 @TIMECARD_LIB.TIMECARD(SCH_1):MUX1_SEL

RESISTOR-G155-11001-01,1KOHM,1%  I442  R453
   2     SG      2 @TIMECARD_LIB.TIMECARD(SCH_1):SG
   1 UNNAMED_524_POWERMOS3PNCHV1_I44      1 @TIMECARD_LIB.TIMECARD(SCH_1):UNNAMED_524_POWERMOS3PNCHV1_I445_D

RESISTOR-G155-14701-01,4.7KOHMA  I443  R452
   2 XP3R3V_FPGA      2 @TIMECARD_LIB.TIMECARD(SCH_1):XP3R3V_FPGA
   1 UNNAMED_524_POWERMOS3PNCHV1_I44      1 @TIMECARD_LIB.TIMECARD(SCH_1):UNNAMED_524_POWERMOS3PNCHV1_I445_D

POWERMOS_3P_NCH_V1-G121-10200-A  I445  Q1
   1 FT_USB_DETECT      G @TIMECARD_LIB.TIMECARD(SCH_1):FT_USB_DETECT
   2     SG      S @TIMECARD_LIB.TIMECARD(SCH_1):SG
   3 UNNAMED_524_POWERMOS3PNCHV1_I44      D @TIMECARD_LIB.TIMECARD(SCH_1):UNNAMED_524_POWERMOS3PNCHV1_I445_D

RESISTOR-G155-11000-01,100OHM,A  I446  R443
   2 FPGA_IO_FT_USBDET_RST_N      2 @TIMECARD_LIB.TIMECARD(SCH_1):FPGA_IO_FT_USBDET_RST_N
   1 FT_USB_DETECT      1 @TIMECARD_LIB.TIMECARD(SCH_1):FT_USB_DETECT

TS3A5018PWR_TSSOP16-G220-10324A  I448  U37
   4 PCA9546_I2C_SDA   COM1 @TIMECARD_LIB.TIMECARD(SCH_1):PCA9546_I2C_SDA
   7 PCA9546_I2C_SCL   COM2 @TIMECARD_LIB.TIMECARD(SCH_1):PCA9546_I2C_SCL
   9 EEPROM_I2C_SDA   COM3 @TIMECARD_LIB.TIMECARD(SCH_1):EEPROM_I2C_SDA
  12 EEPROM_I2C_SCL   COM4 @TIMECARD_LIB.TIMECARD(SCH_1):EEPROM_I2C_SCL
  15 UNNAMED_524_RESISTOR_I463_2    EN* @TIMECARD_LIB.TIMECARD(SCH_1):UNNAMED_524_RESISTOR_I463_2
   1 MUX3_SEL     IN @TIMECARD_LIB.TIMECARD(SCH_1):MUX3_SEL
   2 FPGA_PCA9546_I2C_SDA    NC1 @TIMECARD_LIB.TIMECARD(SCH_1):FPGA_PCA9546_I2C_SDA
   5 FPGA_PCA9546_I2C_SCL    NC2 @TIMECARD_LIB.TIMECARD(SCH_1):FPGA_PCA9546_I2C_SCL
  11 FPGA_EEPROM_I2C_SDA    NC3 @TIMECARD_LIB.TIMECARD(SCH_1):FPGA_EEPROM_I2C_SDA
  14 FPGA_EEPROM_I2C_SCL    NC4 @TIMECARD_LIB.TIMECARD(SCH_1):FPGA_EEPROM_I2C_SCL
   3 FT4232_I2C_SDA    NO1 @TIMECARD_LIB.TIMECARD(SCH_1):FT4232_I2C_SDA
   6 FT4232_I2C_SCL    NO2 @TIMECARD_LIB.TIMECARD(SCH_1):FT4232_I2C_SCL
  10 FT4232_I2C_SDA    NO3 @TIMECARD_LIB.TIMECARD(SCH_1):FT4232_I2C_SDA
  13 FT4232_I2C_SCL    NO4 @TIMECARD_LIB.TIMECARD(SCH_1):FT4232_I2C_SCL

RESISTOR-G155-133R0-01,33OHM,1%  I459  R485
   2 MUX3_SEL      2 @TIMECARD_LIB.TIMECARD(SCH_1):MUX3_SEL
   1 FPGA_OUT_MUX3_SEL      1 @TIMECARD_LIB.TIMECARD(SCH_1):FPGA_OUT_MUX3_SEL

RESISTOR-G155-133R0-01,33OHM,1%  I460  R486
   2 MUX3_SEL      2 @TIMECARD_LIB.TIMECARD(SCH_1):MUX3_SEL
   1 FT4232_MUX3_SEL      1 @TIMECARD_LIB.TIMECARD(SCH_1):FT4232_MUX3_SEL

RESISTOR-G155-11001-01,1KOHM,1%  I462  R483
   2 MUX3_SEL      2 @TIMECARD_LIB.TIMECARD(SCH_1):MUX3_SEL
   1     SG      1 @TIMECARD_LIB.TIMECARD(SCH_1):SG

RESISTOR-G155-11001-01,1KOHM,1%  I463  R484
   2 UNNAMED_524_RESISTOR_I463_2      2 @TIMECARD_LIB.TIMECARD(SCH_1):UNNAMED_524_RESISTOR_I463_2
   1     SG      1 @TIMECARD_LIB.TIMECARD(SCH_1):SG

RESISTOR-G155-14701-01,4.7KOHMA  I464  R482
   2 MUX3_SEL      2 @TIMECARD_LIB.TIMECARD(SCH_1):MUX3_SEL
   1 XP3R3V_FPGA      1 @TIMECARD_LIB.TIMECARD(SCH_1):XP3R3V_FPGA

RESISTOR-G155-11003-01,100KOHMA  I466  R474
   2 FPGA_PCA9546_I2C_SDA      2 @TIMECARD_LIB.TIMECARD(SCH_1):FPGA_PCA9546_I2C_SDA
   1 XP3R3V_FPGA      1 @TIMECARD_LIB.TIMECARD(SCH_1):XP3R3V_FPGA

RESISTOR-G155-11003-01,100KOHMA  I467  R475
   2 FPGA_PCA9546_I2C_SCL      2 @TIMECARD_LIB.TIMECARD(SCH_1):FPGA_PCA9546_I2C_SCL
   1 XP3R3V_FPGA      1 @TIMECARD_LIB.TIMECARD(SCH_1):XP3R3V_FPGA

RESISTOR-G155-11003-01,100KOHMA  I468  R476
   2 FPGA_EEPROM_I2C_SDA      2 @TIMECARD_LIB.TIMECARD(SCH_1):FPGA_EEPROM_I2C_SDA
   1 XP3R3V_FPGA      1 @TIMECARD_LIB.TIMECARD(SCH_1):XP3R3V_FPGA

RESISTOR-G155-11003-01,100KOHMA  I469  R477
   2 FPGA_EEPROM_I2C_SCL      2 @TIMECARD_LIB.TIMECARD(SCH_1):FPGA_EEPROM_I2C_SCL
   1 XP3R3V_FPGA      1 @TIMECARD_LIB.TIMECARD(SCH_1):XP3R3V_FPGA

TS3A5018PWR_TSSOP16-G220-10324A  I473  U30
   8     SG    GND @TIMECARD_LIB.TIMECARD(SCH_1):SG
  16 XP3R3V_FPGA    V_P @TIMECARD_LIB.TIMECARD(SCH_1):XP3R3V_FPGA

CAPACITOR-G105-0B104-EK,0.1UF,A  I474  C89
   1 XP3R3V_FPGA      1 @TIMECARD_LIB.TIMECARD(SCH_1):XP3R3V_FPGA
   2     SG      2 @TIMECARD_LIB.TIMECARD(SCH_1):SG

CAPACITOR-G105-0B104-EK,0.1UF,A  I476  C92
   1 XP3R3V_FPGA      1 @TIMECARD_LIB.TIMECARD(SCH_1):XP3R3V_FPGA
   2     SG      2 @TIMECARD_LIB.TIMECARD(SCH_1):SG

TS3A5018PWR_TSSOP16-G220-10324A  I478  U37
   8     SG    GND @TIMECARD_LIB.TIMECARD(SCH_1):SG
  16 XP3R3V_FPGA    V_P @TIMECARD_LIB.TIMECARD(SCH_1):XP3R3V_FPGA

TS3A5018PWR_TSSOP16-G220-10324A  I481  U38
   8     SG    GND @TIMECARD_LIB.TIMECARD(SCH_1):SG
  16 XP3R3V_FPGA    V_P @TIMECARD_LIB.TIMECARD(SCH_1):XP3R3V_FPGA

CAPACITOR-G105-0B104-EK,0.1UF,A  I482  C97
   1 XP3R3V_FPGA      1 @TIMECARD_LIB.TIMECARD(SCH_1):XP3R3V_FPGA
   2     SG      2 @TIMECARD_LIB.TIMECARD(SCH_1):SG

NLASB3157DFT2G_SC88-G223-10187A  I485  U39
   2     SG    GND @TIMECARD_LIB.TIMECARD(SCH_1):SG
   5 XP3R3V_FPGA    VCC @TIMECARD_LIB.TIMECARD(SCH_1):XP3R3V_FPGA

CAPACITOR-G105-0B104-EK,0.1UF,A  I486  C123
   1 XP3R3V_FPGA      1 @TIMECARD_LIB.TIMECARD(SCH_1):XP3R3V_FPGA
   2     SG      2 @TIMECARD_LIB.TIMECARD(SCH_1):SG

CAPACITOR-G105-0B104-EK,0.1UF,A  I490  C102
   1 XP3R3V_FPGA      1 @TIMECARD_LIB.TIMECARD(SCH_1):XP3R3V_FPGA
   2     SG      2 @TIMECARD_LIB.TIMECARD(SCH_1):SG

NLASB3157DFT2G_SC88-G223-10187A  I491  U40
   2     SG    GND @TIMECARD_LIB.TIMECARD(SCH_1):SG
   5 XP3R3V_FPGA    VCC @TIMECARD_LIB.TIMECARD(SCH_1):XP3R3V_FPGA

RESISTOR-G155-100R0-J0,0OHM,-  I493  R464
   2 FLASH_DQ2      2 @TIMECARD_LIB.TIMECARD(SCH_1):FLASH_DQ2
   1 FPGA_FLASH_DQ2      1 @TIMECARD_LIB.TIMECARD(SCH_1):FPGA_FLASH_DQ2

RESISTOR-G155-100R0-J0,0OHM,-  I494  R465
   2 FLASH_DQ3      2 @TIMECARD_LIB.TIMECARD(SCH_1):FLASH_DQ3
   1 FPGA_FLASH_DQ3      1 @TIMECARD_LIB.TIMECARD(SCH_1):FPGA_FLASH_DQ3

CONN_USB_14P_GH4_F_RA_TH-G200-A  I495  J13
  A1     SG  GND_1 @TIMECARD_LIB.TIMECARD(SCH_1):SG
  A4 XP5R0V_FT4232 VBUS_1 @TIMECARD_LIB.TIMECARD(SCH_1):XP5R0V_FT4232
  A5 UNNAMED_524_CONNUSB14PGH4FRATH_    CC1 @TIMECARD_LIB.TIMECARD(SCH_1):UNNAMED_524_CONNUSB14PGH4FRATH_I495_CC1
  A6 FT_USB_DP   D1_P @TIMECARD_LIB.TIMECARD(SCH_1):FT_USB_DP
  A7 FT_USB_DM   D1_N @TIMECARD_LIB.TIMECARD(SCH_1):FT_USB_DM
  A9 XP5R0V_FT4232 VBUS_2 @TIMECARD_LIB.TIMECARD(SCH_1):XP5R0V_FT4232
 A12     SG  GND_2 @TIMECARD_LIB.TIMECARD(SCH_1):SG
  B1     SG  GND_3 @TIMECARD_LIB.TIMECARD(SCH_1):SG
  B4 XP5R0V_FT4232 VBUS_3 @TIMECARD_LIB.TIMECARD(SCH_1):XP5R0V_FT4232
  B5 UNNAMED_524_CONNUSB14PGH4FRAT_1    CC2 @TIMECARD_LIB.TIMECARD(SCH_1):UNNAMED_524_CONNUSB14PGH4FRATH_I495_CC2
  B6 FT_USB_DP   D2_P @TIMECARD_LIB.TIMECARD(SCH_1):FT_USB_DP
  B7 FT_USB_DM   D2_N @TIMECARD_LIB.TIMECARD(SCH_1):FT_USB_DM
  B9 XP5R0V_FT4232 VBUS_4 @TIMECARD_LIB.TIMECARD(SCH_1):XP5R0V_FT4232
 B12     SG  GND_4 @TIMECARD_LIB.TIMECARD(SCH_1):SG
 GH1     SG    GH1 @TIMECARD_LIB.TIMECARD(SCH_1):SG
 GH2     SG    GH2 @TIMECARD_LIB.TIMECARD(SCH_1):SG
 GH3     SG    GH3 @TIMECARD_LIB.TIMECARD(SCH_1):SG
 GH4     SG    GH4 @TIMECARD_LIB.TIMECARD(SCH_1):SG

RESISTOR-G155-05101-01,5.1KOHMA  I497  R442
   2     SG      2 @TIMECARD_LIB.TIMECARD(SCH_1):SG
   1 UNNAMED_524_CONNUSB14PGH4FRATH_      1 @TIMECARD_LIB.TIMECARD(SCH_1):UNNAMED_524_CONNUSB14PGH4FRATH_I495_CC1


DRAWING: @TIMECARD_LIB.TIMECARD(SCH_1):PAGE525 

CAPACITOR-G107-0F226-CM,22UF,2A  I7  C284
   1 UNNAMED_525_CAPACITOR_I7_1      1 @TIMECARD_LIB.TIMECARD(SCH_1):UNNAMED_525_CAPACITOR_I7_1
   2     SG      2 @TIMECARD_LIB.TIMECARD(SCH_1):SG

CAPACITOR-G105-0B104-EK,0.1UF,A  I8  C298
   1 UNNAMED_525_CAPACITOR_I7_1      1 @TIMECARD_LIB.TIMECARD(SCH_1):UNNAMED_525_CAPACITOR_I7_1
   2     SG      2 @TIMECARD_LIB.TIMECARD(SCH_1):SG

FERRITEBEAD-G191-10101-01,26OHA  I10  L23
   1 UNNAMED_525_CAPACITOR_I7_1      1 @TIMECARD_LIB.TIMECARD(SCH_1):UNNAMED_525_CAPACITOR_I7_1
   2 UNNAMED_525_CAPACITOR_I16_1      2 @TIMECARD_LIB.TIMECARD(SCH_1):UNNAMED_525_CAPACITOR_I16_1

RESISTOR-G155-11002-01,10KOHM,A  I13  R488
   2     SG      2 @TIMECARD_LIB.TIMECARD(SCH_1):SG
   1 UNNAMED_525_CAPACITOR_I14_1      1 @TIMECARD_LIB.TIMECARD(SCH_1):UNNAMED_525_CAPACITOR_I14_1

CAPACITOR-G105-0B104-EK,0.1UF,A  I14  C302
   1 UNNAMED_525_CAPACITOR_I14_1      1 @TIMECARD_LIB.TIMECARD(SCH_1):UNNAMED_525_CAPACITOR_I14_1
   2     SG      2 @TIMECARD_LIB.TIMECARD(SCH_1):SG

CAPACITOR-G107-0F106-EM,10UF,2A  I16  C300
   1 UNNAMED_525_CAPACITOR_I16_1      1 @TIMECARD_LIB.TIMECARD(SCH_1):UNNAMED_525_CAPACITOR_I16_1
   2     SG      2 @TIMECARD_LIB.TIMECARD(SCH_1):SG

CAPACITOR-G104-0B103-EK,0.01UFA  I18  C307
   1 UNNAMED_525_CAPACITOR_I18_1      1 @TIMECARD_LIB.TIMECARD(SCH_1):UNNAMED_525_CAPACITOR_I18_1
   2     SG      2 @TIMECARD_LIB.TIMECARD(SCH_1):SG

CAPACITOR-G105-0B104-EK,0.1UF,A  I20  C304
   1 UNNAMED_525_CAPACITOR_I16_1      1 @TIMECARD_LIB.TIMECARD(SCH_1):UNNAMED_525_CAPACITOR_I16_1
   2     SG      2 @TIMECARD_LIB.TIMECARD(SCH_1):SG

ISL80101IRAJZ_DFN10-G222-10136A  I29  U41
   1 XP3R3V_FT4232 VOUT_1 @TIMECARD_LIB.TIMECARD(SCH_1):XP3R3V_FT4232
   2 XP3R3V_FT4232 VOUT_2 @TIMECARD_LIB.TIMECARD(SCH_1):XP3R3V_FT4232
   3 UNNAMED_525_ISL80101IRAJZDFN10_ SENSE/ADJ @TIMECARD_LIB.TIMECARD(SCH_1):UNNAMED_525_ISL80101IRAJZDFN10_I29_SENSE
   4 XP3R3V_FT_PG     PG @TIMECARD_LIB.TIMECARD(SCH_1):XP3R3V_FT_PG
   5     SG    GND @TIMECARD_LIB.TIMECARD(SCH_1):SG
   6 UNNAMED_525_CAPACITOR_I18_1     SS @TIMECARD_LIB.TIMECARD(SCH_1):UNNAMED_525_CAPACITOR_I18_1
   7 UNNAMED_525_CAPACITOR_I14_1 ENABLE @TIMECARD_LIB.TIMECARD(SCH_1):UNNAMED_525_CAPACITOR_I14_1
   8     NC     NC     NC
   9 UNNAMED_525_CAPACITOR_I16_1  VIN_1 @TIMECARD_LIB.TIMECARD(SCH_1):UNNAMED_525_CAPACITOR_I16_1
  10 UNNAMED_525_CAPACITOR_I16_1  VIN_2 @TIMECARD_LIB.TIMECARD(SCH_1):UNNAMED_525_CAPACITOR_I16_1
  11     SG THRM_PAD @TIMECARD_LIB.TIMECARD(SCH_1):SG

CAPACITOR-G105-0B104-EK,0.1UF,A  I56  C309
   1 XP3R3V_FT4232      1 @TIMECARD_LIB.TIMECARD(SCH_1):XP3R3V_FT4232
   2     SG      2 @TIMECARD_LIB.TIMECARD(SCH_1):SG

CAPACITOR-G107-0F106-EM,10UF,2A  I64  C308
   1 XP3R3V_FT4232      1 @TIMECARD_LIB.TIMECARD(SCH_1):XP3R3V_FT4232
   2     SG      2 @TIMECARD_LIB.TIMECARD(SCH_1):SG

RESISTOR-G155-14701-01,4.7KOHMA  I65  R487
   2 UNNAMED_525_CAPACITOR_I14_1      2 @TIMECARD_LIB.TIMECARD(SCH_1):UNNAMED_525_CAPACITOR_I14_1
   1 UNNAMED_525_CAPACITOR_I16_1      1 @TIMECARD_LIB.TIMECARD(SCH_1):UNNAMED_525_CAPACITOR_I16_1

RESISTOR-G155-11002-01,10KOHM,A  I66  R490
   2 UNNAMED_525_ISL80101IRAJZDFN10_      2 @TIMECARD_LIB.TIMECARD(SCH_1):UNNAMED_525_ISL80101IRAJZDFN10_I29_SENSE
   1 XP3R3V_FT4232      1 @TIMECARD_LIB.TIMECARD(SCH_1):XP3R3V_FT4232

RESISTOR-G155-03241-01,3.24KOHA  I67  R491
   2     SG      2 @TIMECARD_LIB.TIMECARD(SCH_1):SG
   1 UNNAMED_525_ISL80101IRAJZDFN10_      1 @TIMECARD_LIB.TIMECARD(SCH_1):UNNAMED_525_ISL80101IRAJZDFN10_I29_SENSE

RESISTOR-G155-03921-01,3.92KOHA  I68  R489
   2     SG      2 @TIMECARD_LIB.TIMECARD(SCH_1):SG
   1 UNNAMED_525_ISL80101IRAJZDFN10_      1 @TIMECARD_LIB.TIMECARD(SCH_1):UNNAMED_525_ISL80101IRAJZDFN10_I29_SENSE

DIODE_2F-G122-10186-01  I102  CR1
   C UNNAMED_525_CAPACITOR_I7_1      C @TIMECARD_LIB.TIMECARD(SCH_1):UNNAMED_525_CAPACITOR_I7_1
   A XP5R0V      A @TIMECARD_LIB.TIMECARD(SCH_1):XP5R0V

DIODE_2F-G122-10186-01  I104  CR2
   C UNNAMED_525_CAPACITOR_I7_1      C @TIMECARD_LIB.TIMECARD(SCH_1):UNNAMED_525_CAPACITOR_I7_1
   A XP5R0V_FT4232      A @TIMECARD_LIB.TIMECARD(SCH_1):XP5R0V_FT4232

FERRITEBEAD-G191-10100-01,120OA  I108  L24
   1 XP3R3V_FPGA      1 @TIMECARD_LIB.TIMECARD(SCH_1):XP3R3V_FPGA
   2 XP3R3V_FT4232      2 @TIMECARD_LIB.TIMECARD(SCH_1):XP3R3V_FT4232


DRAWING: @TIMECARD_LIB.TIMECARD(SCH_1):PAGE527 

CONN_USB_1X5_G2_GH4_F_RA_SMT-GA  I2  J11
   1 XP5R0V_USB_CONN      1 @TIMECARD_LIB.TIMECARD(SCH_1):XP5R0V_USB_CONN
   2 CONN_MICRO_USB_DM      2 @TIMECARD_LIB.TIMECARD(SCH_1):CONN_MICRO_USB_DM
   3 CONN_MICRO_USB_DP      3 @TIMECARD_LIB.TIMECARD(SCH_1):CONN_MICRO_USB_DP
   4     NC      4     NC
   5     SG      5 @TIMECARD_LIB.TIMECARD(SCH_1):SG
  G1     SG     G1 @TIMECARD_LIB.TIMECARD(SCH_1):SG
  G2     SG     G2 @TIMECARD_LIB.TIMECARD(SCH_1):SG
 GH1     SG    GH1 @TIMECARD_LIB.TIMECARD(SCH_1):SG
 GH2     SG    GH2 @TIMECARD_LIB.TIMECARD(SCH_1):SG
 GH3     SG    GH3 @TIMECARD_LIB.TIMECARD(SCH_1):SG
 GH4     SG    GH4 @TIMECARD_LIB.TIMECARD(SCH_1):SG

CL1001485A-G122-00019-01  I4  U9
   1     NC      1     NC
   2     SG      2 @TIMECARD_LIB.TIMECARD(SCH_1):SG
   3     NC      3     NC
   4 CONN_MICRO_USB_DM      4 @TIMECARD_LIB.TIMECARD(SCH_1):CONN_MICRO_USB_DM
   5 XP5R0V_USB_CONN      5 @TIMECARD_LIB.TIMECARD(SCH_1):XP5R0V_USB_CONN
   6 CONN_MICRO_USB_DP      6 @TIMECARD_LIB.TIMECARD(SCH_1):CONN_MICRO_USB_DP

RESISTOR-G155-100R0-J0,0OHM,-  I13  R88
   2 R_MAC_PPS_OUTN      2 @TIMECARD_LIB.TIMECARD(SCH_1):R_MAC_PPS_OUTN
   1 FPGA_IN_MAC_PPS_OUTN      1 @TIMECARD_LIB.TIMECARD(SCH_1):FPGA_IN_MAC_PPS_OUTN

RESISTOR-G155-100R0-J0,0OHM,-  I14  R87
   2 R_MAC_PPS_OUTP      2 @TIMECARD_LIB.TIMECARD(SCH_1):R_MAC_PPS_OUTP
   1 FPGA_IN_MAC_PPS_OUTP      1 @TIMECARD_LIB.TIMECARD(SCH_1):FPGA_IN_MAC_PPS_OUTP

CAPACITOR-G105-0B104-EK,0.1UF,A  I15  C63
   1 XP5R0V_USB_CONN      1 @TIMECARD_LIB.TIMECARD(SCH_1):XP5R0V_USB_CONN
   2     SG      2 @TIMECARD_LIB.TIMECARD(SCH_1):SG

CAPACITOR-G107-0F106-EM,10UF,2A  I16  C61
   1 XP5R0V_USB_CONN      1 @TIMECARD_LIB.TIMECARD(SCH_1):XP5R0V_USB_CONN
   2     SG      2 @TIMECARD_LIB.TIMECARD(SCH_1):SG

RESISTOR-G155-133R0-01,33OHM,1%  I23  R96
   2 FPGA_IN_MAC_ALARM_OUT_N      2 @TIMECARD_LIB.TIMECARD(SCH_1):FPGA_IN_MAC_ALARM_OUT_N
   1 MAC_ALARM      1 @TIMECARD_LIB.TIMECARD(SCH_1):MAC_ALARM

RESISTOR-G155-100R0-J0,0OHM,-  I29  R86
   2 R_MAC_PPS_IN0N      2 @TIMECARD_LIB.TIMECARD(SCH_1):R_MAC_PPS_IN0N
   1 FPGA_OUT_MAC_PPS_IN0N      1 @TIMECARD_LIB.TIMECARD(SCH_1):FPGA_OUT_MAC_PPS_IN0N

RESISTOR-G155-100R0-J0,0OHM,-  I30  R85
   2 R_MAC_PPS_IN0P      2 @TIMECARD_LIB.TIMECARD(SCH_1):R_MAC_PPS_IN0P
   1 FPGA_OUT_MAC_PPS_IN0P      1 @TIMECARD_LIB.TIMECARD(SCH_1):FPGA_OUT_MAC_PPS_IN0P

RESISTOR-G155-100R0-J0,0OHM,-  I31  R84
   2 R_MAC_PPS_IN1N      2 @TIMECARD_LIB.TIMECARD(SCH_1):R_MAC_PPS_IN1N
   1 FPGA_OUT_MAC_PPS_IN1N      1 @TIMECARD_LIB.TIMECARD(SCH_1):FPGA_OUT_MAC_PPS_IN1N

RESISTOR-G155-100R0-J0,0OHM,-  I32  R83
   2 R_MAC_PPS_IN1P      2 @TIMECARD_LIB.TIMECARD(SCH_1):R_MAC_PPS_IN1P
   1 FPGA_OUT_MAC_PPS_IN1P      1 @TIMECARD_LIB.TIMECARD(SCH_1):FPGA_OUT_MAC_PPS_IN1P

RESISTOR-G155-11000-01,100OHM,A  I33  R90
   2 R_MAC_PPS_IN0P      2 @TIMECARD_LIB.TIMECARD(SCH_1):R_MAC_PPS_IN0P
   1 R_MAC_PPS_IN0N      1 @TIMECARD_LIB.TIMECARD(SCH_1):R_MAC_PPS_IN0N

RESISTOR-G155-11000-01,100OHM,A  I34  R89
   2 R_MAC_PPS_IN1N      2 @TIMECARD_LIB.TIMECARD(SCH_1):R_MAC_PPS_IN1N
   1 R_MAC_PPS_IN1P      1 @TIMECARD_LIB.TIMECARD(SCH_1):R_MAC_PPS_IN1P

CAPACITOR-G107-0F106-EM,10UF,2A  I47  C58
   1 XP5R0V_MAC      1 @TIMECARD_LIB.TIMECARD(SCH_1):XP5R0V_MAC
   2     SG      2 @TIMECARD_LIB.TIMECARD(SCH_1):SG

CAPACITOR-G105-0B104-EK,0.1UF,A  I48  C59
   1 XP5R0V_MAC      1 @TIMECARD_LIB.TIMECARD(SCH_1):XP5R0V_MAC
   2     SG      2 @TIMECARD_LIB.TIMECARD(SCH_1):SG

CAPACITOR-G107-0F106-EM,10UF,2A  I51  C64
   1 XP5R0V_MAC_USB      1 @TIMECARD_LIB.TIMECARD(SCH_1):XP5R0V_MAC_USB
   2     SG      2 @TIMECARD_LIB.TIMECARD(SCH_1):SG

RESISTOR-G155-133R0-01,33OHM,1%  I52  R95
   2 UART_MAC_RX_FPGA_TX      2 @TIMECARD_LIB.TIMECARD(SCH_1):UART_MAC_RX_FPGA_TX
   1 R_MAC_UART_RX_FPGA_TX      1 @TIMECARD_LIB.TIMECARD(SCH_1):R_MAC_UART_RX_FPGA_TX

RESISTOR-G155-133R0-01,33OHM,1%  I53  R93
   2 FPGA_IN_MAC_BITEOUT      2 @TIMECARD_LIB.TIMECARD(SCH_1):FPGA_IN_MAC_BITE OUT
   1 R_MAC_BITEOUT      1 @TIMECARD_LIB.TIMECARD(SCH_1):R_MAC_BITE OUT

RESISTOR-G155-133R0-01,33OHM,1%  I54  R94
   2 UART_MAC_TX_FPGA_RX      2 @TIMECARD_LIB.TIMECARD(SCH_1):UART_MAC_TX_FPGA_RX
   1 R_MAC_UART_TX_FPGA_RX      1 @TIMECARD_LIB.TIMECARD(SCH_1):R_MAC_UART_TX_FPGA_RX

RESISTOR-G155-11000-01,100OHM,A  I55  R92
   2 FPGA_IN_MAC_10MHZ_OUT      2 @TIMECARD_LIB.TIMECARD(SCH_1):FPGA_IN_MAC_10MHZ_OUT
   1 R_MAC_10MHZ_RF_OUT      1 @TIMECARD_LIB.TIMECARD(SCH_1):R_MAC_10MHZ_RF_OUT

CAPACITOR-G105-0B104-EK,0.1UF,A  I56  C65
   1 XP5R0V_MAC_USB      1 @TIMECARD_LIB.TIMECARD(SCH_1):XP5R0V_MAC_USB
   2     SG      2 @TIMECARD_LIB.TIMECARD(SCH_1):SG

CAPACITOR-G105-0B104-EK,0.1UF,A  I57  C66
   1 XP5R0V_MAC_USB      1 @TIMECARD_LIB.TIMECARD(SCH_1):XP5R0V_MAC_USB
   2     SG      2 @TIMECARD_LIB.TIMECARD(SCH_1):SG

CAPACITOR-G105-0B104-EK,0.1UF,A  I66  C60
   1 XP5R0V_MAC      1 @TIMECARD_LIB.TIMECARD(SCH_1):XP5R0V_MAC
   2     SG      2 @TIMECARD_LIB.TIMECARD(SCH_1):SG

CAPACITOR-G105-0B104-EK,0.1UF,A  I74  C69
   1 USB_PWR_EN      1 @TIMECARD_LIB.TIMECARD(SCH_1):USB_PWR_EN
   2     SG      2 @TIMECARD_LIB.TIMECARD(SCH_1):SG

CAPACITOR-G105-0B104-EK,0.1UF,A  I77  C70
   1 XP5R0V_MAC      1 @TIMECARD_LIB.TIMECARD(SCH_1):XP5R0V_MAC
   2     SG      2 @TIMECARD_LIB.TIMECARD(SCH_1):SG

TPS2051BDBVT_SOT23_5-G220-1033A  I78  U12
   2     SG    GND @TIMECARD_LIB.TIMECARD(SCH_1):SG

TPS2051BDBVT_SOT23_5-G220-1033A  I79  U12
   1 XP5R0V_MAC_USB    OUT @TIMECARD_LIB.TIMECARD(SCH_1):XP5R0V_MAC_USB
   3 UNNAMED_527_RESISTOR_I206_1    OC* @TIMECARD_LIB.TIMECARD(SCH_1):UNNAMED_527_RESISTOR_I206_1
   5 XP5R0V_MAC     IN @TIMECARD_LIB.TIMECARD(SCH_1):XP5R0V_MAC
   4 USB_PWR_EN     EN @TIMECARD_LIB.TIMECARD(SCH_1):USB_PWR_EN

RESISTOR-G155-14701-01,4.7KOHMA  I83  R107
   2 FPGA_IN_MAC_USB_OC_N      2 @TIMECARD_LIB.TIMECARD(SCH_1):FPGA_IN_MAC_USB_OC_N
   1 XP3R3V_FPGA      1 @TIMECARD_LIB.TIMECARD(SCH_1):XP3R3V_FPGA

CAPACITOR-G105-0B104-EK,0.1UF,A  I85  C71
   1 XP5R0V_MAC_USB      1 @TIMECARD_LIB.TIMECARD(SCH_1):XP5R0V_MAC_USB
   2     SG      2 @TIMECARD_LIB.TIMECARD(SCH_1):SG

FERRITEBEAD-G191-10101-01,26OHA  I91  L3
   1 XP5R0V_MAC      1 @TIMECARD_LIB.TIMECARD(SCH_1):XP5R0V_MAC
   2 XP5R0V      2 @TIMECARD_LIB.TIMECARD(SCH_1):XP5R0V

CAPACITOR-G105-0B104-EK,0.1UF,A  I93  C62
   1 XP5R0V      1 @TIMECARD_LIB.TIMECARD(SCH_1):XP5R0V
   2     SG      2 @TIMECARD_LIB.TIMECARD(SCH_1):SG

CAPACITOR-G105-0B104-CK,0.1UF,A  I103  C67
   1 XP3R3V_FPGA      1 @TIMECARD_LIB.TIMECARD(SCH_1):XP3R3V_FPGA
   2     SG      2 @TIMECARD_LIB.TIMECARD(SCH_1):SG

TS3USB3031RMGR_WQFN12-G220-103A  I108  U11
  12 XP3R3V_FPGA    VCC @TIMECARD_LIB.TIMECARD(SCH_1):XP3R3V_FPGA
  11 MUX_USB_DP    D_P @TIMECARD_LIB.TIMECARD(SCH_1):MUX_USB_DP
  10 MUX_USB_DM    D_N @TIMECARD_LIB.TIMECARD(SCH_1):MUX_USB_DM
   1 XP5R0V_USB_CONN_DET   SEL0 @TIMECARD_LIB.TIMECARD(SCH_1):XP5R0V_USB_CONN_DET
   2 UNNAMED_527_RESISTOR_I126_1   SEL1 @TIMECARD_LIB.TIMECARD(SCH_1):UNNAMED_527_RESISTOR_I126_1
   3 MAC_USB_DP USB1_P @TIMECARD_LIB.TIMECARD(SCH_1):MAC_USB_DP
   4 MAC_USB_DM USB1_N @TIMECARD_LIB.TIMECARD(SCH_1):MAC_USB_DM
   5 CONN_MICRO_USB_DP USB2_P @TIMECARD_LIB.TIMECARD(SCH_1):CONN_MICRO_USB_DP
   6 CONN_MICRO_USB_DM USB2_N @TIMECARD_LIB.TIMECARD(SCH_1):CONN_MICRO_USB_DM
   7     NC  MHL_P     NC
   8     NC  MHL_N     NC
   9     SG    GND @TIMECARD_LIB.TIMECARD(SCH_1):SG

RESISTOR-G155-100R0-J0,0OHM,-  I123  R105
   2 MAC_USB_DM      2 @TIMECARD_LIB.TIMECARD(SCH_1):MAC_USB_DM
   1 MUX_USB_DM      1 @TIMECARD_LIB.TIMECARD(SCH_1):MUX_USB_DM

RESISTOR-G155-100R0-J0,0OHM,-  I124  R106
   2 MAC_USB_DP      2 @TIMECARD_LIB.TIMECARD(SCH_1):MAC_USB_DP
   1 MUX_USB_DP      1 @TIMECARD_LIB.TIMECARD(SCH_1):MUX_USB_DP

RESISTOR-G155-14701-01,4.7KOHMA  I126  R104
   2     SG      2 @TIMECARD_LIB.TIMECARD(SCH_1):SG
   1 UNNAMED_527_RESISTOR_I126_1      1 @TIMECARD_LIB.TIMECARD(SCH_1):UNNAMED_527_RESISTOR_I126_1

CAPACITOR-G105-0B104-EK,0.1UF,A  I144  C68
   1 XP3R3V_FPGA      1 @TIMECARD_LIB.TIMECARD(SCH_1):XP3R3V_FPGA
   2     SG      2 @TIMECARD_LIB.TIMECARD(SCH_1):SG

CL5003148A-G220-10019-01  I146  U10
   3     SG    GND @TIMECARD_LIB.TIMECARD(SCH_1):SG
   5 XP3R3V_FPGA    VCC @TIMECARD_LIB.TIMECARD(SCH_1):XP3R3V_FPGA

CL5003148A-G220-10019-01  I147  U10
   1 FPGA_OUT_MACUSBPOWER_EN      A @TIMECARD_LIB.TIMECARD(SCH_1):FPGA_OUT_MACUSBPOWER_EN
   2 XP5R0V_USB_CONN_DET      B @TIMECARD_LIB.TIMECARD(SCH_1):XP5R0V_USB_CONN_DET
   4 USB_PWR_EN      Y @TIMECARD_LIB.TIMECARD(SCH_1):USB_PWR_EN

RESISTOR-G155-14701-01,4.7KOHMA  I149  R99
   2     SG      2 @TIMECARD_LIB.TIMECARD(SCH_1):SG
   1 FPGA_OUT_MACUSBPOWER_EN      1 @TIMECARD_LIB.TIMECARD(SCH_1):FPGA_OUT_MACUSBPOWER_EN

RESISTOR-G155-133R0-01,33OHM,1%  I155  R100
   2 USB_PWR_EN      2 @TIMECARD_LIB.TIMECARD(SCH_1):USB_PWR_EN
   1 FPGA_OUT_MACUSBPOWER_EN      1 @TIMECARD_LIB.TIMECARD(SCH_1):FPGA_OUT_MACUSBPOWER_EN

RESISTOR-G155-100R0-J0,0OHM,-  I175  R98
   2 MUX_USB_DM      2 @TIMECARD_LIB.TIMECARD(SCH_1):MUX_USB_DM
   1 R_MAC_USB_DM      1 @TIMECARD_LIB.TIMECARD(SCH_1):R_MAC_USB_DM

RESISTOR-G155-100R0-J0,0OHM,-  I176  R97
   2 MUX_USB_DP      2 @TIMECARD_LIB.TIMECARD(SCH_1):MUX_USB_DP
   1 R_MAC_USB_DP      1 @TIMECARD_LIB.TIMECARD(SCH_1):R_MAC_USB_DP

RESISTOR-G155-133R0-01,33OHM,1%  I187  R91
   2 SMA_ANALOG_TUNING_IN      2 @TIMECARD_LIB.TIMECARD(SCH_1):SMA_ANALOG_TUNING_IN
   1 ANALOG_TUNING_IN      1 @TIMECARD_LIB.TIMECARD(SCH_1):ANALOG_TUNING_IN

CONN_HDR_2X10_M_S_SMT-G200-130A  I193  P1
   1 R_MAC_PPS_IN1P      1 @TIMECARD_LIB.TIMECARD(SCH_1):R_MAC_PPS_IN1P
   3 R_MAC_PPS_IN1N      3 @TIMECARD_LIB.TIMECARD(SCH_1):R_MAC_PPS_IN1N
   5 R_MAC_PPS_IN0P      5 @TIMECARD_LIB.TIMECARD(SCH_1):R_MAC_PPS_IN0P
   7 R_MAC_PPS_IN0N      7 @TIMECARD_LIB.TIMECARD(SCH_1):R_MAC_PPS_IN0N
   9     SG      9 @TIMECARD_LIB.TIMECARD(SCH_1):SG
  11     NC     11     NC
  13     NC     13     NC
  15     SG     15 @TIMECARD_LIB.TIMECARD(SCH_1):SG
  17 R_MAC_PPS_OUTP     17 @TIMECARD_LIB.TIMECARD(SCH_1):R_MAC_PPS_OUTP
  19 R_MAC_PPS_OUTN     19 @TIMECARD_LIB.TIMECARD(SCH_1):R_MAC_PPS_OUTN
   2 R_MAC_USB_DP      2 @TIMECARD_LIB.TIMECARD(SCH_1):R_MAC_USB_DP
   4 R_MAC_USB_DM      4 @TIMECARD_LIB.TIMECARD(SCH_1):R_MAC_USB_DM
   6 XP5R0V_MAC_USB      6 @TIMECARD_LIB.TIMECARD(SCH_1):XP5R0V_MAC_USB
   8     SG      8 @TIMECARD_LIB.TIMECARD(SCH_1):SG
  10     NC     10     NC
  12     NC     12     NC
  14     NC     14     NC
  16     NC     16     NC
  18     NC     18     NC
  20 MAC_ALARM     20 @TIMECARD_LIB.TIMECARD(SCH_1):MAC_ALARM

CONN_HDR_1X3_M_S_SMT-G205-1002A  I198  J18
   1     SG      1 @TIMECARD_LIB.TIMECARD(SCH_1):SG
   2 SMA_ANALOG_TUNING_IN      2 @TIMECARD_LIB.TIMECARD(SCH_1):SMA_ANALOG_TUNING_IN
   3     SG      3 @TIMECARD_LIB.TIMECARD(SCH_1):SG

RESISTOR-G155-11001-01,1KOHM,1%  I200  R101
   2 XP5R0V_USB_CONN_DET      2 @TIMECARD_LIB.TIMECARD(SCH_1):XP5R0V_USB_CONN_DET
   1 XP5R0V_USB_CONN      1 @TIMECARD_LIB.TIMECARD(SCH_1):XP5R0V_USB_CONN

RESISTOR-G155-11001-01,1KOHM,1%  I201  R102
   2 UNNAMED_527_RESISTOR_I201_2      2 @TIMECARD_LIB.TIMECARD(SCH_1):UNNAMED_527_RESISTOR_I201_2
   1 XP5R0V_USB_CONN_DET      1 @TIMECARD_LIB.TIMECARD(SCH_1):XP5R0V_USB_CONN_DET

RESISTOR-G155-11001-01,1KOHM,1%  I202  R103
   2     SG      2 @TIMECARD_LIB.TIMECARD(SCH_1):SG
   1 UNNAMED_527_RESISTOR_I201_2      1 @TIMECARD_LIB.TIMECARD(SCH_1):UNNAMED_527_RESISTOR_I201_2

RESISTOR-G155-133R0-01,33OHM,1%  I204  R266
   2 XP5R0V_USB_CONN_DET      2 @TIMECARD_LIB.TIMECARD(SCH_1):XP5R0V_USB_CONN_DET
   1 RSVD_DBG_USB_MUX_SEL      1 @TIMECARD_LIB.TIMECARD(SCH_1):RSVD_DBG_USB_MUX_SEL

RESISTOR-G155-133R0-01,33OHM,1%  I206  R267
   2 FPGA_IN_MAC_USB_OC_N      2 @TIMECARD_LIB.TIMECARD(SCH_1):FPGA_IN_MAC_USB_OC_N
   1 UNNAMED_527_RESISTOR_I206_1      1 @TIMECARD_LIB.TIMECARD(SCH_1):UNNAMED_527_RESISTOR_I206_1

CAPACITOR-G107-0F106-EM,10UF,2A  I208  C282
   1 XP5R0V_MAC      1 @TIMECARD_LIB.TIMECARD(SCH_1):XP5R0V_MAC
   2     SG      2 @TIMECARD_LIB.TIMECARD(SCH_1):SG

CAPACITOR-G107-0F106-EM,10UF,2A  I209  C283
   1 XP5R0V_MAC      1 @TIMECARD_LIB.TIMECARD(SCH_1):XP5R0V_MAC
   2     SG      2 @TIMECARD_LIB.TIMECARD(SCH_1):SG

RESISTOR-G155-14701-01,4.7KOHMA  I211  R287
   2 XP3R3V_FPGA      2 @TIMECARD_LIB.TIMECARD(SCH_1):XP3R3V_FPGA
   1 FPGA_IN_MAC_ALARM_OUT_N      1 @TIMECARD_LIB.TIMECARD(SCH_1):FPGA_IN_MAC_ALARM_OUT_N

NUT-A200-00029-FB  I220  MAC_PIN8
   1 R_MAC_UART_RX_FPGA_TX      1 @TIMECARD_LIB.TIMECARD(SCH_1):R_MAC_UART_RX_FPGA_TX

RESISTOR-G155-11003-01,100KOHMA  I221  R265
   2 UART_MAC_TX_FPGA_RX      2 @TIMECARD_LIB.TIMECARD(SCH_1):UART_MAC_TX_FPGA_RX
   1 XP3R3V_FPGA      1 @TIMECARD_LIB.TIMECARD(SCH_1):XP3R3V_FPGA

RESISTOR-G155-11003-01,100KOHMA  I222  R264
   2 R_MAC_UART_RX_FPGA_TX      2 @TIMECARD_LIB.TIMECARD(SCH_1):R_MAC_UART_RX_FPGA_TX
   1 XP3R3V_FPGA      1 @TIMECARD_LIB.TIMECARD(SCH_1):XP3R3V_FPGA

NUT-A200-00029-FB  I224  MAC_PIN7
   1 R_MAC_UART_TX_FPGA_RX      1 @TIMECARD_LIB.TIMECARD(SCH_1):R_MAC_UART_TX_FPGA_RX

NUT-A200-00029-FB  I225  MAC_PIN6
   1 R_MAC_BITEOUT      1 @TIMECARD_LIB.TIMECARD(SCH_1):R_MAC_BITE OUT

NUT-A200-00029-FB  I226  MAC_PIN3
   1 R_MAC_10MHZ_RF_OUT      1 @TIMECARD_LIB.TIMECARD(SCH_1):R_MAC_10MHZ_RF_OUT

NUT-A200-00029-FB  I227  MAC_PIN1
   1 ANALOG_TUNING_IN      1 @TIMECARD_LIB.TIMECARD(SCH_1):ANALOG_TUNING_IN

NUT-A200-00029-FB  I228  MAC_PIN4
   1     SG      1 @TIMECARD_LIB.TIMECARD(SCH_1):SG

NUT-A200-00029-FB  I229  MAC_PIN2
   1     SG      1 @TIMECARD_LIB.TIMECARD(SCH_1):SG

NUT-A200-00029-FB  I230  MAC_PIN5
   1 XP5R0V_MAC      1 @TIMECARD_LIB.TIMECARD(SCH_1):XP5R0V_MAC

POWERMOS_3P_PCH-G121-10216-01  I231  Q3
   1 UNNAMED_527_POWERMOS3PNCHV1_I23      G @TIMECARD_LIB.TIMECARD(SCH_1):UNNAMED_527_POWERMOS3PNCHV1_I232_D
   2 XP5R0V_MAC      S @TIMECARD_LIB.TIMECARD(SCH_1):XP5R0V_MAC
   3 UNNAMED_527_FUSE_I244_1      D @TIMECARD_LIB.TIMECARD(SCH_1):UNNAMED_527_FUSE_I244_1

POWERMOS_3P_NCH_V1-G121-10200-A  I232  Q2
   1 USB_PWR_EN      G @TIMECARD_LIB.TIMECARD(SCH_1):USB_PWR_EN
   2     SG      S @TIMECARD_LIB.TIMECARD(SCH_1):SG
   3 UNNAMED_527_POWERMOS3PNCHV1_I23      D @TIMECARD_LIB.TIMECARD(SCH_1):UNNAMED_527_POWERMOS3PNCHV1_I232_D

RESISTOR-G155-14701-01,4.7KOHMA  I233  R44
   2 UNNAMED_527_POWERMOS3PNCHV1_I23      2 @TIMECARD_LIB.TIMECARD(SCH_1):UNNAMED_527_POWERMOS3PNCHV1_I232_D
   1 XP5R0V_MAC      1 @TIMECARD_LIB.TIMECARD(SCH_1):XP5R0V_MAC

RESISTOR-G155-133R0-01,33OHM,1%  I240  R81
   2 DBG_UART_MAC_RX      2 @TIMECARD_LIB.TIMECARD(SCH_1):DBG_UART_MAC_RX
   1 R_MAC_UART_RX_FPGA_TX      1 @TIMECARD_LIB.TIMECARD(SCH_1):R_MAC_UART_RX_FPGA_TX

RESISTOR-G155-133R0-01,33OHM,1%  I241  R82
   2 DBG_UART_MAC_TX      2 @TIMECARD_LIB.TIMECARD(SCH_1):DBG_UART_MAC_TX
   1 R_MAC_UART_TX_FPGA_RX      1 @TIMECARD_LIB.TIMECARD(SCH_1):R_MAC_UART_TX_FPGA_RX

FUSE-G280-10049-01,1A  I244  FU3
   1 UNNAMED_527_FUSE_I244_1      1 @TIMECARD_LIB.TIMECARD(SCH_1):UNNAMED_527_FUSE_I244_1
   2 XP5R0V_MAC_USB      2 @TIMECARD_LIB.TIMECARD(SCH_1):XP5R0V_MAC_USB

RESISTOR-G157-100R0-J0,0OHM,-  I245  R357
   2 UNNAMED_527_FUSE_I244_1      2 @TIMECARD_LIB.TIMECARD(SCH_1):UNNAMED_527_FUSE_I244_1
   1 XP5R0V_MAC      1 @TIMECARD_LIB.TIMECARD(SCH_1):XP5R0V_MAC


DRAWING: @TIMECARD_LIB.TIMECARD(SCH_1):PAGE16 

TP_PIONT-TP010CT020B030_PTH-TPA  I1014  TP132
   1 IO_L20P_34      1 @TIMECARD_LIB.TIMECARD(SCH_1):IO_L20P_34

TP_PIONT-TP010CT020B030_PTH-TPA  I1015  TP133
   1 IO_L20N_34      1 @TIMECARD_LIB.TIMECARD(SCH_1):IO_L20N_34

TP_PIONT-TP010CT020B030_PTH-TPA  I1016  TP134
   1 IO_L21P_34      1 @TIMECARD_LIB.TIMECARD(SCH_1):IO_L21P_34

TP_PIONT-TP010CT020B030_PTH-TPA  I1017  TP135
   1 IO_L21N_34      1 @TIMECARD_LIB.TIMECARD(SCH_1):IO_L21N_34

TP_PIONT-TP010CT020B030_PTH-TPA  I1018  TP136
   1 IO_L22P_34      1 @TIMECARD_LIB.TIMECARD(SCH_1):IO_L22P_34

TP_PIONT-TP010CT020B030_PTH-TPA  I1019  TP137
   1 IO_L22N_34      1 @TIMECARD_LIB.TIMECARD(SCH_1):IO_L22N_34

TP_PIONT-TP010CT020B030_PTH-TPA  I1020  TP138
   1 IO_L23P_34      1 @TIMECARD_LIB.TIMECARD(SCH_1):IO_L23P_34

TP_PIONT-TP010CT020B030_PTH-TPA  I1021  TP139
   1 IO_L23N_34      1 @TIMECARD_LIB.TIMECARD(SCH_1):IO_L23N_34

TP_PIONT-TP010CT020B030_PTH-TPA  I1022  TP140
   1 IO_L24P_34      1 @TIMECARD_LIB.TIMECARD(SCH_1):IO_L24P_34

TP_PIONT-TP010CT020B030_PTH-TPA  I1023  TP141
   1 IO_L24N_34      1 @TIMECARD_LIB.TIMECARD(SCH_1):IO_L24N_34

TP_PIONT-TP010CT020B030_PTH-TPA  I1206  TP52
   1 XP12R0V      1 @TIMECARD_LIB.TIMECARD(SCH_1):XP12R0V

TP_PIONT-TP010CT020B030_PTH-TPA  I1208  TP53
   1 XP3R3V      1 @TIMECARD_LIB.TIMECARD(SCH_1):XP3R3V

TP_PIONT-TP010CT020B030_PTH-TPA  I1210  TP54
   1 XP1R0V_FPGA      1 @TIMECARD_LIB.TIMECARD(SCH_1):XP1R0V_FPGA

TP_PIONT-TP010CT020B030_PTH-TPA  I1212  TP55
   1 XP1R2V_FPGA      1 @TIMECARD_LIB.TIMECARD(SCH_1):XP1R2V_FPGA

TP_PIONT-TP010CT020B030_PTH-TPA  I1215  TP56
   1 XP1R8V_FPGA      1 @TIMECARD_LIB.TIMECARD(SCH_1):XP1R8V_FPGA

TP_PIONT-TP010CT020B030_PTH-TPA  I1217  TP57
   1 XP2R5V_FPGA      1 @TIMECARD_LIB.TIMECARD(SCH_1):XP2R5V_FPGA

TP_PIONT-TP010CT020B030_PTH-TPA  I1219  TP58
   1 XP3R3V_FPGA      1 @TIMECARD_LIB.TIMECARD(SCH_1):XP3R3V_FPGA

TP_PIONT-TP010CT020B030_PTH-TPA  I1233  TP60
   1 XP5R0V      1 @TIMECARD_LIB.TIMECARD(SCH_1):XP5R0V

TP_PIONT-TP010CT020B030_PTH-TPA  I1487  TP193
   1 IO_L21P_35      1 @TIMECARD_LIB.TIMECARD(SCH_1):IO_L21P_35

TP_PIONT-TP010CT020B030_PTH-TPA  I1488  TP194
   1 IO_L21N_35      1 @TIMECARD_LIB.TIMECARD(SCH_1):IO_L21N_35

TP_PIONT-TP010CT020B030_PTH-TPA  I1489  TP195
   1 IO_L23P_35      1 @TIMECARD_LIB.TIMECARD(SCH_1):IO_L23P_35

TP_PIONT-TP010CT020B030_PTH-TPA  I1490  TP196
   1 IO_L23N_35      1 @TIMECARD_LIB.TIMECARD(SCH_1):IO_L23N_35

TP_PIONT-TP010CT020B030_PTH-TPA  I1505  TP183
   1 IO_L22P_16      1 @TIMECARD_LIB.TIMECARD(SCH_1):IO_L22P_16

TP_PIONT-TP010CT020B030_PTH-TPA  I1506  TP184
   1 IO_L22N_16      1 @TIMECARD_LIB.TIMECARD(SCH_1):IO_L22N_16

TP_PIONT-TP010CT020B030_PTH-TPA  I1507  TP185
   1 IO_L23P_16      1 @TIMECARD_LIB.TIMECARD(SCH_1):IO_L23P_16

TP_PIONT-TP010CT020B030_PTH-TPA  I1508  TP186
   1 IO_L23N_16      1 @TIMECARD_LIB.TIMECARD(SCH_1):IO_L23N_16

TP_PIONT-TP010CT020B030_PTH-TPA  I1509  TP187
   1 IO_L24P_16      1 @TIMECARD_LIB.TIMECARD(SCH_1):IO_L24P_16

TP_PIONT-TP010CT020B030_PTH-TPA  I1510  TP188
   1 IO_L24N_16      1 @TIMECARD_LIB.TIMECARD(SCH_1):IO_L24N_16

TP_PIONT-TP010CT020B030_PTH-TPA  I1511  TP180
   1 IO_L20N_16      1 @TIMECARD_LIB.TIMECARD(SCH_1):IO_L20N_16

TP_PIONT-TP010CT020B030_PTH-TPA  I1512  TP181
   1 IO_L21P_16      1 @TIMECARD_LIB.TIMECARD(SCH_1):IO_L21P_16

TP_PIONT-TP010CT020B030_PTH-TPA  I1513  TP182
   1 IO_L21N_16      1 @TIMECARD_LIB.TIMECARD(SCH_1):IO_L21N_16

TP_PIONT-TP010CT020B030_PTH-TPA  I1516  TP78
   1 IO_L20P_16      1 @TIMECARD_LIB.TIMECARD(SCH_1):IO_L20P_16

TP_PIONT-TP010CT020B030_PTH-TPA  I1523  TP203
   1 IO_L24P_35      1 @TIMECARD_LIB.TIMECARD(SCH_1):IO_L24P_35

TP_PIONT-TP010CT020B030_PTH-TPA  I1524  TP204
   1 IO_L24N_35      1 @TIMECARD_LIB.TIMECARD(SCH_1):IO_L24N_35

TP_PIONT-TP010CT020B030_PTH-TPA  I1527  TP199
   1 IO_L20P_35      1 @TIMECARD_LIB.TIMECARD(SCH_1):IO_L20P_35

TP_PIONT-TP010CT020B030_PTH-TPA  I1528  TP200
   1 IO_L20N_35      1 @TIMECARD_LIB.TIMECARD(SCH_1):IO_L20N_35

TP_PIONT-TP010CT020B030_PTH-TPA  I1529  TP201
   1 IO_L22P_35      1 @TIMECARD_LIB.TIMECARD(SCH_1):IO_L22P_35

TP_PIONT-TP010CT020B030_PTH-TPA  I1530  TP202
   1 IO_L22N_35      1 @TIMECARD_LIB.TIMECARD(SCH_1):IO_L22N_35

RESISTOR-G155-14701-01,4.7KOHMA  I1542  R171
   2 FPGA_IO_0      2 @TIMECARD_LIB.TIMECARD(SCH_1):FPGA_IO_0
   1     SG      1 @TIMECARD_LIB.TIMECARD(SCH_1):SG

RESISTOR-G155-14701-01,4.7KOHMA  I1544  R173
   2 FPGA_IO_1      2 @TIMECARD_LIB.TIMECARD(SCH_1):FPGA_IO_1
   1     SG      1 @TIMECARD_LIB.TIMECARD(SCH_1):SG

RESISTOR-G155-14701-01,4.7KOHMA  I1547  R284
   2 FPGA_IO_2      2 @TIMECARD_LIB.TIMECARD(SCH_1):FPGA_IO_2
   1     SG      1 @TIMECARD_LIB.TIMECARD(SCH_1):SG

RESISTOR-G155-14701-01,4.7KOHMA  I1549  R286
   2 FPGA_IO_3      2 @TIMECARD_LIB.TIMECARD(SCH_1):FPGA_IO_3
   1     SG      1 @TIMECARD_LIB.TIMECARD(SCH_1):SG

RESISTOR-G155-14701-01,4.7KOHMA  I1550  R328
   2 FPGA_IO_7      2 @TIMECARD_LIB.TIMECARD(SCH_1):FPGA_IO_7
   1     SG      1 @TIMECARD_LIB.TIMECARD(SCH_1):SG

RESISTOR-G155-14701-01,4.7KOHMA  I1552  R326
   2 FPGA_IO_6      2 @TIMECARD_LIB.TIMECARD(SCH_1):FPGA_IO_6
   1     SG      1 @TIMECARD_LIB.TIMECARD(SCH_1):SG

RESISTOR-G155-14701-01,4.7KOHMA  I1555  R293
   2 FPGA_IO_4      2 @TIMECARD_LIB.TIMECARD(SCH_1):FPGA_IO_4
   1     SG      1 @TIMECARD_LIB.TIMECARD(SCH_1):SG

RESISTOR-G155-14701-01,4.7KOHMA  I1557  R309
   2 FPGA_IO_5      2 @TIMECARD_LIB.TIMECARD(SCH_1):FPGA_IO_5
   1     SG      1 @TIMECARD_LIB.TIMECARD(SCH_1):SG

RESISTOR-G155-11002-01,10KOHM,A  I1602  R325
   2 FPGA_IO_6      2 @TIMECARD_LIB.TIMECARD(SCH_1):FPGA_IO_6
   1 XP3R3V_FPGA      1 @TIMECARD_LIB.TIMECARD(SCH_1):XP3R3V_FPGA

RESISTOR-G155-11002-01,10KOHM,A  I1603  R327
   2 FPGA_IO_7      2 @TIMECARD_LIB.TIMECARD(SCH_1):FPGA_IO_7
   1 XP3R3V_FPGA      1 @TIMECARD_LIB.TIMECARD(SCH_1):XP3R3V_FPGA

RESISTOR-G155-11002-01,10KOHM,A  I1604  R308
   2 FPGA_IO_5      2 @TIMECARD_LIB.TIMECARD(SCH_1):FPGA_IO_5
   1 XP3R3V_FPGA      1 @TIMECARD_LIB.TIMECARD(SCH_1):XP3R3V_FPGA

RESISTOR-G155-11002-01,10KOHM,A  I1605  R292
   2 FPGA_IO_4      2 @TIMECARD_LIB.TIMECARD(SCH_1):FPGA_IO_4
   1 XP3R3V_FPGA      1 @TIMECARD_LIB.TIMECARD(SCH_1):XP3R3V_FPGA

RESISTOR-G155-11002-01,10KOHM,A  I1606  R285
   2 FPGA_IO_3      2 @TIMECARD_LIB.TIMECARD(SCH_1):FPGA_IO_3
   1 XP3R3V_FPGA      1 @TIMECARD_LIB.TIMECARD(SCH_1):XP3R3V_FPGA

RESISTOR-G155-11002-01,10KOHM,A  I1607  R172
   2 FPGA_IO_1      2 @TIMECARD_LIB.TIMECARD(SCH_1):FPGA_IO_1
   1 XP3R3V_FPGA      1 @TIMECARD_LIB.TIMECARD(SCH_1):XP3R3V_FPGA

RESISTOR-G155-11002-01,10KOHM,A  I1608  R170
   2 FPGA_IO_0      2 @TIMECARD_LIB.TIMECARD(SCH_1):FPGA_IO_0
   1 XP3R3V_FPGA      1 @TIMECARD_LIB.TIMECARD(SCH_1):XP3R3V_FPGA

RESISTOR-G155-11002-01,10KOHM,A  I1609  R283
   2 FPGA_IO_2      2 @TIMECARD_LIB.TIMECARD(SCH_1):FPGA_IO_2
   1 XP3R3V_FPGA      1 @TIMECARD_LIB.TIMECARD(SCH_1):XP3R3V_FPGA

TP_PIONT-TP010CT020B030_PTH-TPA  I1610  TP3
   1 XP3R3V_FT4232      1 @TIMECARD_LIB.TIMECARD(SCH_1):XP3R3V_FT4232

TP_PIONT-TP010CT020B030_PTH-TPA  I1612  TP4
   1 XP5R0V_FT4232      1 @TIMECARD_LIB.TIMECARD(SCH_1):XP5R0V_FT4232

CONN_HDR_2X6_F_S_SMT-G200-1313A  I1614  J5
   1 UNNAMED_16_CONNHDR2X6FSSMT_I161      1 @TIMECARD_LIB.TIMECARD(SCH_1):UNNAMED_16_CONNHDR2X6FSSMT_I1614_1
   3 UNNAMED_16_CONNHDR2X6FSSMT_I1_2      3 @TIMECARD_LIB.TIMECARD(SCH_1):UNNAMED_16_CONNHDR2X6FSSMT_I1614_3
   5 UNNAMED_16_CONNHDR2X6FSSMT_I1_6      5 @TIMECARD_LIB.TIMECARD(SCH_1):UNNAMED_16_CONNHDR2X6FSSMT_I1614_5
   7 UNNAMED_16_CONNHDR2X6FSSMT_I1_4      7 @TIMECARD_LIB.TIMECARD(SCH_1):UNNAMED_16_CONNHDR2X6FSSMT_I1614_7
   9     SG      9 @TIMECARD_LIB.TIMECARD(SCH_1):SG
  11 XP3R3V_FPGA     11 @TIMECARD_LIB.TIMECARD(SCH_1):XP3R3V_FPGA
   2 UNNAMED_16_CONNHDR2X6FSSMT_I1_1      2 @TIMECARD_LIB.TIMECARD(SCH_1):UNNAMED_16_CONNHDR2X6FSSMT_I1614_2
   4 UNNAMED_16_CONNHDR2X6FSSMT_I1_3      4 @TIMECARD_LIB.TIMECARD(SCH_1):UNNAMED_16_CONNHDR2X6FSSMT_I1614_4
   6 UNNAMED_16_CONNHDR2X6FSSMT_I1_7      6 @TIMECARD_LIB.TIMECARD(SCH_1):UNNAMED_16_CONNHDR2X6FSSMT_I1614_6
   8 UNNAMED_16_CONNHDR2X6FSSMT_I1_5      8 @TIMECARD_LIB.TIMECARD(SCH_1):UNNAMED_16_CONNHDR2X6FSSMT_I1614_8
  10     SG     10 @TIMECARD_LIB.TIMECARD(SCH_1):SG
  12 XP3R3V_FPGA     12 @TIMECARD_LIB.TIMECARD(SCH_1):XP3R3V_FPGA

TP_PIONT-TP010CT020B030_PTH-TPA  I1615  TP20
   1 SEC_EEPROM_WP      1 @TIMECARD_LIB.TIMECARD(SCH_1):SEC_EEPROM_WP

TP_PIONT-TP010CT020B030_PTH-TPA  I1626  TP11
   1 FT_USB_DETECT      1 @TIMECARD_LIB.TIMECARD(SCH_1):FT_USB_DETECT

TP_PIONT-TP010CT020B030_PTH-TPA  I1627  TP12
   1 MUX3_SEL      1 @TIMECARD_LIB.TIMECARD(SCH_1):MUX3_SEL

TP_PIONT-TP010CT020B030_PTH-TPA  I1628  TP13
   1 MUX2_SEL      1 @TIMECARD_LIB.TIMECARD(SCH_1):MUX2_SEL

TP_PIONT-TP010CT020B030_PTH-TPA  I1629  TP14
   1 MUX1_SEL      1 @TIMECARD_LIB.TIMECARD(SCH_1):MUX1_SEL

TP_PIONT-TP010CT020B030_PTH-TPA  I1630  TP15
   1 GPS_RST_N      1 @TIMECARD_LIB.TIMECARD(SCH_1):GPS_RST_N

TP_PIONT-TP010CT020B030_PTH-TPA  I1631  TP16
   1 R_BNO080_RST_N      1 @TIMECARD_LIB.TIMECARD(SCH_1):R_BNO080_RST_N

TP_PIONT-TP010CT020B030_PTH-TPA  I1632  TP17
   1 R_BNO080_INT_N      1 @TIMECARD_LIB.TIMECARD(SCH_1):R_BNO080_INT_N

TP_PIONT-TP010CT020B030_PTH-TPA  I1633  TP18
   1 R_BNO080_BOOT_N      1 @TIMECARD_LIB.TIMECARD(SCH_1):R_BNO080_BOOT_N

TP_PIONT-TP010CT020B030_PTH-TPA  I1634  TP19
   1 SN_EEPROM_WP      1 @TIMECARD_LIB.TIMECARD(SCH_1):SN_EEPROM_WP

TP_PIONT-TP010CT020B030_PTH-TPA  I1645  TP21
   1 PCA9546_RST_N      1 @TIMECARD_LIB.TIMECARD(SCH_1):PCA9546_RST_N

TP_PIONT-TP010CT020B030_PTH-TPA  I1646  TP22
   1 FPGA_IN_LM75B_INT3_N      1 @TIMECARD_LIB.TIMECARD(SCH_1):FPGA_IN_LM75B_INT3_N

TP_PIONT-TP010CT020B030_PTH-TPA  I1647  TP23
   1 FPGA_IN_LM75B_INT2_N      1 @TIMECARD_LIB.TIMECARD(SCH_1):FPGA_IN_LM75B_INT2_N

TP_PIONT-TP010CT020B030_PTH-TPA  I1648  TP24
   1 FPGA_IN_LM75B_INT1_N      1 @TIMECARD_LIB.TIMECARD(SCH_1):FPGA_IN_LM75B_INT1_N

TP_PIONT-TP010CT020B030_PTH-TPA  I1649  TP25
   1 RGB_LED_SHUTDOWN_N      1 @TIMECARD_LIB.TIMECARD(SCH_1):RGB_LED_SHUTDOWN_N

TP_PIONT-TP010CT020B030_PTH-TPA  I1650  TP36
   1 XP12R0V_A_PG      1 @TIMECARD_LIB.TIMECARD(SCH_1):XP12R0V_A_PG

TP_PIONT-TP010CT020B030_PTH-TPA  I1651  TP38
   1 XP3R3V_PG      1 @TIMECARD_LIB.TIMECARD(SCH_1):XP3R3V_PG

TP_PIONT-TP010CT020B030_PTH-TPA  I1652  TP39
   1 XP1R0V_FPGA_PG      1 @TIMECARD_LIB.TIMECARD(SCH_1):XP1R0V_FPGA_PG

TP_PIONT-TP010CT020B030_PTH-TPA  I1653  TP40
   1 XP1R2V_FPGA_PG      1 @TIMECARD_LIB.TIMECARD(SCH_1):XP1R2V_FPGA_PG

TP_PIONT-TP010CT020B030_PTH-TPA  I1654  TP41
   1 XP1R8V_FPGA_PG      1 @TIMECARD_LIB.TIMECARD(SCH_1):XP1R8V_FPGA_PG

TP_PIONT-TP010CT020B030_PTH-TPA  I1660  TP26
   1 R_SHT3X_RST_N      1 @TIMECARD_LIB.TIMECARD(SCH_1):R_SHT3X_RST_N

TP_PIONT-TP010CT020B030_PTH-TPA  I1661  TP27
   1 R_SHT3X_ALERT_N      1 @TIMECARD_LIB.TIMECARD(SCH_1):R_SHT3X_ALERT_N

TP_PIONT-TP010CT020B030_PTH-TPA  I1662  TP32
   1 SMA1_SIG_OUT_BF_EN_N      1 @TIMECARD_LIB.TIMECARD(SCH_1):SMA1_SIG_OUT_BF_EN_N

TP_PIONT-TP010CT020B030_PTH-TPA  I1663  TP59
   1 XP3R3V_EN      1 @TIMECARD_LIB.TIMECARD(SCH_1):XP3R3V_EN

TP_PIONT-TP010CT020B030_PTH-TPA  I1665  TP42
   1 XP12R0V_IN      1 @TIMECARD_LIB.TIMECARD(SCH_1):XP12R0V_IN

TP_PIONT-TP010CT020B030_PTH-TPA  I1667  TP28
   1 SMA1_SIG_IN_BF_EN_N      1 @TIMECARD_LIB.TIMECARD(SCH_1):SMA1_SIG_IN_BF_EN_N

TP_PIONT-TP010CT020B030_PTH-TPA  I1669  TP33
   1 SMA2_SIG_OUT_BF_EN_N      1 @TIMECARD_LIB.TIMECARD(SCH_1):SMA2_SIG_OUT_BF_EN_N

TP_PIONT-TP010CT020B030_PTH-TPA  I1672  TP29
   1 SMA2_SIG_IN_BF_EN_N      1 @TIMECARD_LIB.TIMECARD(SCH_1):SMA2_SIG_IN_BF_EN_N

TP_PIONT-TP010CT020B030_PTH-TPA  I1673  TP34
   1 SMA3_SIG_OUT_BF_EN_N      1 @TIMECARD_LIB.TIMECARD(SCH_1):SMA3_SIG_OUT_BF_EN_N

TP_PIONT-TP010CT020B030_PTH-TPA  I1675  TP35
   1 SMA4_SIG_OUT_BF_EN_N      1 @TIMECARD_LIB.TIMECARD(SCH_1):SMA4_SIG_OUT_BF_EN_N

TP_PIONT-TP010CT020B030_PTH-TPA  I1678  TP30
   1 SMA3_SIG_IN_BF_EN_N      1 @TIMECARD_LIB.TIMECARD(SCH_1):SMA3_SIG_IN_BF_EN_N

TP_PIONT-TP010CT020B030_PTH-TPA  I1679  TP31
   1 SMA4_SIG_IN_BF_EN_N      1 @TIMECARD_LIB.TIMECARD(SCH_1):SMA4_SIG_IN_BF_EN_N

TP_PIONT-TP010CT020B030_PTH-TPA  I1682  TP37
   1 XP12R0V_A_FLTB      1 @TIMECARD_LIB.TIMECARD(SCH_1):XP12R0V_A_FLTB

TP_PIONT-TP010CT020B030_PTH-TPA  I1684  TP46
   1 FPGA_CFG_INIT_N      1 @TIMECARD_LIB.TIMECARD(SCH_1):FPGA_CFG_INIT_N

TP_PIONT-TP010CT020B030_PTH-TPA  I1689  TP44
   1 FPGA_DONE      1 @TIMECARD_LIB.TIMECARD(SCH_1):FPGA_DONE

TP_PIONT-TP010CT020B030_PTH-TPA  I1690  TP45
   1 FPGA_PROGRAM_N      1 @TIMECARD_LIB.TIMECARD(SCH_1):FPGA_PROGRAM_N

TP_PIONT-TP010CT020B030_PTH-TPA  I1691  TP43
   1 XP12R0V_A_EN      1 @TIMECARD_LIB.TIMECARD(SCH_1):XP12R0V_A_EN

TP_PIONT-TP010CT020B030_PTH-TPA  I1693  TP47
   1 FPGA_MGTRREF      1 @TIMECARD_LIB.TIMECARD(SCH_1):FPGA_MGTRREF

TP_PIONT-TP010CT020B030_PTH-TPA  I1695  TP48
   1 PCIE_CONN_PERST_N      1 @TIMECARD_LIB.TIMECARD(SCH_1):PCIE_CONN_PERST_N

TP_PIONT-TP010CT020B030_PTH-TPA  I1699  TP49
   1 CLK_200M_OE      1 @TIMECARD_LIB.TIMECARD(SCH_1):CLK_200M_OE

TP_PIONT-TP010CT020B030_PTH-TPA  I1701  TP50
   1 CLK_125M_OE      1 @TIMECARD_LIB.TIMECARD(SCH_1):CLK_125M_OE

TP_PIONT-TP010CT020B030_PTH-TPA  I1704  TP51
   1 MAC_ALARM      1 @TIMECARD_LIB.TIMECARD(SCH_1):MAC_ALARM

TP_PIONT-TP010CT020B030_PTH-TPA  I1705  TP62
   1 R_MAC_BITEOUT      1 @TIMECARD_LIB.TIMECARD(SCH_1):R_MAC_BITE OUT

RESISTOR-G155-133R0-01,33OHM,1%  I1706  R430
   2 UNNAMED_16_CONNHDR2X6FSSMT_I161      2 @TIMECARD_LIB.TIMECARD(SCH_1):UNNAMED_16_CONNHDR2X6FSSMT_I1614_1
   1 FPGA_IO_4      1 @TIMECARD_LIB.TIMECARD(SCH_1):FPGA_IO_4

RESISTOR-G155-133R0-01,33OHM,1%  I1707  R329
   2 UNNAMED_16_CONNHDR2X6FSSMT_I1_4      2 @TIMECARD_LIB.TIMECARD(SCH_1):UNNAMED_16_CONNHDR2X6FSSMT_I1614_7
   1 FPGA_IO_7      1 @TIMECARD_LIB.TIMECARD(SCH_1):FPGA_IO_7

RESISTOR-G155-133R0-01,33OHM,1%  I1708  R428
   2 UNNAMED_16_CONNHDR2X6FSSMT_I1_6      2 @TIMECARD_LIB.TIMECARD(SCH_1):UNNAMED_16_CONNHDR2X6FSSMT_I1614_5
   1 FPGA_IO_6      1 @TIMECARD_LIB.TIMECARD(SCH_1):FPGA_IO_6

RESISTOR-G155-133R0-01,33OHM,1%  I1709  R429
   2 UNNAMED_16_CONNHDR2X6FSSMT_I1_2      2 @TIMECARD_LIB.TIMECARD(SCH_1):UNNAMED_16_CONNHDR2X6FSSMT_I1614_3
   1 FPGA_IO_5      1 @TIMECARD_LIB.TIMECARD(SCH_1):FPGA_IO_5

RESISTOR-G155-133R0-01,33OHM,1%  I1718  R431
   2 FPGA_IO_3      2 @TIMECARD_LIB.TIMECARD(SCH_1):FPGA_IO_3
   1 UNNAMED_16_CONNHDR2X6FSSMT_I1_5      1 @TIMECARD_LIB.TIMECARD(SCH_1):UNNAMED_16_CONNHDR2X6FSSMT_I1614_8

RESISTOR-G155-133R0-01,33OHM,1%  I1719  R432
   2 FPGA_IO_2      2 @TIMECARD_LIB.TIMECARD(SCH_1):FPGA_IO_2
   1 UNNAMED_16_CONNHDR2X6FSSMT_I1_7      1 @TIMECARD_LIB.TIMECARD(SCH_1):UNNAMED_16_CONNHDR2X6FSSMT_I1614_6

RESISTOR-G155-133R0-01,33OHM,1%  I1720  R433
   2 FPGA_IO_1      2 @TIMECARD_LIB.TIMECARD(SCH_1):FPGA_IO_1
   1 UNNAMED_16_CONNHDR2X6FSSMT_I1_3      1 @TIMECARD_LIB.TIMECARD(SCH_1):UNNAMED_16_CONNHDR2X6FSSMT_I1614_4

RESISTOR-G155-133R0-01,33OHM,1%  I1721  R434
   2 FPGA_IO_0      2 @TIMECARD_LIB.TIMECARD(SCH_1):FPGA_IO_0
   1 UNNAMED_16_CONNHDR2X6FSSMT_I1_1      1 @TIMECARD_LIB.TIMECARD(SCH_1):UNNAMED_16_CONNHDR2X6FSSMT_I1614_2


DRAWING: @TIMECARD_LIB.TIMECARD(SCH_1):PAGE7 

RESISTOR-G155-14701-01,4.7KOHMA  I3  R64
   2 SHT3X_I2C_SDA      2 @TIMECARD_LIB.TIMECARD(SCH_1):SHT3X_I2C_SDA
   1 XP3R3V_FPGA      1 @TIMECARD_LIB.TIMECARD(SCH_1):XP3R3V_FPGA

RESISTOR-G155-14701-01,4.7KOHMA  I4  R65
   2 SHT3X_I2C_SCL      2 @TIMECARD_LIB.TIMECARD(SCH_1):SHT3X_I2C_SCL
   1 XP3R3V_FPGA      1 @TIMECARD_LIB.TIMECARD(SCH_1):XP3R3V_FPGA

RESISTOR-G155-11001-01,1KOHM,1%  I7  R69
   2     SG      2 @TIMECARD_LIB.TIMECARD(SCH_1):SG
   1 SHT3X_ADDR      1 @TIMECARD_LIB.TIMECARD(SCH_1):SHT3X_ADDR

RESISTOR-G155-14701-01,4.7KOHMA  I8  R68
   2 SHT3X_ADDR      2 @TIMECARD_LIB.TIMECARD(SCH_1):SHT3X_ADDR
   1 XP3R3V_FPGA      1 @TIMECARD_LIB.TIMECARD(SCH_1):XP3R3V_FPGA

RESISTOR-G155-133R0-01,33OHM,1%  I13  R67
   2 R_SHT3X_I2C_SCL      2 @TIMECARD_LIB.TIMECARD(SCH_1):R_SHT3X_I2C_SCL
   1 SHT3X_I2C_SCL      1 @TIMECARD_LIB.TIMECARD(SCH_1):SHT3X_I2C_SCL

RESISTOR-G155-133R0-01,33OHM,1%  I14  R66
   2 R_SHT3X_I2C_SDA      2 @TIMECARD_LIB.TIMECARD(SCH_1):R_SHT3X_I2C_SDA
   1 SHT3X_I2C_SDA      1 @TIMECARD_LIB.TIMECARD(SCH_1):SHT3X_I2C_SDA

CAPACITOR-G105-0B104-EK,0.1UF,A  I18  C40
   1 XP3R3V_FPGA      1 @TIMECARD_LIB.TIMECARD(SCH_1):XP3R3V_FPGA
   2     SG      2 @TIMECARD_LIB.TIMECARD(SCH_1):SG

CAPACITOR-G105-0B104-EK,0.1UF,A  I19  C275
   1 VDD3V3_SHT31A      1 @TIMECARD_LIB.TIMECARD(SCH_1):VDD3V3_SHT31A
   2     SG      2 @TIMECARD_LIB.TIMECARD(SCH_1):SG

FERRITEBEAD-G191-10097-01,600OA  I21  L17
   1 XP3R3V_FPGA      1 @TIMECARD_LIB.TIMECARD(SCH_1):XP3R3V_FPGA
   2 VDD3V3_SHT31A      2 @TIMECARD_LIB.TIMECARD(SCH_1):VDD3V3_SHT31A

CAPACITOR-G105-0C106-BM,10UF,2A  I23  C274
   1 VDD3V3_SHT31A      1 @TIMECARD_LIB.TIMECARD(SCH_1):VDD3V3_SHT31A
   2     SG      2 @TIMECARD_LIB.TIMECARD(SCH_1):SG

RESISTOR-G155-133R0-01,33OHM,1%  I33  R298
   2 FPGA_OUT_SHT3X_RST_N      2 @TIMECARD_LIB.TIMECARD(SCH_1):FPGA_OUT_SHT3X_RST_N
   1 R_SHT3X_RST_N      1 @TIMECARD_LIB.TIMECARD(SCH_1):R_SHT3X_RST_N

RESISTOR-G155-14701-01,4.7KOHMA  I38  R296
   2 R_SHT3X_RST_N      2 @TIMECARD_LIB.TIMECARD(SCH_1):R_SHT3X_RST_N
   1 XP3R3V_FPGA      1 @TIMECARD_LIB.TIMECARD(SCH_1):XP3R3V_FPGA

RESISTOR-G155-14701-01,4.7KOHMA  I39  R297
   2     SG      2 @TIMECARD_LIB.TIMECARD(SCH_1):SG
   1 R_SHT3X_RST_N      1 @TIMECARD_LIB.TIMECARD(SCH_1):R_SHT3X_RST_N

RESISTOR-G155-133R0-01,33OHM,1%  I40  R299
   2 FPGA_IN_SHT3X_ALERT_N      2 @TIMECARD_LIB.TIMECARD(SCH_1):FPGA_IN_SHT3X_ALERT_N
   1 R_SHT3X_ALERT_N      1 @TIMECARD_LIB.TIMECARD(SCH_1):R_SHT3X_ALERT_N

RESISTOR-G155-14701-01,4.7KOHMA  I41  R300
   2 FPGA_IN_SHT3X_ALERT_N      2 @TIMECARD_LIB.TIMECARD(SCH_1):FPGA_IN_SHT3X_ALERT_N
   1 XP3R3V_FPGA      1 @TIMECARD_LIB.TIMECARD(SCH_1):XP3R3V_FPGA

SHT31A_DIS_B10KS_DFN8-A222-000A  I44  U27
   1 R_SHT3X_I2C_SDA    SDA @TIMECARD_LIB.TIMECARD(SCH_1):R_SHT3X_I2C_SDA
   2 SHT3X_ADDR   ADDR @TIMECARD_LIB.TIMECARD(SCH_1):SHT3X_ADDR
   3 R_SHT3X_ALERT_N  ALERT @TIMECARD_LIB.TIMECARD(SCH_1):R_SHT3X_ALERT_N
   4 R_SHT3X_I2C_SCL    SCL @TIMECARD_LIB.TIMECARD(SCH_1):R_SHT3X_I2C_SCL
   5 VDD3V3_SHT31A    VDD @TIMECARD_LIB.TIMECARD(SCH_1):VDD3V3_SHT31A
   6 R_SHT3X_RST_N RESET* @TIMECARD_LIB.TIMECARD(SCH_1):R_SHT3X_RST_N
   7     SG      R @TIMECARD_LIB.TIMECARD(SCH_1):SG
   8     SG    VSS @TIMECARD_LIB.TIMECARD(SCH_1):SG
   9     SG THRM_PAD @TIMECARD_LIB.TIMECARD(SCH_1):SG


DRAWING: @TIMECARD_LIB.TIMECARD(SCH_1):PAGE11 

RESISTOR-G155-133R0-01,33OHM,1%  I5  R111
   2 GPSTP2_OUT      2 @TIMECARD_LIB.TIMECARD(SCH_1):GPSTP2_OUT
   1 FPGA_IN_GPSTP2_OUT      1 @TIMECARD_LIB.TIMECARD(SCH_1):FPGA_IN_GPSTP2_OUT

RESISTOR-G155-133R0-01,33OHM,1%  I7  R113
   2 GPS_UART_RXD      2 @TIMECARD_LIB.TIMECARD(SCH_1):GPS_UART_RXD
   1 DBG_UART_GPS_RXD      1 @TIMECARD_LIB.TIMECARD(SCH_1):DBG_UART_GPS_RXD

RESISTOR-G155-133R0-01,33OHM,1%  I8  R112
   2 GPS_UART_TXD      2 @TIMECARD_LIB.TIMECARD(SCH_1):GPS_UART_TXD
   1 DBG_UART_GPS_TXD      1 @TIMECARD_LIB.TIMECARD(SCH_1):DBG_UART_GPS_TXD

RESISTOR-G155-133R0-01,33OHM,1%  I11  R109
   2 GPS_UART_TXD      2 @TIMECARD_LIB.TIMECARD(SCH_1):GPS_UART_TXD
   1 UART_GPS_TX_FPGA_RX      1 @TIMECARD_LIB.TIMECARD(SCH_1):UART_GPS_TX_FPGA_RX

CAPACITOR-G107-0F106-EM,10UF,2A  I12  C72
   1 XP5R0V_VCC_ANT      1 @TIMECARD_LIB.TIMECARD(SCH_1):XP5R0V_VCC_ANT
   2     SG      2 @TIMECARD_LIB.TIMECARD(SCH_1):SG

CAPACITOR-G105-0B104-EK,0.1UF,A  I13  C73
   1 XP5R0V_VCC_ANT      1 @TIMECARD_LIB.TIMECARD(SCH_1):XP5R0V_VCC_ANT
   2     SG      2 @TIMECARD_LIB.TIMECARD(SCH_1):SG

CAPACITOR-G105-0B104-EK,0.1UF,A  I15  C78
   1 XP5R0V_VCC_ANT      1 @TIMECARD_LIB.TIMECARD(SCH_1):XP5R0V_VCC_ANT
   2     SG      2 @TIMECARD_LIB.TIMECARD(SCH_1):SG

RESISTOR-G155-14701-01,4.7KOHMA  I18  R114
   2     SG      2 @TIMECARD_LIB.TIMECARD(SCH_1):SG
   1 GPS_RST_N      1 @TIMECARD_LIB.TIMECARD(SCH_1):GPS_RST_N

RESISTOR-G155-133R0-01,33OHM,1%  I20  R117
   2 FPGA_IN_GPSTP1_OUT      2 @TIMECARD_LIB.TIMECARD(SCH_1):FPGA_IN_GPSTP1_OUT
   1 GPSTP1_OUT      1 @TIMECARD_LIB.TIMECARD(SCH_1):GPSTP1_OUT

RESISTOR-G155-14701-01,4.7KOHMA  I21  R115
   2 GPS_RST_N      2 @TIMECARD_LIB.TIMECARD(SCH_1):GPS_RST_N
   1 XP3R3V_GPS      1 @TIMECARD_LIB.TIMECARD(SCH_1):XP3R3V_GPS

CAPACITOR-G107-0F106-EM,10UF,2A  I24  C79
   1 XP3R3V_GPS      1 @TIMECARD_LIB.TIMECARD(SCH_1):XP3R3V_GPS
   2     SG      2 @TIMECARD_LIB.TIMECARD(SCH_1):SG

RESISTOR-G155-133R0-01,33OHM,1%  I25  R116
   2 FPGA_OUT_GPS_RST_N      2 @TIMECARD_LIB.TIMECARD(SCH_1):FPGA_OUT_GPS_RST_N
   1 GPS_RST_N      1 @TIMECARD_LIB.TIMECARD(SCH_1):GPS_RST_N

CAPACITOR-G105-0B104-CK,0.1UF,A  I26  C80
   1 XP3R3V_GPS      1 @TIMECARD_LIB.TIMECARD(SCH_1):XP3R3V_GPS
   2     SG      2 @TIMECARD_LIB.TIMECARD(SCH_1):SG

RESISTOR-G155-133R0-01,33OHM,1%  I29  R110
   2 GPS_UART_RXD      2 @TIMECARD_LIB.TIMECARD(SCH_1):GPS_UART_RXD
   1 UART_GPS_RX_FPGA_TX      1 @TIMECARD_LIB.TIMECARD(SCH_1):UART_GPS_RX_FPGA_TX

CONN_HDR_2X4_F_S_SMT-G200-1307A  I36  P2
   1 XP5R0V_VCC_ANT      1 @TIMECARD_LIB.TIMECARD(SCH_1):XP5R0V_VCC_ANT
   2 XP3R3V_GPS      2 @TIMECARD_LIB.TIMECARD(SCH_1):XP3R3V_GPS
   3 GPS_UART_TXD      3 @TIMECARD_LIB.TIMECARD(SCH_1):GPS_UART_TXD
   4 GPS_RST_N      4 @TIMECARD_LIB.TIMECARD(SCH_1):GPS_RST_N
   5 GPS_UART_RXD      5 @TIMECARD_LIB.TIMECARD(SCH_1):GPS_UART_RXD
   6 GPSTP1_OUT      6 @TIMECARD_LIB.TIMECARD(SCH_1):GPSTP1_OUT
   7 GPSTP2_OUT      7 @TIMECARD_LIB.TIMECARD(SCH_1):GPSTP2_OUT
   8     SG      8 @TIMECARD_LIB.TIMECARD(SCH_1):SG

RESISTOR-G155-11003-01,100KOHMA  I38  R268
   2 GPS_UART_RXD      2 @TIMECARD_LIB.TIMECARD(SCH_1):GPS_UART_RXD
   1 XP3R3V_FPGA      1 @TIMECARD_LIB.TIMECARD(SCH_1):XP3R3V_FPGA

RESISTOR-G155-11003-01,100KOHMA  I40  R269
   2 UART_GPS_TX_FPGA_RX      2 @TIMECARD_LIB.TIMECARD(SCH_1):UART_GPS_TX_FPGA_RX
   1 XP3R3V_FPGA      1 @TIMECARD_LIB.TIMECARD(SCH_1):XP3R3V_FPGA

CAPACITOR-G105-0B104-CK,0.1UF,A  I43  C81
   1 XP3R3V_FPGA      1 @TIMECARD_LIB.TIMECARD(SCH_1):XP3R3V_FPGA
   2     SG      2 @TIMECARD_LIB.TIMECARD(SCH_1):SG

CAPACITOR-G105-0B104-EK,0.1UF,A  I44  C272
   1 XP5R0V      1 @TIMECARD_LIB.TIMECARD(SCH_1):XP5R0V
   2     SG      2 @TIMECARD_LIB.TIMECARD(SCH_1):SG

CAPACITOR-G105-0B104-CK,0.1UF,A  I45  C273
   1 XP3R3V_GPS      1 @TIMECARD_LIB.TIMECARD(SCH_1):XP3R3V_GPS
   2     SG      2 @TIMECARD_LIB.TIMECARD(SCH_1):SG

FERRITEBEAD-G191-10100-01,120OA  I55  L16
   1 XP3R3V_GPS      1 @TIMECARD_LIB.TIMECARD(SCH_1):XP3R3V_GPS
   2 XP3R3V_FPGA      2 @TIMECARD_LIB.TIMECARD(SCH_1):XP3R3V_FPGA

FERRITEBEAD-G191-10100-01,120OA  I56  L15
   1 XP5R0V      1 @TIMECARD_LIB.TIMECARD(SCH_1):XP5R0V
   2 XP5R0V_VCC_ANT      2 @TIMECARD_LIB.TIMECARD(SCH_1):XP5R0V_VCC_ANT


DRAWING: @TIMECARD_LIB.TIMECARD(SCH_1):PAGE68 

RESISTOR-G155-11002-01,10KOHM,A  I2  R165
   2     SG      2 @TIMECARD_LIB.TIMECARD(SCH_1):SG
   1 XP1R2V_EN_R      1 @TIMECARD_LIB.TIMECARD(SCH_1):XP1R2V_EN_R

CAPACITOR-G105-0B104-EK,0.1UF,A  I3  C184
   1 XP1R2V_EN_R      1 @TIMECARD_LIB.TIMECARD(SCH_1):XP1R2V_EN_R
   2     SG      2 @TIMECARD_LIB.TIMECARD(SCH_1):SG

CAPACITOR-G104-0B103-EK,0.01UFA  I5  C190
   1 XP1R2V_SS      1 @TIMECARD_LIB.TIMECARD(SCH_1):XP1R2V_SS
   2     SG      2 @TIMECARD_LIB.TIMECARD(SCH_1):SG

ISL80101IRAJZ_DFN10-G222-10136A  I6  U20
   1 XP1R2V_FPGA VOUT_1 @TIMECARD_LIB.TIMECARD(SCH_1):XP1R2V_FPGA
   2 XP1R2V_FPGA VOUT_2 @TIMECARD_LIB.TIMECARD(SCH_1):XP1R2V_FPGA
   3 XP1R2V_FB SENSE/ADJ @TIMECARD_LIB.TIMECARD(SCH_1):XP1R2V_FB
   4 XP1R2V_PG_R     PG @TIMECARD_LIB.TIMECARD(SCH_1):XP1R2V_PG_R
   5     SG    GND @TIMECARD_LIB.TIMECARD(SCH_1):SG
   6 XP1R2V_SS     SS @TIMECARD_LIB.TIMECARD(SCH_1):XP1R2V_SS
   7 XP1R2V_EN_R ENABLE @TIMECARD_LIB.TIMECARD(SCH_1):XP1R2V_EN_R
   8     NC     NC     NC
   9 XP1R2V_VIN  VIN_1 @TIMECARD_LIB.TIMECARD(SCH_1):XP1R2V_VIN
  10 XP1R2V_VIN  VIN_2 @TIMECARD_LIB.TIMECARD(SCH_1):XP1R2V_VIN
  11     SG THRM_PAD @TIMECARD_LIB.TIMECARD(SCH_1):SG

CAPACITOR-G104-0B103-EK,0.01UFA  I9  C192
   1 XP1R2V_PG_R      1 @TIMECARD_LIB.TIMECARD(SCH_1):XP1R2V_PG_R
   2     SG      2 @TIMECARD_LIB.TIMECARD(SCH_1):SG

RESISTOR-G155-100R0-J0,0OHM,-  I10  R181
   2 XP1R2V_FPGA_PG      2 @TIMECARD_LIB.TIMECARD(SCH_1):XP1R2V_FPGA_PG
   1 XP1R2V_PG_R      1 @TIMECARD_LIB.TIMECARD(SCH_1):XP1R2V_PG_R

RESISTOR-G155-14701-01,4.7KOHMA  I11  R178
   2 XP1R2V_PG_R      2 @TIMECARD_LIB.TIMECARD(SCH_1):XP1R2V_PG_R
   1 XP3R3V      1 @TIMECARD_LIB.TIMECARD(SCH_1):XP3R3V

RESISTOR-G155-03001-01,3KOHM,1%  I14  R186
   2 XP1R2V_FB      2 @TIMECARD_LIB.TIMECARD(SCH_1):XP1R2V_FB
   1     SG      1 @TIMECARD_LIB.TIMECARD(SCH_1):SG

RESISTOR-G155-03241-01,3.24KOHA  I16  R189
   2 XP1R2V_FB      2 @TIMECARD_LIB.TIMECARD(SCH_1):XP1R2V_FB
   1     SG      1 @TIMECARD_LIB.TIMECARD(SCH_1):SG

RESISTOR-G155-100R0-J0,0OHM,-  I18  R140
   2 XP1R2V_EN_R      2 @TIMECARD_LIB.TIMECARD(SCH_1):XP1R2V_EN_R
   1 XP1R0V_FPGA_PG      1 @TIMECARD_LIB.TIMECARD(SCH_1):XP1R0V_FPGA_PG

FERRITEBEAD-G191-10101-01,26OHA  I25  L11
   1 XP3R3V      1 @TIMECARD_LIB.TIMECARD(SCH_1):XP3R3V
   2 XP1R2V_VIN      2 @TIMECARD_LIB.TIMECARD(SCH_1):XP1R2V_VIN

RESISTOR-G152-00055-01,1.13KOHA  I26  R177
   2 XP1R2V_EN_R      2 @TIMECARD_LIB.TIMECARD(SCH_1):XP1R2V_EN_R
   1 XP1R2V_VIN      1 @TIMECARD_LIB.TIMECARD(SCH_1):XP1R2V_VIN

CAPACITOR-G107-0F106-EM,10UF,2A  I27  C185
   1 XP1R2V_VIN      1 @TIMECARD_LIB.TIMECARD(SCH_1):XP1R2V_VIN
   2     SG      2 @TIMECARD_LIB.TIMECARD(SCH_1):SG

CAPACITOR-G105-0B104-EK,0.1UF,A  I35  C188
   1 XP1R2V_VIN      1 @TIMECARD_LIB.TIMECARD(SCH_1):XP1R2V_VIN
   2     SG      2 @TIMECARD_LIB.TIMECARD(SCH_1):SG

RESISTOR-G155-100R0-J0,0OHM,-  I42  R141
   2 XP1R8V_EN_R      2 @TIMECARD_LIB.TIMECARD(SCH_1):XP1R8V_EN_R
   1 XP1R2V_FPGA_PG      1 @TIMECARD_LIB.TIMECARD(SCH_1):XP1R2V_FPGA_PG

FERRITEBEAD-G191-10101-01,26OHA  I43  L6
   1 XP3R3V      1 @TIMECARD_LIB.TIMECARD(SCH_1):XP3R3V
   2 XP1R8V_VIN      2 @TIMECARD_LIB.TIMECARD(SCH_1):XP1R8V_VIN

RESISTOR-G155-11002-01,10KOHM,A  I44  R174
   2     SG      2 @TIMECARD_LIB.TIMECARD(SCH_1):SG
   1 XP1R8V_EN_R      1 @TIMECARD_LIB.TIMECARD(SCH_1):XP1R8V_EN_R

RESISTOR-G152-00055-01,1.13KOHA  I45  R166
   2 XP1R8V_EN_R      2 @TIMECARD_LIB.TIMECARD(SCH_1):XP1R8V_EN_R
   1 XP1R8V_VIN      1 @TIMECARD_LIB.TIMECARD(SCH_1):XP1R8V_VIN

CAPACITOR-G105-0B104-EK,0.1UF,A  I46  C187
   1 XP1R8V_EN_R      1 @TIMECARD_LIB.TIMECARD(SCH_1):XP1R8V_EN_R
   2     SG      2 @TIMECARD_LIB.TIMECARD(SCH_1):SG

CAPACITOR-G107-0F106-EM,10UF,2A  I47  C186
   1 XP1R8V_VIN      1 @TIMECARD_LIB.TIMECARD(SCH_1):XP1R8V_VIN
   2     SG      2 @TIMECARD_LIB.TIMECARD(SCH_1):SG

CAPACITOR-G104-0B103-EK,0.01UFA  I49  C191
   1 XP1R8V_SS      1 @TIMECARD_LIB.TIMECARD(SCH_1):XP1R8V_SS
   2     SG      2 @TIMECARD_LIB.TIMECARD(SCH_1):SG

CAPACITOR-G105-0B104-EK,0.1UF,A  I51  C189
   1 XP1R8V_VIN      1 @TIMECARD_LIB.TIMECARD(SCH_1):XP1R8V_VIN
   2     SG      2 @TIMECARD_LIB.TIMECARD(SCH_1):SG

ISL80101IRAJZ_DFN10-G222-10136A  I52  U21
   1 XP1R8V_FPGA VOUT_1 @TIMECARD_LIB.TIMECARD(SCH_1):XP1R8V_FPGA
   2 XP1R8V_FPGA VOUT_2 @TIMECARD_LIB.TIMECARD(SCH_1):XP1R8V_FPGA
   3 XP1R8V_FB SENSE/ADJ @TIMECARD_LIB.TIMECARD(SCH_1):XP1R8V_FB
   4 XP1R8V_PG_R     PG @TIMECARD_LIB.TIMECARD(SCH_1):XP1R8V_PG_R
   5     SG    GND @TIMECARD_LIB.TIMECARD(SCH_1):SG
   6 XP1R8V_SS     SS @TIMECARD_LIB.TIMECARD(SCH_1):XP1R8V_SS
   7 XP1R8V_EN_R ENABLE @TIMECARD_LIB.TIMECARD(SCH_1):XP1R8V_EN_R
   8     NC     NC     NC
   9 XP1R8V_VIN  VIN_1 @TIMECARD_LIB.TIMECARD(SCH_1):XP1R8V_VIN
  10 XP1R8V_VIN  VIN_2 @TIMECARD_LIB.TIMECARD(SCH_1):XP1R8V_VIN
  11     SG THRM_PAD @TIMECARD_LIB.TIMECARD(SCH_1):SG

RESISTOR-G155-04221-01,4.22KOHA  I59  R185
   2 XP1R2V_FB      2 @TIMECARD_LIB.TIMECARD(SCH_1):XP1R2V_FB
   1 XP1R2V_FPGA      1 @TIMECARD_LIB.TIMECARD(SCH_1):XP1R2V_FPGA

CAPACITOR-G107-0F106-EM,10UF,2A  I60  C194
   1 XP1R2V_FPGA      1 @TIMECARD_LIB.TIMECARD(SCH_1):XP1R2V_FPGA
   2     SG      2 @TIMECARD_LIB.TIMECARD(SCH_1):SG

CAPACITOR-G105-0B104-EK,0.1UF,A  I61  C196
   1 XP1R2V_FPGA      1 @TIMECARD_LIB.TIMECARD(SCH_1):XP1R2V_FPGA
   2     SG      2 @TIMECARD_LIB.TIMECARD(SCH_1):SG

CAPACITOR-G104-0B103-EK,0.01UFA  I71  C193
   1 XP1R8V_PG_R      1 @TIMECARD_LIB.TIMECARD(SCH_1):XP1R8V_PG_R
   2     SG      2 @TIMECARD_LIB.TIMECARD(SCH_1):SG

RESISTOR-G155-14701-01,4.7KOHMA  I73  R179
   2 XP1R8V_PG_R      2 @TIMECARD_LIB.TIMECARD(SCH_1):XP1R8V_PG_R
   1 XP3R3V      1 @TIMECARD_LIB.TIMECARD(SCH_1):XP3R3V

RESISTOR-G155-100R0-J0,0OHM,-  I74  R182
   2 XP1R8V_FPGA_PG      2 @TIMECARD_LIB.TIMECARD(SCH_1):XP1R8V_FPGA_PG
   1 XP1R8V_PG_R      1 @TIMECARD_LIB.TIMECARD(SCH_1):XP1R8V_PG_R

RESISTOR-G155-04221-01,4.22KOHA  I78  R187
   2 XP1R8V_FB      2 @TIMECARD_LIB.TIMECARD(SCH_1):XP1R8V_FB
   1 XP1R8V_FPGA      1 @TIMECARD_LIB.TIMECARD(SCH_1):XP1R8V_FPGA

RESISTOR-G155-03241-01,3.24KOHA  I79  R188
   2 XP1R8V_FB      2 @TIMECARD_LIB.TIMECARD(SCH_1):XP1R8V_FB
   1     SG      1 @TIMECARD_LIB.TIMECARD(SCH_1):SG

RESISTOR-G155-03241-01,3.24KOHA  I80  R190
   2 XP1R8V_FB      2 @TIMECARD_LIB.TIMECARD(SCH_1):XP1R8V_FB
   1     SG      1 @TIMECARD_LIB.TIMECARD(SCH_1):SG

CAPACITOR-G107-0F106-EM,10UF,2A  I81  C195
   1 XP1R8V_FPGA      1 @TIMECARD_LIB.TIMECARD(SCH_1):XP1R8V_FPGA
   2     SG      2 @TIMECARD_LIB.TIMECARD(SCH_1):SG

CAPACITOR-G105-0B104-EK,0.1UF,A  I83  C197
   1 XP1R8V_FPGA      1 @TIMECARD_LIB.TIMECARD(SCH_1):XP1R8V_FPGA
   2     SG      2 @TIMECARD_LIB.TIMECARD(SCH_1):SG

CAPACITOR-G107-0F226-CM,22UF,2A  I93  C180
   1 XP3R3V      1 @TIMECARD_LIB.TIMECARD(SCH_1):XP3R3V
   2     SG      2 @TIMECARD_LIB.TIMECARD(SCH_1):SG

CAPACITOR-G105-0B104-EK,0.1UF,A  I94  C182
   1 XP3R3V      1 @TIMECARD_LIB.TIMECARD(SCH_1):XP3R3V
   2     SG      2 @TIMECARD_LIB.TIMECARD(SCH_1):SG

CAPACITOR-G107-0F226-CM,22UF,2A  I97  C181
   1 XP3R3V      1 @TIMECARD_LIB.TIMECARD(SCH_1):XP3R3V
   2     SG      2 @TIMECARD_LIB.TIMECARD(SCH_1):SG

CAPACITOR-G105-0B104-EK,0.1UF,A  I98  C183
   1 XP3R3V      1 @TIMECARD_LIB.TIMECARD(SCH_1):XP3R3V
   2     SG      2 @TIMECARD_LIB.TIMECARD(SCH_1):SG


DRAWING: @TIMECARD_LIB.TIMECARD(SCH_1):PAGE161 

XC7A200T_2FBG484C_FBG484-G240-A  I2  U24
 Y17     NC IO_0_13     NC
 P20 UART_GPS_RX_FPGA_TX IO_0_14 @TIMECARD_LIB.TIMECARD(SCH_1):UART_GPS_RX_FPGA_TX
 N15 UART_GPS_TX_FPGA_RX IO_25_14 @TIMECARD_LIB.TIMECARD(SCH_1):UART_GPS_TX_FPGA_RX
AA16     NC IO_L1N_T0_13     NC
 R22 FPGA_D01 IO_L1N_T0_D01_DIN_14 @TIMECARD_LIB.TIMECARD(SCH_1):FPGA_D01
 Y16 FPGA_OUT_GPS_RST_N IO_L1P_T0_13 @TIMECARD_LIB.TIMECARD(SCH_1):FPGA_OUT_GPS_RST_N
 P22 FPGA_D00_MOSI IO_L1P_T0_D00_MOSI_14 @TIMECARD_LIB.TIMECARD(SCH_1):FPGA_D00_MOSI
AB17 FPGA_EEPROM_I2C_SDA IO_L2N_T0_13 @TIMECARD_LIB.TIMECARD(SCH_1):FPGA_EEPROM_I2C_SDA
 R21 FPGA_D03 IO_L2N_T0_D03_14 @TIMECARD_LIB.TIMECARD(SCH_1):FPGA_D03
AB16 FPGA_EEPROM_I2C_SCL IO_L2P_T0_13 @TIMECARD_LIB.TIMECARD(SCH_1):FPGA_EEPROM_I2C_SCL
 P21 FPGA_D02 IO_L2P_T0_D02_14 @TIMECARD_LIB.TIMECARD(SCH_1):FPGA_D02
AB13 FPGA_OUT_SEC_EEPROM_WP IO_L3N_T0_DQS_13 @TIMECARD_LIB.TIMECARD(SCH_1):FPGA_OUT_SEC_EEPROM_WP
 V22     NC IO_L3N_T0_DQS_EMCCLK_14     NC
AA13 FPGA_OUT_SN_EEPROM_WP IO_L3P_T0_DQS_13 @TIMECARD_LIB.TIMECARD(SCH_1):FPGA_OUT_SN_EEPROM_WP
 U22   PUDC IO_L3P_T0_DQS_PUDC_14* @TIMECARD_LIB.TIMECARD(SCH_1):PUDC
AB15     NC IO_L4N_T0_13     NC
 U21     NC IO_L4N_T0_D05_14     NC
AA15 FPGA_IO_FT_USBDET_RST_N IO_L4P_T0_13 @TIMECARD_LIB.TIMECARD(SCH_1):FPGA_IO_FT_USBDET_RST_N
 T21     NC IO_L4P_T0_D04_14     NC
AA14     NC IO_L5N_T0_13     NC
 R19     NC IO_L5N_T0_D07_14     NC
 Y13     NC IO_L5P_T0_13     NC
 P19     NC IO_L5P_T0_D06_14     NC
 T20     NC IO_L6N_T0_D08_VREF_14     NC
 Y14 FPGA_IN_GPSTP2_OUT IO_L6N_T0_VREF_13 @TIMECARD_LIB.TIMECARD(SCH_1):FPGA_IN_GPSTP2_OUT
 W14 FPGA_IN_GPSTP1_OUT IO_L6P_T0_13 @TIMECARD_LIB.TIMECARD(SCH_1):FPGA_IN_GPSTP1_OUT
 T19 FPGA_FCS_B IO_L6P_T0_FCS_B_14 @TIMECARD_LIB.TIMECARD(SCH_1):FPGA_FCS_B
AB12     NC IO_L7N_T1_13     NC
 W22     NC IO_L7N_T1_D10_14     NC
AB11     NC IO_L7P_T1_13     NC
 W21     NC IO_L7P_T1_D09_14     NC
AB10 FPGA_IN_MAC_ALARM_OUT_N IO_L8N_T1_13 @TIMECARD_LIB.TIMECARD(SCH_1):FPGA_IN_MAC_ALARM_OUT_N
AA21 ANT1_IN IO_L8N_T1_D12_14 @TIMECARD_LIB.TIMECARD(SCH_1):ANT1_IN
 AA9 FPGA_IN_MAC_BITEOUT IO_L8P_T1_13 @TIMECARD_LIB.TIMECARD(SCH_1):FPGA_IN_MAC_BITE OUT
AA20 ANT2_IN IO_L8P_T1_D11_14 @TIMECARD_LIB.TIMECARD(SCH_1):ANT2_IN
AA11     NC IO_L9N_T1_DQS_13     NC
 Y22     NC IO_L9N_T1_DQS_D13_14     NC
AA10     NC IO_L9P_T1_DQS_13     NC
 Y21     NC IO_L9P_T1_DQS_14     NC
 W10 ANT2_OUT IO_L10N_T1_13 @TIMECARD_LIB.TIMECARD(SCH_1):ANT2_OUT
AB22     NC IO_L10N_T1_D15_14     NC
 V10 ANT1_OUT IO_L10P_T1_13 @TIMECARD_LIB.TIMECARD(SCH_1):ANT1_OUT
AB21     NC IO_L10P_T1_D14_14     NC
 Y12 ANT4_IN IO_L11N_T1_SRCC_13 @TIMECARD_LIB.TIMECARD(SCH_1):ANT4_IN
 V20     NC IO_L11N_T1_SRCC_14     NC
 Y11 ANT3_IN IO_L11P_T1_SRCC_13 @TIMECARD_LIB.TIMECARD(SCH_1):ANT3_IN
 U20     NC IO_L11P_T1_SRCC_14     NC
 W12 ANT4_OUT IO_L12N_T1_MRCC_13 @TIMECARD_LIB.TIMECARD(SCH_1):ANT4_OUT
 W20 FPGA_M_RGB_LED_I2C_SCL IO_L12N_T1_MRCC_14 @TIMECARD_LIB.TIMECARD(SCH_1):FPGA_M_RGB_LED_I2C_SCL
 W11 ANT3_OUT IO_L12P_T1_MRCC_13 @TIMECARD_LIB.TIMECARD(SCH_1):ANT3_OUT
 W19 FPGA_M_RGB_LED_I2C_SDA IO_L12P_T1_MRCC_14 @TIMECARD_LIB.TIMECARD(SCH_1):FPGA_M_RGB_LED_I2C_SDA
 V14     NC IO_L13N_T2_MRCC_13     NC
 Y19     NC IO_L13N_T2_MRCC_14     NC
 V13 FPGA_IN_MAC_10MHZ_OUT IO_L13P_T2_MRCC_13 @TIMECARD_LIB.TIMECARD(SCH_1):FPGA_IN_MAC_10MHZ_OUT
 Y18 FPGA_OUT_RGB_LED_SHUTDOWN_N IO_L13P_T2_MRCC_14 @TIMECARD_LIB.TIMECARD(SCH_1):FPGA_OUT_RGB_LED_SHUTDOWN_N
 V15 FPGA_OUT_MACUSBPOWER_EN IO_L14N_T2_SRCC_13 @TIMECARD_LIB.TIMECARD(SCH_1):FPGA_OUT_MACUSBPOWER_EN
 V19     NC IO_L14N_T2_SRCC_14     NC
 U15     NC IO_L14P_T2_SRCC_13     NC
 V18     NC IO_L14P_T2_SRCC_14     NC
 T15     NC IO_L15N_T2_DQS_13     NC
AB20     NC IO_L15N_T2_DQS_DOUT_CSO_14*     NC
 T14     NC IO_L15P_T2_DQS_13     NC
AA19     NC IO_L15P_T2_DQS_RDWR_14*     NC
 W16     NC IO_L16N_T2_13     NC
 W17     NC IO_L16N_T2_A15_D31_14     NC
 W15     NC IO_L16P_T2_13     NC
 V17     NC IO_L16P_T2_CSI_14*     NC
 U16 FPGA_OUT_PCA9546_RST_N IO_L17N_T2_13 @TIMECARD_LIB.TIMECARD(SCH_1):FPGA_OUT_PCA9546_RST_N
AB18 UART_MAC_TX_FPGA_RX IO_L17N_T2_A13_D29_14 @TIMECARD_LIB.TIMECARD(SCH_1):UART_MAC_TX_FPGA_RX
 T16 FPGA_PCA9546_I2C_SDA IO_L17P_T2_13 @TIMECARD_LIB.TIMECARD(SCH_1):FPGA_PCA9546_I2C_SDA
AA18 UART_MAC_RX_FPGA_TX IO_L17P_T2_A14_D30_14 @TIMECARD_LIB.TIMECARD(SCH_1):UART_MAC_RX_FPGA_TX
 U18     NC IO_L18N_T2_A11_D27_14     NC
 U17     NC IO_L18P_T2_A12_D28_14     NC
 R14 MAC_USB_DM IO_L19N_T3_A09_D25_VREF_14 @TIMECARD_LIB.TIMECARD(SCH_1):MAC_USB_DM
 P14 MAC_USB_DP IO_L19P_T3_A10_D26_14 @TIMECARD_LIB.TIMECARD(SCH_1):MAC_USB_DP
 T18     NC IO_L20N_T3_A07_D23_14     NC
 R18     NC IO_L20P_T3_A08_D24_14     NC
 P17     NC IO_L21N_T3_DQS_A06_D22_14     NC
 N17 FPGA_PCA9546_I2C_SCL IO_L21P_T3_DQS_14 @TIMECARD_LIB.TIMECARD(SCH_1):FPGA_PCA9546_I2C_SCL
 R16     NC IO_L22N_T3_A04_D20_14     NC
 P15 UART_FT4232_RX_FPGA_TX IO_L22P_T3_A05_D21_14 @TIMECARD_LIB.TIMECARD(SCH_1):UART_FT4232_RX_FPGA_TX
 N14     NC IO_L23N_T3_A02_D18_14     NC
 N13     NC IO_L23P_T3_A03_D19_14     NC
 R17     NC IO_L24N_T3_A00_D16_14     NC
 P16 UART_FT4232_TX_FPGA_RX IO_L24P_T3_A01_D17_14 @TIMECARD_LIB.TIMECARD(SCH_1):UART_FT4232_TX_FPGA_RX

RESISTOR-G155-14701-01,4.7KOHMA  I140  R270
   2 FPGA_IN_GPSTP1_OUT      2 @TIMECARD_LIB.TIMECARD(SCH_1):FPGA_IN_GPSTP1_OUT
   1     SG      1 @TIMECARD_LIB.TIMECARD(SCH_1):SG

RESISTOR-G155-14701-01,4.7KOHMA  I200  R271
   2 FPGA_IN_GPSTP2_OUT      2 @TIMECARD_LIB.TIMECARD(SCH_1):FPGA_IN_GPSTP2_OUT
   1     SG      1 @TIMECARD_LIB.TIMECARD(SCH_1):SG

RESISTOR-G155-14701-01,4.7KOHMA  I201  R288
   2 FPGA_IN_MAC_BITEOUT      2 @TIMECARD_LIB.TIMECARD(SCH_1):FPGA_IN_MAC_BITE OUT
   1     SG      1 @TIMECARD_LIB.TIMECARD(SCH_1):SG

RESISTOR-G155-11502-01,15KOHM,A  I239  R437
   2 MAC_USB_DM      2 @TIMECARD_LIB.TIMECARD(SCH_1):MAC_USB_DM
   1     SG      1 @TIMECARD_LIB.TIMECARD(SCH_1):SG

RESISTOR-G155-11502-01,15KOHM,A  I240  R436
   2 MAC_USB_DP      2 @TIMECARD_LIB.TIMECARD(SCH_1):MAC_USB_DP
   1     SG      1 @TIMECARD_LIB.TIMECARD(SCH_1):SG

RESISTOR-G155-14701-01,4.7KOHMA  I241  R501
   2 ANT4_IN      2 @TIMECARD_LIB.TIMECARD(SCH_1):ANT4_IN
   1     SG      1 @TIMECARD_LIB.TIMECARD(SCH_1):SG

RESISTOR-G155-14701-01,4.7KOHMA  I242  R500
   2 ANT3_IN      2 @TIMECARD_LIB.TIMECARD(SCH_1):ANT3_IN
   1     SG      1 @TIMECARD_LIB.TIMECARD(SCH_1):SG

RESISTOR-G155-14701-01,4.7KOHMA  I244  R504
   2     SG      2 @TIMECARD_LIB.TIMECARD(SCH_1):SG
   1 ANT1_IN      1 @TIMECARD_LIB.TIMECARD(SCH_1):ANT1_IN

RESISTOR-G155-14701-01,4.7KOHMA  I246  R503
   2     SG      2 @TIMECARD_LIB.TIMECARD(SCH_1):SG
   1 ANT2_IN      1 @TIMECARD_LIB.TIMECARD(SCH_1):ANT2_IN

RESISTOR-G155-14701-01,4.7KOHMA  I247  R502
   2 FPGA_IN_MAC_10MHZ_OUT      2 @TIMECARD_LIB.TIMECARD(SCH_1):FPGA_IN_MAC_10MHZ_OUT
   1 XP3R3V_FPGA      1 @TIMECARD_LIB.TIMECARD(SCH_1):XP3R3V_FPGA

RESISTOR-G155-11003-01,100KOHMA  I251  R435
   2 XP3R3V_FPGA      2 @TIMECARD_LIB.TIMECARD(SCH_1):XP3R3V_FPGA
   1 FPGA_FLASH_DQ1_MISO      1 @TIMECARD_LIB.TIMECARD(SCH_1):FPGA_FLASH_DQ1_MISO

RESISTOR-G155-11001-01,1KOHM,1%  I252  R223
   2 XP3R3V_FPGA      2 @TIMECARD_LIB.TIMECARD(SCH_1):XP3R3V_FPGA
   1   PUDC      1 @TIMECARD_LIB.TIMECARD(SCH_1):PUDC

RESISTOR-G155-11001-01,1KOHM,1%  I253  R224
   2   PUDC      2 @TIMECARD_LIB.TIMECARD(SCH_1):PUDC
   1     SG      1 @TIMECARD_LIB.TIMECARD(SCH_1):SG

RESISTOR-G155-133R0-01,33OHM,1%  I258  R234
   2 FPGA_FLASH_DQ0_MOSI      2 @TIMECARD_LIB.TIMECARD(SCH_1):FPGA_FLASH_DQ0_MOSI
   1 FPGA_D00_MOSI      1 @TIMECARD_LIB.TIMECARD(SCH_1):FPGA_D00_MOSI

RESISTOR-G155-133R0-01,33OHM,1%  I259  R238
   2 FPGA_FLASH_DQ1_MISO      2 @TIMECARD_LIB.TIMECARD(SCH_1):FPGA_FLASH_DQ1_MISO
   1 FPGA_D01      1 @TIMECARD_LIB.TIMECARD(SCH_1):FPGA_D01

RESISTOR-G155-133R0-01,33OHM,1%  I260  R348
   2 FPGA_FLASH_DQ3      2 @TIMECARD_LIB.TIMECARD(SCH_1):FPGA_FLASH_DQ3
   1 FPGA_D03      1 @TIMECARD_LIB.TIMECARD(SCH_1):FPGA_D03

RESISTOR-G155-133R0-01,33OHM,1%  I261  R339
   2 FPGA_FLASH_DQ2      2 @TIMECARD_LIB.TIMECARD(SCH_1):FPGA_FLASH_DQ2
   1 FPGA_D02      1 @TIMECARD_LIB.TIMECARD(SCH_1):FPGA_D02

RESISTOR-G155-133R0-01,33OHM,1%  I263  R362
   2 FPGA_FLASH_CS_N      2 @TIMECARD_LIB.TIMECARD(SCH_1):FPGA_FLASH_CS_N
   1 FPGA_FCS_B      1 @TIMECARD_LIB.TIMECARD(SCH_1):FPGA_FCS_B


DRAWING: @TIMECARD_LIB.TIMECARD(SCH_1):PAGE162 

XC7A200T_2FBG484C_FBG484-G240-A  I228  U24
 J16     NC IO_0_15     NC
 F15     NC IO_0_16     NC
 M17     NC IO_25_15     NC
 F21     NC IO_25_16     NC
 F14 FPGA_OUT_SMA1_LED_GREEN_N IO_L1N_T0_16 @TIMECARD_LIB.TIMECARD(SCH_1):FPGA_OUT_SMA1_LED_GREEN_N
 G13 FPGA_OUT_MUX2_SEL IO_L1N_T0_AD0N_15 @TIMECARD_LIB.TIMECARD(SCH_1):FPGA_OUT_MUX2_SEL
 F13 FPGA_OUT_SMA1_LED_BLUE_N IO_L1P_T0_16 @TIMECARD_LIB.TIMECARD(SCH_1):FPGA_OUT_SMA1_LED_BLUE_N
 H13 FPGA_OUT_MUX1_SEL IO_L1P_T0_AD0P_15 @TIMECARD_LIB.TIMECARD(SCH_1):FPGA_OUT_MUX1_SEL
 E17     NC IO_L2N_T0_16     NC
 G16     NC IO_L2N_T0_AD8N_15     NC
 F16 FPGA_OUT_SMA1_LED_RED_N IO_L2P_T0_16 @TIMECARD_LIB.TIMECARD(SCH_1):FPGA_OUT_SMA1_LED_RED_N
 G15 FPGA_OUT_MUX3_SEL IO_L2P_T0_AD8P_15 @TIMECARD_LIB.TIMECARD(SCH_1):FPGA_OUT_MUX3_SEL
 C15 FPGA_OUT_SMA2_LED_GREEN_N IO_L3N_T0_DQS_16 @TIMECARD_LIB.TIMECARD(SCH_1):FPGA_OUT_SMA2_LED_GREEN_N
 H14 SMA4_SIG_OUT_BF_EN_N IO_L3N_T0_DQS_AD1N_15 @TIMECARD_LIB.TIMECARD(SCH_1):SMA4_SIG_OUT_BF_EN_N
 C14 FPGA_OUT_SMA2_LED_BLUE_N IO_L3P_T0_DQS_16 @TIMECARD_LIB.TIMECARD(SCH_1):FPGA_OUT_SMA2_LED_BLUE_N
 J14 SMA4_SIG_IN_BF_EN_N IO_L3P_T0_DQS_AD1P_15 @TIMECARD_LIB.TIMECARD(SCH_1):SMA4_SIG_IN_BF_EN_N
 G18     NC IO_L4N_T0_15     NC
 E14     NC IO_L4N_T0_16     NC
 G17     NC IO_L4P_T0_15     NC
 E13 FPGA_OUT_SMA2_LED_RED_N IO_L4P_T0_16 @TIMECARD_LIB.TIMECARD(SCH_1):FPGA_OUT_SMA2_LED_RED_N
 D16     NC IO_L5N_T0_16     NC
 H15 SMA3_SIG_IN_BF_EN_N IO_L5N_T0_AD9N_15 @TIMECARD_LIB.TIMECARD(SCH_1):SMA3_SIG_IN_BF_EN_N
 E16     NC IO_L5P_T0_16     NC
 J15 SMA3_SIG_OUT_BF_EN_N IO_L5P_T0_AD9P_15 @TIMECARD_LIB.TIMECARD(SCH_1):SMA3_SIG_OUT_BF_EN_N
 H18     NC IO_L6N_T0_VREF_15     NC
 D15 LED_DATOUT3 IO_L6N_T0_VREF_16 @TIMECARD_LIB.TIMECARD(SCH_1):LED_DATOUT3
 H17     NC IO_L6P_T0_15     NC
 D14 LED_DATOUT2 IO_L6P_T0_16 @TIMECARD_LIB.TIMECARD(SCH_1):LED_DATOUT2
 B16     NC IO_L7N_T1_16     NC
 H22 FPGA_IO_1 IO_L7N_T1_AD2N_15 @TIMECARD_LIB.TIMECARD(SCH_1):FPGA_IO_1
 B15     NC IO_L7P_T1_16     NC
 J22 FPGA_IO_0 IO_L7P_T1_AD2P_15 @TIMECARD_LIB.TIMECARD(SCH_1):FPGA_IO_0
 B13 LED_DATOUT0 IO_L8N_T1_16 @TIMECARD_LIB.TIMECARD(SCH_1):LED_DATOUT0
 G20 FPGA_IO_3 IO_L8N_T1_AD10N_15 @TIMECARD_LIB.TIMECARD(SCH_1):FPGA_IO_3
 C13 LED_DATOUT1 IO_L8P_T1_16 @TIMECARD_LIB.TIMECARD(SCH_1):LED_DATOUT1
 H20 FPGA_IO_2 IO_L8P_T1_AD10P_15 @TIMECARD_LIB.TIMECARD(SCH_1):FPGA_IO_2
 A16     NC IO_L9N_T1_DQS_16     NC
 K22 FPGA_IO_5 IO_L9N_T1_DQS_AD3N_15 @TIMECARD_LIB.TIMECARD(SCH_1):FPGA_IO_5
 A15     NC IO_L9P_T1_DQS_16     NC
 K21 FPGA_IO_4 IO_L9P_T1_DQS_AD3P_15 @TIMECARD_LIB.TIMECARD(SCH_1):FPGA_IO_4
 A14 FPGA_USR_LED0 IO_L10N_T1_16 @TIMECARD_LIB.TIMECARD(SCH_1):FPGA_USR_LED0
 L21 FPGA_IO_7 IO_L10N_T1_AD11N_15 @TIMECARD_LIB.TIMECARD(SCH_1):FPGA_IO_7
 A13 FPGA_USR_LED1 IO_L10P_T1_16 @TIMECARD_LIB.TIMECARD(SCH_1):FPGA_USR_LED1
 M21 FPGA_IO_6 IO_L10P_T1_AD11P_15 @TIMECARD_LIB.TIMECARD(SCH_1):FPGA_IO_6
 J21     NC IO_L11N_T1_SRCC_15     NC
 B18     NC IO_L11N_T1_SRCC_16     NC
 J20 FPGA_IN_RST_DLY_N IO_L11P_T1_SRCC_15 @TIMECARD_LIB.TIMECARD(SCH_1):FPGA_IN_RST_DLY_N
 B17     NC IO_L11P_T1_SRCC_16     NC
 H19 FPGA_OUT_SHT3X_RST_N IO_L12N_T1_MRCC_15 @TIMECARD_LIB.TIMECARD(SCH_1):FPGA_OUT_SHT3X_RST_N
 C17 FPGA_OUT_SMA3_LED_GREEN_N IO_L12N_T1_MRCC_16 @TIMECARD_LIB.TIMECARD(SCH_1):FPGA_OUT_SMA3_LED_GREEN_N
 J19 FPGA_IN_SHT3X_ALERT_N IO_L12P_T1_MRCC_15 @TIMECARD_LIB.TIMECARD(SCH_1):FPGA_IN_SHT3X_ALERT_N
 D17 FPGA_OUT_SMA3_LED_BLUE_N IO_L12P_T1_MRCC_16 @TIMECARD_LIB.TIMECARD(SCH_1):FPGA_OUT_SMA3_LED_BLUE_N
 K19     NC IO_L13N_T2_MRCC_15     NC
 C19     NC IO_L13N_T2_MRCC_16     NC
 K18     NC IO_L13P_T2_MRCC_15     NC
 C18 FPGA_OUT_SMA3_LED_RED_N IO_L13P_T2_MRCC_16 @TIMECARD_LIB.TIMECARD(SCH_1):FPGA_OUT_SMA3_LED_RED_N
 L20     NC IO_L14N_T2_SRCC_15     NC
 D19 FPGA_OUT_SMA4_LED_GREEN_N IO_L14N_T2_SRCC_16 @TIMECARD_LIB.TIMECARD(SCH_1):FPGA_OUT_SMA4_LED_GREEN_N
 L19     NC IO_L14P_T2_SRCC_15     NC
 E19 FPGA_OUT_SMA4_LED_BLUE_N IO_L14P_T2_SRCC_16 @TIMECARD_LIB.TIMECARD(SCH_1):FPGA_OUT_SMA4_LED_BLUE_N
 E18     NC IO_L15N_T2_DQS_16     NC
 M22 FPGA_IN_LM75B_INT2_N IO_L15N_T2_DQS_ADV_B_15 @TIMECARD_LIB.TIMECARD(SCH_1):FPGA_IN_LM75B_INT2_N
 N22 FPGA_IN_LM75B_INT1_N IO_L15P_T2_DQS_15 @TIMECARD_LIB.TIMECARD(SCH_1):FPGA_IN_LM75B_INT1_N
 F18 FPGA_OUT_SMA4_LED_RED_N IO_L15P_T2_DQS_16 @TIMECARD_LIB.TIMECARD(SCH_1):FPGA_OUT_SMA4_LED_RED_N
 A20 FPGA_OUT_GPS_LED_GREEN_N IO_L16N_T2_16 @TIMECARD_LIB.TIMECARD(SCH_1):FPGA_OUT_GPS_LED_GREEN_N
 L18     NC IO_L16N_T2_A27_15     NC
 B20 FPGA_OUT_GPS_LED_BLUE_N IO_L16P_T2_16 @TIMECARD_LIB.TIMECARD(SCH_1):FPGA_OUT_GPS_LED_BLUE_N
 M18 FPGA_IN_LM75B_INT3_N IO_L16P_T2_A28_15 @TIMECARD_LIB.TIMECARD(SCH_1):FPGA_IN_LM75B_INT3_N
 A19     NC IO_L17N_T2_16     NC
 N19 FPGA_BRD_REV1 IO_L17N_T2_A25_15 @TIMECARD_LIB.TIMECARD(SCH_1):FPGA_BRD_REV1
 A18 FPGA_OUT_GPS_LED_RED_N IO_L17P_T2_16 @TIMECARD_LIB.TIMECARD(SCH_1):FPGA_OUT_GPS_LED_RED_N
 N18 FPGA_BRD_REV2 IO_L17P_T2_A26_15 @TIMECARD_LIB.TIMECARD(SCH_1):FPGA_BRD_REV2
 F20     NC IO_L18N_T2_16     NC
 M20     NC IO_L18N_T2_A23_15     NC
 F19     NC IO_L18P_T2_16     NC
 N20 FPGA_BRD_REV0 IO_L18P_T2_A24_15 @TIMECARD_LIB.TIMECARD(SCH_1):FPGA_BRD_REV0
 K14 SMA1_SIG_IN_BF_EN_N IO_L19N_T3_A21_VREF_15 @TIMECARD_LIB.TIMECARD(SCH_1):SMA1_SIG_IN_BF_EN_N
 C20     NC IO_L19N_T3_VREF_16     NC
 D20     NC IO_L19P_T3_16     NC
 K13 SMA1_SIG_OUT_BF_EN_N IO_L19P_T3_A22_15 @TIMECARD_LIB.TIMECARD(SCH_1):SMA1_SIG_OUT_BF_EN_N
 B22 IO_L20N_16 IO_L20N_T3_16 @TIMECARD_LIB.TIMECARD(SCH_1):IO_L20N_16
 L13 SMA2_SIG_IN_BF_EN_N IO_L20N_T3_A19_15 @TIMECARD_LIB.TIMECARD(SCH_1):SMA2_SIG_IN_BF_EN_N
 C22 IO_L20P_16 IO_L20P_T3_16 @TIMECARD_LIB.TIMECARD(SCH_1):IO_L20P_16
 M13 SMA2_SIG_OUT_BF_EN_N IO_L20P_T3_A20_15 @TIMECARD_LIB.TIMECARD(SCH_1):SMA2_SIG_OUT_BF_EN_N
 A21 IO_L21N_16 IO_L21N_T3_DQS_16 @TIMECARD_LIB.TIMECARD(SCH_1):IO_L21N_16
 J17 FPGA_OUT_BNO080_RST_N IO_L21N_T3_DQS_A18_15 @TIMECARD_LIB.TIMECARD(SCH_1):FPGA_OUT_BNO080_RST_N
 K17     NC IO_L21P_T3_DQS_15     NC
 B21 IO_L21P_16 IO_L21P_T3_DQS_16 @TIMECARD_LIB.TIMECARD(SCH_1):IO_L21P_16
 D22 IO_L22N_16 IO_L22N_T3_16 @TIMECARD_LIB.TIMECARD(SCH_1):IO_L22N_16
 L15 FPGA_OUT_BNO080_BOOT_N IO_L22N_T3_A16_15 @TIMECARD_LIB.TIMECARD(SCH_1):FPGA_OUT_BNO080_BOOT_N
 E22 IO_L22P_16 IO_L22P_T3_16 @TIMECARD_LIB.TIMECARD(SCH_1):IO_L22P_16
 L14 FPGA_IN_BNO080_INT_N IO_L22P_T3_A17_15 @TIMECARD_LIB.TIMECARD(SCH_1):FPGA_IN_BNO080_INT_N
 D21 IO_L23N_16 IO_L23N_T3_16 @TIMECARD_LIB.TIMECARD(SCH_1):IO_L23N_16
 K16 FPGA_OUT_I2C_BUFFER_EN IO_L23N_T3_FWE_B_15 @TIMECARD_LIB.TIMECARD(SCH_1):FPGA_OUT_I2C_BUFFER_EN
 E21 IO_L23P_16 IO_L23P_T3_16 @TIMECARD_LIB.TIMECARD(SCH_1):IO_L23P_16
 L16     NC IO_L23P_T3_FOE_B_15     NC
 G22 IO_L24N_16 IO_L24N_T3_16 @TIMECARD_LIB.TIMECARD(SCH_1):IO_L24N_16
 M16 RSVD_DBG_USB_MUX_SEL IO_L24N_T3_RS0_15 @TIMECARD_LIB.TIMECARD(SCH_1):RSVD_DBG_USB_MUX_SEL
 G21 IO_L24P_16 IO_L24P_T3_16 @TIMECARD_LIB.TIMECARD(SCH_1):IO_L24P_16
 M15 FPGA_IN_MAC_USB_OC_N IO_L24P_T3_RS1_15 @TIMECARD_LIB.TIMECARD(SCH_1):FPGA_IN_MAC_USB_OC_N


DRAWING: @TIMECARD_LIB.TIMECARD(SCH_1):PAGE163 

XC7A200T_2FBG484C_FBG484-G240-A  I1  U24
  T3     NC IO_0_34     NC
  F4     NC IO_0_35     NC
  U7     NC IO_25_34     NC
  L6     NC IO_25_35     NC
  U1     NC IO_L1N_T0_34     NC
  A1     NC IO_L1N_T0_AD4N_35     NC
  T1     NC IO_L1P_T0_34     NC
  B1     NC IO_L1P_T0_AD4P_35     NC
  V2     NC IO_L2N_T0_34     NC
  B2     NC IO_L2N_T0_AD12N_35     NC
  U2     NC IO_L2P_T0_34     NC
  C2     NC IO_L2P_T0_AD12P_35     NC
  R2     NC IO_L3N_T0_DQS_34     NC
  D1     NC IO_L3N_T0_DQS_AD5N_35     NC
  R3     NC IO_L3P_T0_DQS_34     NC
  E1     NC IO_L3P_T0_DQS_AD5P_35     NC
  Y2     NC IO_L4N_T0_34     NC
  D2     NC IO_L4N_T0_35     NC
  W2     NC IO_L4P_T0_34     NC
  E2     NC IO_L4P_T0_35     NC
  Y1 FPGA_IN_MAC_PPS_OUTN IO_L5N_T0_34 @TIMECARD_LIB.TIMECARD(SCH_1):FPGA_IN_MAC_PPS_OUTN
  F1     NC IO_L5N_T0_AD13N_35     NC
  W1 FPGA_IN_MAC_PPS_OUTP IO_L5P_T0_34 @TIMECARD_LIB.TIMECARD(SCH_1):FPGA_IN_MAC_PPS_OUTP
  G1     NC IO_L5P_T0_AD13P_35     NC
  V3     NC IO_L6N_T0_VREF_34     NC
  E3     NC IO_L6N_T0_VREF_35     NC
  U3     NC IO_L6P_T0_34     NC
  F3     NC IO_L6P_T0_35     NC
 AB1     NC IO_L7N_T1_34     NC
  J1     NC IO_L7N_T1_AD6N_35     NC
 AA1     NC IO_L7P_T1_34     NC
  K1     NC IO_L7P_T1_AD6P_35     NC
 AB2 FPGA_OUT_MAC_PPS_IN0N IO_L8N_T1_34 @TIMECARD_LIB.TIMECARD(SCH_1):FPGA_OUT_MAC_PPS_IN0N
  G2     NC IO_L8N_T1_AD14N_35     NC
 AB3 FPGA_OUT_MAC_PPS_IN0P IO_L8P_T1_34 @TIMECARD_LIB.TIMECARD(SCH_1):FPGA_OUT_MAC_PPS_IN0P
  H2     NC IO_L8P_T1_AD14P_35     NC
 AA3     NC IO_L9N_T1_DQS_34     NC
  J2     NC IO_L9N_T1_DQS_AD7N_35     NC
  Y3     NC IO_L9P_T1_DQS_34     NC
  K2     NC IO_L9P_T1_DQS_AD7P_35     NC
 AB5 FPGA_OUT_MAC_PPS_IN1N IO_L10N_T1_34 @TIMECARD_LIB.TIMECARD(SCH_1):FPGA_OUT_MAC_PPS_IN1N
  H5     NC IO_L10N_T1_AD15N_35     NC
 AA5 FPGA_OUT_MAC_PPS_IN1P IO_L10P_T1_34 @TIMECARD_LIB.TIMECARD(SCH_1):FPGA_OUT_MAC_PPS_IN1P
  J5     NC IO_L10P_T1_AD15P_35     NC
 AA4     NC IO_L11N_T1_SRCC_34     NC
  G3     NC IO_L11N_T1_SRCC_35     NC
  Y4     NC IO_L11P_T1_SRCC_34     NC
  H3     NC IO_L11P_T1_SRCC_35     NC
  W4     NC IO_L12N_T1_MRCC_34     NC
  G4     NC IO_L12N_T1_MRCC_35     NC
  V4     NC IO_L12P_T1_MRCC_34     NC
  H4     NC IO_L12P_T1_MRCC_35     NC
  T4 MHZ200CLKN_CLKIN IO_L13N_T2_MRCC_34 @TIMECARD_LIB.TIMECARD(SCH_1):MHZ200CLKN_CLKIN
  J4     NC IO_L13N_T2_MRCC_35     NC
  R4 MHZ200CLKP_CLKIN IO_L13P_T2_MRCC_34 @TIMECARD_LIB.TIMECARD(SCH_1):MHZ200CLKP_CLKIN
  K4     NC IO_L13P_T2_MRCC_35     NC
  U5     NC IO_L14N_T2_SRCC_34     NC
  K3     NC IO_L14N_T2_SRCC_35     NC
  T5     NC IO_L14P_T2_SRCC_34     NC
  L3     NC IO_L14P_T2_SRCC_35     NC
  W5     NC IO_L15N_T2_DQS_34     NC
  L1     NC IO_L15N_T2_DQS_35     NC
  W6     NC IO_L15P_T2_DQS_34     NC
  M1     NC IO_L15P_T2_DQS_35     NC
  V5     NC IO_L16N_T2_34     NC
  M2     NC IO_L16N_T2_35     NC
  U6     NC IO_L16P_T2_34     NC
  M3     NC IO_L16P_T2_35     NC
  T6     NC IO_L17N_T2_34     NC
  J6     NC IO_L17N_T2_35     NC
  R6     NC IO_L17P_T2_34     NC
  K6     NC IO_L17P_T2_35     NC
 AA6     NC IO_L18N_T2_34     NC
  L4     NC IO_L18N_T2_35     NC
  Y6     NC IO_L18P_T2_34     NC
  L5     NC IO_L18P_T2_35     NC
  W7     NC IO_L19N_T3_VREF_34     NC
  N3     NC IO_L19N_T3_VREF_35     NC
  V7     NC IO_L19P_T3_34     NC
  N4     NC IO_L19P_T3_35     NC
 AB6 IO_L20N_34 IO_L20N_T3_34 @TIMECARD_LIB.TIMECARD(SCH_1):IO_L20N_34
  P1 IO_L20N_35 IO_L20N_T3_35 @TIMECARD_LIB.TIMECARD(SCH_1):IO_L20N_35
 AB7 IO_L20P_34 IO_L20P_T3_34 @TIMECARD_LIB.TIMECARD(SCH_1):IO_L20P_34
  R1 IO_L20P_35 IO_L20P_T3_35 @TIMECARD_LIB.TIMECARD(SCH_1):IO_L20P_35
  V8 IO_L21N_34 IO_L21N_T3_DQS_34 @TIMECARD_LIB.TIMECARD(SCH_1):IO_L21N_34
  P4 IO_L21N_35 IO_L21N_T3_DQS_35 @TIMECARD_LIB.TIMECARD(SCH_1):IO_L21N_35
  V9 IO_L21P_34 IO_L21P_T3_DQS_34 @TIMECARD_LIB.TIMECARD(SCH_1):IO_L21P_34
  P5 IO_L21P_35 IO_L21P_T3_DQS_35 @TIMECARD_LIB.TIMECARD(SCH_1):IO_L21P_35
 AB8 IO_L22N_34 IO_L22N_T3_34 @TIMECARD_LIB.TIMECARD(SCH_1):IO_L22N_34
  N2 IO_L22N_35 IO_L22N_T3_35 @TIMECARD_LIB.TIMECARD(SCH_1):IO_L22N_35
 AA8 IO_L22P_34 IO_L22P_T3_34 @TIMECARD_LIB.TIMECARD(SCH_1):IO_L22P_34
  P2 IO_L22P_35 IO_L22P_T3_35 @TIMECARD_LIB.TIMECARD(SCH_1):IO_L22P_35
  Y7 IO_L23N_34 IO_L23N_T3_34 @TIMECARD_LIB.TIMECARD(SCH_1):IO_L23N_34
  M5 IO_L23N_35 IO_L23N_T3_35 @TIMECARD_LIB.TIMECARD(SCH_1):IO_L23N_35
  Y8 IO_L23P_34 IO_L23P_T3_34 @TIMECARD_LIB.TIMECARD(SCH_1):IO_L23P_34
  M6 IO_L23P_35 IO_L23P_T3_35 @TIMECARD_LIB.TIMECARD(SCH_1):IO_L23P_35
  Y9 IO_L24N_34 IO_L24N_T3_34 @TIMECARD_LIB.TIMECARD(SCH_1):IO_L24N_34
  N5 IO_L24N_35 IO_L24N_T3_35 @TIMECARD_LIB.TIMECARD(SCH_1):IO_L24N_35
  W9 IO_L24P_34 IO_L24P_T3_34 @TIMECARD_LIB.TIMECARD(SCH_1):IO_L24P_34
  P6 IO_L24P_35 IO_L24P_T3_35 @TIMECARD_LIB.TIMECARD(SCH_1):IO_L24P_35

RESISTOR-G155-11000-01,100OHM,A  I36  R278
   2 MHZ200CLKN_CLKIN      2 @TIMECARD_LIB.TIMECARD(SCH_1):MHZ200CLKN_CLKIN
   1 MHZ200CLKP_CLKIN      1 @TIMECARD_LIB.TIMECARD(SCH_1):MHZ200CLKP_CLKIN

RESISTOR-G155-11000-01,100OHM,A  I37  R277
   2 FPGA_OUT_MAC_PPS_IN1N      2 @TIMECARD_LIB.TIMECARD(SCH_1):FPGA_OUT_MAC_PPS_IN1N
   1 FPGA_OUT_MAC_PPS_IN1P      1 @TIMECARD_LIB.TIMECARD(SCH_1):FPGA_OUT_MAC_PPS_IN1P

RESISTOR-G155-11000-01,100OHM,A  I38  R276
   2 FPGA_OUT_MAC_PPS_IN0N      2 @TIMECARD_LIB.TIMECARD(SCH_1):FPGA_OUT_MAC_PPS_IN0N
   1 FPGA_OUT_MAC_PPS_IN0P      1 @TIMECARD_LIB.TIMECARD(SCH_1):FPGA_OUT_MAC_PPS_IN0P

RESISTOR-G155-11000-01,100OHM,A  I39  R275
   2 FPGA_IN_MAC_PPS_OUTN      2 @TIMECARD_LIB.TIMECARD(SCH_1):FPGA_IN_MAC_PPS_OUTN
   1 FPGA_IN_MAC_PPS_OUTP      1 @TIMECARD_LIB.TIMECARD(SCH_1):FPGA_IN_MAC_PPS_OUTP

RESISTOR-G155-11002-01,10KOHM,A  I120  R355
   2 XP2R5V_FPGA      2 @TIMECARD_LIB.TIMECARD(SCH_1):XP2R5V_FPGA
   1 MHZ200CLKN_CLKIN      1 @TIMECARD_LIB.TIMECARD(SCH_1):MHZ200CLKN_CLKIN

RESISTOR-G155-11002-01,10KOHM,A  I126  R358
   2 XP2R5V_FPGA      2 @TIMECARD_LIB.TIMECARD(SCH_1):XP2R5V_FPGA
   1 MHZ200CLKP_CLKIN      1 @TIMECARD_LIB.TIMECARD(SCH_1):MHZ200CLKP_CLKIN

RESISTOR-G155-11002-01,10KOHM,A  I127  R359
   2     SG      2 @TIMECARD_LIB.TIMECARD(SCH_1):SG
   1 MHZ200CLKP_CLKIN      1 @TIMECARD_LIB.TIMECARD(SCH_1):MHZ200CLKP_CLKIN

RESISTOR-G155-11002-01,10KOHM,A  I128  R360
   2     SG      2 @TIMECARD_LIB.TIMECARD(SCH_1):SG
   1 MHZ200CLKN_CLKIN      1 @TIMECARD_LIB.TIMECARD(SCH_1):MHZ200CLKN_CLKIN

RESISTOR-G155-11002-01,10KOHM,A  I132  R438
   2 XP2R5V_FPGA      2 @TIMECARD_LIB.TIMECARD(SCH_1):XP2R5V_FPGA
   1 FPGA_IN_MAC_PPS_OUTN      1 @TIMECARD_LIB.TIMECARD(SCH_1):FPGA_IN_MAC_PPS_OUTN

RESISTOR-G155-11002-01,10KOHM,A  I133  R439
   2 XP2R5V_FPGA      2 @TIMECARD_LIB.TIMECARD(SCH_1):XP2R5V_FPGA
   1 FPGA_IN_MAC_PPS_OUTP      1 @TIMECARD_LIB.TIMECARD(SCH_1):FPGA_IN_MAC_PPS_OUTP

RESISTOR-G155-11002-01,10KOHM,A  I134  R441
   2     SG      2 @TIMECARD_LIB.TIMECARD(SCH_1):SG
   1 FPGA_IN_MAC_PPS_OUTN      1 @TIMECARD_LIB.TIMECARD(SCH_1):FPGA_IN_MAC_PPS_OUTN

RESISTOR-G155-11002-01,10KOHM,A  I135  R440
   2     SG      2 @TIMECARD_LIB.TIMECARD(SCH_1):SG
   1 FPGA_IN_MAC_PPS_OUTP      1 @TIMECARD_LIB.TIMECARD(SCH_1):FPGA_IN_MAC_PPS_OUTP


DRAWING: @TIMECARD_LIB.TIMECARD(SCH_1):PAGE164 

FERRITEBEAD-G191-10100-01,120OA  I36  L35
   1 FPGA_MGTAVTT      1 @TIMECARD_LIB.TIMECARD(SCH_1):FPGA_MGTAVTT
   2 XP1R2V_FPGA      2 @TIMECARD_LIB.TIMECARD(SCH_1):XP1R2V_FPGA

FERRITEBEAD-G191-10100-01,120OA  I37  L34
   1 XP1R0V_FPGA_MGTAVCC      1 @TIMECARD_LIB.TIMECARD(SCH_1):XP1R0V_FPGA_MGTAVCC
   2 XP1R0V_FPGA      2 @TIMECARD_LIB.TIMECARD(SCH_1):XP1R0V_FPGA

FERRITEBEAD-G191-10100-01,120OA  I102  L33
   1 XP1R8V_FPGA_VCCAUX      1 @TIMECARD_LIB.TIMECARD(SCH_1):XP1R8V_FPGA_VCCAUX
   2 XP1R8V_FPGA      2 @TIMECARD_LIB.TIMECARD(SCH_1):XP1R8V_FPGA

XC7A200T_2FBG484C_FBG484-G240-A  I138  U24
  K9     SG GNDADC_0 @TIMECARD_LIB.TIMECARD(SCH_1):SG
 A11     SG  GND_1 @TIMECARD_LIB.TIMECARD(SCH_1):SG
 A12     SG  GND_2 @TIMECARD_LIB.TIMECARD(SCH_1):SG
  A2     SG  GND_3 @TIMECARD_LIB.TIMECARD(SCH_1):SG
 A22     SG  GND_4 @TIMECARD_LIB.TIMECARD(SCH_1):SG
  A3     SG  GND_5 @TIMECARD_LIB.TIMECARD(SCH_1):SG
  A5     SG  GND_6 @TIMECARD_LIB.TIMECARD(SCH_1):SG
  A7     SG  GND_7 @TIMECARD_LIB.TIMECARD(SCH_1):SG
  A9     SG  GND_8 @TIMECARD_LIB.TIMECARD(SCH_1):SG
AA12     SG  GND_9 @TIMECARD_LIB.TIMECARD(SCH_1):SG
 AA2     SG GND_10 @TIMECARD_LIB.TIMECARD(SCH_1):SG
AA22     SG GND_11 @TIMECARD_LIB.TIMECARD(SCH_1):SG
AB19     SG GND_12 @TIMECARD_LIB.TIMECARD(SCH_1):SG
 AB9     SG GND_13 @TIMECARD_LIB.TIMECARD(SCH_1):SG
 B12     SG GND_14 @TIMECARD_LIB.TIMECARD(SCH_1):SG
 B19     SG GND_15 @TIMECARD_LIB.TIMECARD(SCH_1):SG
  B3     SG GND_16 @TIMECARD_LIB.TIMECARD(SCH_1):SG
 C10     SG GND_17 @TIMECARD_LIB.TIMECARD(SCH_1):SG
 C12     SG GND_18 @TIMECARD_LIB.TIMECARD(SCH_1):SG
 C16     SG GND_19 @TIMECARD_LIB.TIMECARD(SCH_1):SG
  C3     SG GND_20 @TIMECARD_LIB.TIMECARD(SCH_1):SG
  C6     SG GND_21 @TIMECARD_LIB.TIMECARD(SCH_1):SG
 D12     SG GND_22 @TIMECARD_LIB.TIMECARD(SCH_1):SG
 D13     SG GND_23 @TIMECARD_LIB.TIMECARD(SCH_1):SG
  D3     SG GND_24 @TIMECARD_LIB.TIMECARD(SCH_1):SG
  D4     SG GND_25 @TIMECARD_LIB.TIMECARD(SCH_1):SG
  D8     SG GND_26 @TIMECARD_LIB.TIMECARD(SCH_1):SG
 E11     SG GND_27 @TIMECARD_LIB.TIMECARD(SCH_1):SG
 E20     SG GND_28 @TIMECARD_LIB.TIMECARD(SCH_1):SG
  E4     SG GND_29 @TIMECARD_LIB.TIMECARD(SCH_1):SG
  E5     SG GND_30 @TIMECARD_LIB.TIMECARD(SCH_1):SG
  E7     SG GND_31 @TIMECARD_LIB.TIMECARD(SCH_1):SG
  E9     SG GND_32 @TIMECARD_LIB.TIMECARD(SCH_1):SG
 F11     SG GND_33 @TIMECARD_LIB.TIMECARD(SCH_1):SG
 F17     SG GND_34 @TIMECARD_LIB.TIMECARD(SCH_1):SG
  F5     SG GND_35 @TIMECARD_LIB.TIMECARD(SCH_1):SG
 G10     SG GND_36 @TIMECARD_LIB.TIMECARD(SCH_1):SG
 G12     SG GND_37 @TIMECARD_LIB.TIMECARD(SCH_1):SG
 G14     SG GND_38 @TIMECARD_LIB.TIMECARD(SCH_1):SG
  G5     SG GND_39 @TIMECARD_LIB.TIMECARD(SCH_1):SG
  G6     SG GND_40 @TIMECARD_LIB.TIMECARD(SCH_1):SG
  G7     SG GND_41 @TIMECARD_LIB.TIMECARD(SCH_1):SG
  G8     SG GND_42 @TIMECARD_LIB.TIMECARD(SCH_1):SG
  G9     SG GND_43 @TIMECARD_LIB.TIMECARD(SCH_1):SG
  H1     SG GND_44 @TIMECARD_LIB.TIMECARD(SCH_1):SG
 H11     SG GND_45 @TIMECARD_LIB.TIMECARD(SCH_1):SG
 H21     SG GND_46 @TIMECARD_LIB.TIMECARD(SCH_1):SG
  H7     SG GND_47 @TIMECARD_LIB.TIMECARD(SCH_1):SG
  H9     SG GND_48 @TIMECARD_LIB.TIMECARD(SCH_1):SG
 J10     SG GND_49 @TIMECARD_LIB.TIMECARD(SCH_1):SG
 J12     SG GND_50 @TIMECARD_LIB.TIMECARD(SCH_1):SG
 J18     SG GND_51 @TIMECARD_LIB.TIMECARD(SCH_1):SG
  J8     SG GND_52 @TIMECARD_LIB.TIMECARD(SCH_1):SG
 K11     SG GND_53 @TIMECARD_LIB.TIMECARD(SCH_1):SG
 K15     SG GND_54 @TIMECARD_LIB.TIMECARD(SCH_1):SG
  K5     SG GND_55 @TIMECARD_LIB.TIMECARD(SCH_1):SG
  K7     SG GND_56 @TIMECARD_LIB.TIMECARD(SCH_1):SG
  L2     SG GND_57 @TIMECARD_LIB.TIMECARD(SCH_1):SG
 L22     SG GND_58 @TIMECARD_LIB.TIMECARD(SCH_1):SG
  L8     SG GND_59 @TIMECARD_LIB.TIMECARD(SCH_1):SG
 M11     SG GND_60 @TIMECARD_LIB.TIMECARD(SCH_1):SG
 M19     SG GND_61 @TIMECARD_LIB.TIMECARD(SCH_1):SG
  M7     SG GND_62 @TIMECARD_LIB.TIMECARD(SCH_1):SG
 N16     SG GND_63 @TIMECARD_LIB.TIMECARD(SCH_1):SG
  N6     SG GND_64 @TIMECARD_LIB.TIMECARD(SCH_1):SG
  N8     SG GND_65 @TIMECARD_LIB.TIMECARD(SCH_1):SG
 P11     SG GND_66 @TIMECARD_LIB.TIMECARD(SCH_1):SG
 P13     SG GND_67 @TIMECARD_LIB.TIMECARD(SCH_1):SG
  P3     SG GND_68 @TIMECARD_LIB.TIMECARD(SCH_1):SG
  P7     SG GND_69 @TIMECARD_LIB.TIMECARD(SCH_1):SG
  P9     SG GND_70 @TIMECARD_LIB.TIMECARD(SCH_1):SG
 R10     SG GND_71 @TIMECARD_LIB.TIMECARD(SCH_1):SG
 R12     SG GND_72 @TIMECARD_LIB.TIMECARD(SCH_1):SG
 R20     SG GND_73 @TIMECARD_LIB.TIMECARD(SCH_1):SG
  R8     SG GND_74 @TIMECARD_LIB.TIMECARD(SCH_1):SG
 T11     SG GND_75 @TIMECARD_LIB.TIMECARD(SCH_1):SG
 T17     SG GND_76 @TIMECARD_LIB.TIMECARD(SCH_1):SG
  T7     SG GND_77 @TIMECARD_LIB.TIMECARD(SCH_1):SG
  T9     SG GND_78 @TIMECARD_LIB.TIMECARD(SCH_1):SG
 U14     SG GND_79 @TIMECARD_LIB.TIMECARD(SCH_1):SG
  U4     SG GND_80 @TIMECARD_LIB.TIMECARD(SCH_1):SG
  V1     SG GND_81 @TIMECARD_LIB.TIMECARD(SCH_1):SG
 V11     SG GND_82 @TIMECARD_LIB.TIMECARD(SCH_1):SG
 V21     SG GND_83 @TIMECARD_LIB.TIMECARD(SCH_1):SG
 W18     SG GND_84 @TIMECARD_LIB.TIMECARD(SCH_1):SG
  W8     SG GND_85 @TIMECARD_LIB.TIMECARD(SCH_1):SG
 Y15     SG GND_86 @TIMECARD_LIB.TIMECARD(SCH_1):SG
  Y5     SG GND_87 @TIMECARD_LIB.TIMECARD(SCH_1):SG
 D10 XP1R0V_FPGA_MGTAVCC MGTAVCC_1 @TIMECARD_LIB.TIMECARD(SCH_1):XP1R0V_FPGA_MGTAVCC
  D6 XP1R0V_FPGA_MGTAVCC MGTAVCC_2 @TIMECARD_LIB.TIMECARD(SCH_1):XP1R0V_FPGA_MGTAVCC
  E8 XP1R0V_FPGA_MGTAVCC MGTAVCC_3 @TIMECARD_LIB.TIMECARD(SCH_1):XP1R0V_FPGA_MGTAVCC
  F7 XP1R0V_FPGA_MGTAVCC MGTAVCC_4 @TIMECARD_LIB.TIMECARD(SCH_1):XP1R0V_FPGA_MGTAVCC
  F9 XP1R0V_FPGA_MGTAVCC MGTAVCC_5 @TIMECARD_LIB.TIMECARD(SCH_1):XP1R0V_FPGA_MGTAVCC
 B11 FPGA_MGTAVTT MGTAVTT_1 @TIMECARD_LIB.TIMECARD(SCH_1):FPGA_MGTAVTT
  B5 FPGA_MGTAVTT MGTAVTT_2 @TIMECARD_LIB.TIMECARD(SCH_1):FPGA_MGTAVTT
  B7 FPGA_MGTAVTT MGTAVTT_3 @TIMECARD_LIB.TIMECARD(SCH_1):FPGA_MGTAVTT
  B9 FPGA_MGTAVTT MGTAVTT_4 @TIMECARD_LIB.TIMECARD(SCH_1):FPGA_MGTAVTT
  C4 FPGA_MGTAVTT MGTAVTT_5 @TIMECARD_LIB.TIMECARD(SCH_1):FPGA_MGTAVTT
  C8 FPGA_MGTAVTT MGTAVTT_6 @TIMECARD_LIB.TIMECARD(SCH_1):FPGA_MGTAVTT
 K10 XP1R8V_FPGA_VCCAUX VCCADC_0 @TIMECARD_LIB.TIMECARD(SCH_1):XP1R8V_FPGA_VCCAUX
 H12 XP1R8V_FPGA_VCCAUX VCCAUX_1 @TIMECARD_LIB.TIMECARD(SCH_1):XP1R8V_FPGA_VCCAUX
 K12 XP1R8V_FPGA_VCCAUX VCCAUX_2 @TIMECARD_LIB.TIMECARD(SCH_1):XP1R8V_FPGA_VCCAUX
 M12 XP1R8V_FPGA_VCCAUX VCCAUX_3 @TIMECARD_LIB.TIMECARD(SCH_1):XP1R8V_FPGA_VCCAUX
 P12 XP1R8V_FPGA_VCCAUX VCCAUX_4 @TIMECARD_LIB.TIMECARD(SCH_1):XP1R8V_FPGA_VCCAUX
 R11 XP1R8V_FPGA_VCCAUX VCCAUX_5 @TIMECARD_LIB.TIMECARD(SCH_1):XP1R8V_FPGA_VCCAUX
 E12 XP1R8V_FPGA_VCCAUX VCCBATT_0 @TIMECARD_LIB.TIMECARD(SCH_1):XP1R8V_FPGA_VCCAUX
 J11 XP1R0V_FPGA_VCCINT VCCBRAM_1 @TIMECARD_LIB.TIMECARD(SCH_1):XP1R0V_FPGA_VCCINT
 L11 XP1R0V_FPGA_VCCINT VCCBRAM_2 @TIMECARD_LIB.TIMECARD(SCH_1):XP1R0V_FPGA_VCCINT
 N11 XP1R0V_FPGA_VCCINT VCCBRAM_3 @TIMECARD_LIB.TIMECARD(SCH_1):XP1R0V_FPGA_VCCINT
 H10 XP1R0V_FPGA_VCCINT VCCINT_1 @TIMECARD_LIB.TIMECARD(SCH_1):XP1R0V_FPGA_VCCINT
  H8 XP1R0V_FPGA_VCCINT VCCINT_2 @TIMECARD_LIB.TIMECARD(SCH_1):XP1R0V_FPGA_VCCINT
  J7 XP1R0V_FPGA_VCCINT VCCINT_3 @TIMECARD_LIB.TIMECARD(SCH_1):XP1R0V_FPGA_VCCINT
  J9 XP1R0V_FPGA_VCCINT VCCINT_4 @TIMECARD_LIB.TIMECARD(SCH_1):XP1R0V_FPGA_VCCINT
  K8 XP1R0V_FPGA_VCCINT VCCINT_5 @TIMECARD_LIB.TIMECARD(SCH_1):XP1R0V_FPGA_VCCINT
  L7 XP1R0V_FPGA_VCCINT VCCINT_6 @TIMECARD_LIB.TIMECARD(SCH_1):XP1R0V_FPGA_VCCINT
  M8 XP1R0V_FPGA_VCCINT VCCINT_7 @TIMECARD_LIB.TIMECARD(SCH_1):XP1R0V_FPGA_VCCINT
  N7 XP1R0V_FPGA_VCCINT VCCINT_8 @TIMECARD_LIB.TIMECARD(SCH_1):XP1R0V_FPGA_VCCINT
 P10 XP1R0V_FPGA_VCCINT VCCINT_9 @TIMECARD_LIB.TIMECARD(SCH_1):XP1R0V_FPGA_VCCINT
  P8 XP1R0V_FPGA_VCCINT VCCINT_10 @TIMECARD_LIB.TIMECARD(SCH_1):XP1R0V_FPGA_VCCINT
  R7 XP1R0V_FPGA_VCCINT VCCINT_11 @TIMECARD_LIB.TIMECARD(SCH_1):XP1R0V_FPGA_VCCINT
  R9 XP1R0V_FPGA_VCCINT VCCINT_12 @TIMECARD_LIB.TIMECARD(SCH_1):XP1R0V_FPGA_VCCINT
 T10 XP1R0V_FPGA_VCCINT VCCINT_13 @TIMECARD_LIB.TIMECARD(SCH_1):XP1R0V_FPGA_VCCINT
  T8 XP1R0V_FPGA_VCCINT VCCINT_14 @TIMECARD_LIB.TIMECARD(SCH_1):XP1R0V_FPGA_VCCINT
 F12 XP3R3V_FPGA VCCO_0_1 @TIMECARD_LIB.TIMECARD(SCH_1):XP3R3V_FPGA
 T12 XP3R3V_FPGA VCCO_0_2 @TIMECARD_LIB.TIMECARD(SCH_1):XP3R3V_FPGA
AA17 XP3R3V_FPGA VCCO_13_1 @TIMECARD_LIB.TIMECARD(SCH_1):XP3R3V_FPGA
AB14 XP3R3V_FPGA VCCO_13_2 @TIMECARD_LIB.TIMECARD(SCH_1):XP3R3V_FPGA
 V16 XP3R3V_FPGA VCCO_13_3 @TIMECARD_LIB.TIMECARD(SCH_1):XP3R3V_FPGA
 W13 XP3R3V_FPGA VCCO_13_4 @TIMECARD_LIB.TIMECARD(SCH_1):XP3R3V_FPGA
 Y10 XP3R3V_FPGA VCCO_13_5 @TIMECARD_LIB.TIMECARD(SCH_1):XP3R3V_FPGA
 M14 XP3R3V_FPGA VCCO_14_1 @TIMECARD_LIB.TIMECARD(SCH_1):XP3R3V_FPGA
 P18 XP3R3V_FPGA VCCO_14_2 @TIMECARD_LIB.TIMECARD(SCH_1):XP3R3V_FPGA
 R15 XP3R3V_FPGA VCCO_14_3 @TIMECARD_LIB.TIMECARD(SCH_1):XP3R3V_FPGA
 T22 XP3R3V_FPGA VCCO_14_4 @TIMECARD_LIB.TIMECARD(SCH_1):XP3R3V_FPGA
 U19 XP3R3V_FPGA VCCO_14_5 @TIMECARD_LIB.TIMECARD(SCH_1):XP3R3V_FPGA
 Y20 XP3R3V_FPGA VCCO_14_6 @TIMECARD_LIB.TIMECARD(SCH_1):XP3R3V_FPGA
 G19 XP3R3V_FPGA VCCO_15_1 @TIMECARD_LIB.TIMECARD(SCH_1):XP3R3V_FPGA
 H16 XP3R3V_FPGA VCCO_15_2 @TIMECARD_LIB.TIMECARD(SCH_1):XP3R3V_FPGA
 J13 XP3R3V_FPGA VCCO_15_3 @TIMECARD_LIB.TIMECARD(SCH_1):XP3R3V_FPGA
 K20 XP3R3V_FPGA VCCO_15_4 @TIMECARD_LIB.TIMECARD(SCH_1):XP3R3V_FPGA
 L17 XP3R3V_FPGA VCCO_15_5 @TIMECARD_LIB.TIMECARD(SCH_1):XP3R3V_FPGA
 N21 XP3R3V_FPGA VCCO_15_6 @TIMECARD_LIB.TIMECARD(SCH_1):XP3R3V_FPGA
 A17 XP3R3V_FPGA VCCO_16_1 @TIMECARD_LIB.TIMECARD(SCH_1):XP3R3V_FPGA
 B14 XP3R3V_FPGA VCCO_16_2 @TIMECARD_LIB.TIMECARD(SCH_1):XP3R3V_FPGA
 C21 XP3R3V_FPGA VCCO_16_3 @TIMECARD_LIB.TIMECARD(SCH_1):XP3R3V_FPGA
 D18 XP3R3V_FPGA VCCO_16_4 @TIMECARD_LIB.TIMECARD(SCH_1):XP3R3V_FPGA
 E15 XP3R3V_FPGA VCCO_16_5 @TIMECARD_LIB.TIMECARD(SCH_1):XP3R3V_FPGA
 F22 XP3R3V_FPGA VCCO_16_6 @TIMECARD_LIB.TIMECARD(SCH_1):XP3R3V_FPGA
 AA7 XP2R5V_FPGA VCCO_34_1 @TIMECARD_LIB.TIMECARD(SCH_1):XP2R5V_FPGA
 AB4 XP2R5V_FPGA VCCO_34_2 @TIMECARD_LIB.TIMECARD(SCH_1):XP2R5V_FPGA
  R5 XP2R5V_FPGA VCCO_34_3 @TIMECARD_LIB.TIMECARD(SCH_1):XP2R5V_FPGA
  T2 XP2R5V_FPGA VCCO_34_4 @TIMECARD_LIB.TIMECARD(SCH_1):XP2R5V_FPGA
  V6 XP2R5V_FPGA VCCO_34_5 @TIMECARD_LIB.TIMECARD(SCH_1):XP2R5V_FPGA
  W3 XP2R5V_FPGA VCCO_34_6 @TIMECARD_LIB.TIMECARD(SCH_1):XP2R5V_FPGA
  C1 XP2R5V_FPGA VCCO_35_1 @TIMECARD_LIB.TIMECARD(SCH_1):XP2R5V_FPGA
  F2 XP2R5V_FPGA VCCO_35_2 @TIMECARD_LIB.TIMECARD(SCH_1):XP2R5V_FPGA
  H6 XP2R5V_FPGA VCCO_35_3 @TIMECARD_LIB.TIMECARD(SCH_1):XP2R5V_FPGA
  J3 XP2R5V_FPGA VCCO_35_4 @TIMECARD_LIB.TIMECARD(SCH_1):XP2R5V_FPGA
  M4 XP2R5V_FPGA VCCO_35_5 @TIMECARD_LIB.TIMECARD(SCH_1):XP2R5V_FPGA
  N1 XP2R5V_FPGA VCCO_35_6 @TIMECARD_LIB.TIMECARD(SCH_1):XP2R5V_FPGA

FERRITEBEAD-G191-10100-01,120OA  I139  L12
   1 XP1R0V_FPGA_VCCINT      1 @TIMECARD_LIB.TIMECARD(SCH_1):XP1R0V_FPGA_VCCINT
   2 XP1R0V_FPGA      2 @TIMECARD_LIB.TIMECARD(SCH_1):XP1R0V_FPGA

CAPACITOR-G109-0G107-BM,100UF,A  I172  C176
   1 XP1R0V_FPGA_VCCINT      1 @TIMECARD_LIB.TIMECARD(SCH_1):XP1R0V_FPGA_VCCINT
   2     SG      2 @TIMECARD_LIB.TIMECARD(SCH_1):SG

CAPACITOR-G109-0G107-BM,100UF,A  I173  C175
   1 XP1R0V_FPGA_VCCINT      1 @TIMECARD_LIB.TIMECARD(SCH_1):XP1R0V_FPGA_VCCINT
   2     SG      2 @TIMECARD_LIB.TIMECARD(SCH_1):SG

CAPACITOR-G109-0G107-BM,100UF,A  I174  C172
   1 XP3R3V_FPGA      1 @TIMECARD_LIB.TIMECARD(SCH_1):XP3R3V_FPGA
   2     SG      2 @TIMECARD_LIB.TIMECARD(SCH_1):SG

CAPACITOR-G107-0F226-CM,22UF,2A  I176  C158
   1 XP1R8V_FPGA      1 @TIMECARD_LIB.TIMECARD(SCH_1):XP1R8V_FPGA
   2     SG      2 @TIMECARD_LIB.TIMECARD(SCH_1):SG

CAPACITOR-G105-0F475-BM,4.7UF,A  I177  C120
   1 XP1R8V_FPGA_VCCAUX      1 @TIMECARD_LIB.TIMECARD(SCH_1):XP1R8V_FPGA_VCCAUX
   2     SG      2 @TIMECARD_LIB.TIMECARD(SCH_1):SG

CAPACITOR-G109-0G107-BM,100UF,A  I178  C174
   1 XP3R3V_FPGA      1 @TIMECARD_LIB.TIMECARD(SCH_1):XP3R3V_FPGA
   2     SG      2 @TIMECARD_LIB.TIMECARD(SCH_1):SG

CAPACITOR-G105-0B104-CK,0.1UF,A  I182  C201
   1 XP1R0V_FPGA_VCCINT      1 @TIMECARD_LIB.TIMECARD(SCH_1):XP1R0V_FPGA_VCCINT
   2     SG      2 @TIMECARD_LIB.TIMECARD(SCH_1):SG

CAPACITOR-G105-0B104-CK,0.1UF,A  I183  C207
   1 XP1R0V_FPGA_VCCINT      1 @TIMECARD_LIB.TIMECARD(SCH_1):XP1R0V_FPGA_VCCINT
   2     SG      2 @TIMECARD_LIB.TIMECARD(SCH_1):SG

CAPACITOR-G105-0B104-CK,0.1UF,A  I184  C214
   1 XP1R0V_FPGA_VCCINT      1 @TIMECARD_LIB.TIMECARD(SCH_1):XP1R0V_FPGA_VCCINT
   2     SG      2 @TIMECARD_LIB.TIMECARD(SCH_1):SG

CAPACITOR-G105-0B104-CK,0.1UF,A  I185  C222
   1 XP1R0V_FPGA_VCCINT      1 @TIMECARD_LIB.TIMECARD(SCH_1):XP1R0V_FPGA_VCCINT
   2     SG      2 @TIMECARD_LIB.TIMECARD(SCH_1):SG

CAPACITOR-G105-0B104-CK,0.1UF,A  I186  C109
   1 XP1R0V_FPGA_VCCINT      1 @TIMECARD_LIB.TIMECARD(SCH_1):XP1R0V_FPGA_VCCINT
   2     SG      2 @TIMECARD_LIB.TIMECARD(SCH_1):SG

CAPACITOR-G105-0B104-CK,0.1UF,A  I187  C114
   1 XP1R0V_FPGA_VCCINT      1 @TIMECARD_LIB.TIMECARD(SCH_1):XP1R0V_FPGA_VCCINT
   2     SG      2 @TIMECARD_LIB.TIMECARD(SCH_1):SG

CAPACITOR-G105-0B104-CK,0.1UF,A  I188  C121
   1 XP1R0V_FPGA_VCCINT      1 @TIMECARD_LIB.TIMECARD(SCH_1):XP1R0V_FPGA_VCCINT
   2     SG      2 @TIMECARD_LIB.TIMECARD(SCH_1):SG

CAPACITOR-G105-0B104-CK,0.1UF,A  I189  C129
   1 XP1R0V_FPGA_VCCINT      1 @TIMECARD_LIB.TIMECARD(SCH_1):XP1R0V_FPGA_VCCINT
   2     SG      2 @TIMECARD_LIB.TIMECARD(SCH_1):SG

CAPACITOR-G105-0B104-CK,0.1UF,A  I190  C133
   1 XP1R0V_FPGA_VCCINT      1 @TIMECARD_LIB.TIMECARD(SCH_1):XP1R0V_FPGA_VCCINT
   2     SG      2 @TIMECARD_LIB.TIMECARD(SCH_1):SG

CAPACITOR-G105-0B104-CK,0.1UF,A  I191  C141
   1 XP1R0V_FPGA_VCCINT      1 @TIMECARD_LIB.TIMECARD(SCH_1):XP1R0V_FPGA_VCCINT
   2     SG      2 @TIMECARD_LIB.TIMECARD(SCH_1):SG

CAPACITOR-G105-0B104-CK,0.1UF,A  I192  C147
   1 XP1R0V_FPGA_VCCINT      1 @TIMECARD_LIB.TIMECARD(SCH_1):XP1R0V_FPGA_VCCINT
   2     SG      2 @TIMECARD_LIB.TIMECARD(SCH_1):SG

CAPACITOR-G105-0B104-CK,0.1UF,A  I193  C152
   1 XP1R0V_FPGA_VCCINT      1 @TIMECARD_LIB.TIMECARD(SCH_1):XP1R0V_FPGA_VCCINT
   2     SG      2 @TIMECARD_LIB.TIMECARD(SCH_1):SG

CAPACITOR-G105-0B104-CK,0.1UF,A  I194  C156
   1 XP1R0V_FPGA_VCCINT      1 @TIMECARD_LIB.TIMECARD(SCH_1):XP1R0V_FPGA_VCCINT
   2     SG      2 @TIMECARD_LIB.TIMECARD(SCH_1):SG

CAPACITOR-G105-0B104-CK,0.1UF,A  I195  C161
   1 XP1R0V_FPGA_VCCINT      1 @TIMECARD_LIB.TIMECARD(SCH_1):XP1R0V_FPGA_VCCINT
   2     SG      2 @TIMECARD_LIB.TIMECARD(SCH_1):SG

CAPACITOR-G105-0B104-CK,0.1UF,A  I196  C166
   1 XP1R0V_FPGA_VCCINT      1 @TIMECARD_LIB.TIMECARD(SCH_1):XP1R0V_FPGA_VCCINT
   2     SG      2 @TIMECARD_LIB.TIMECARD(SCH_1):SG

CAPACITOR-G105-0B104-CK,0.1UF,A  I197  C169
   1 XP1R0V_FPGA_VCCINT      1 @TIMECARD_LIB.TIMECARD(SCH_1):XP1R0V_FPGA_VCCINT
   2     SG      2 @TIMECARD_LIB.TIMECARD(SCH_1):SG

CAPACITOR-G105-0B104-CK,0.1UF,A  I198  C171
   1 XP1R0V_FPGA_VCCINT      1 @TIMECARD_LIB.TIMECARD(SCH_1):XP1R0V_FPGA_VCCINT
   2     SG      2 @TIMECARD_LIB.TIMECARD(SCH_1):SG

CAPACITOR-G105-0B104-CK,0.1UF,A  I199  C200
   1 XP1R8V_FPGA_VCCAUX      1 @TIMECARD_LIB.TIMECARD(SCH_1):XP1R8V_FPGA_VCCAUX
   2     SG      2 @TIMECARD_LIB.TIMECARD(SCH_1):SG

CAPACITOR-G105-0B104-CK,0.1UF,A  I200  C206
   1 XP1R8V_FPGA_VCCAUX      1 @TIMECARD_LIB.TIMECARD(SCH_1):XP1R8V_FPGA_VCCAUX
   2     SG      2 @TIMECARD_LIB.TIMECARD(SCH_1):SG

CAPACITOR-G105-0B104-CK,0.1UF,A  I201  C212
   1 XP1R8V_FPGA_VCCAUX      1 @TIMECARD_LIB.TIMECARD(SCH_1):XP1R8V_FPGA_VCCAUX
   2     SG      2 @TIMECARD_LIB.TIMECARD(SCH_1):SG

CAPACITOR-G105-0B104-CK,0.1UF,A  I202  C219
   1 XP1R8V_FPGA_VCCAUX      1 @TIMECARD_LIB.TIMECARD(SCH_1):XP1R8V_FPGA_VCCAUX
   2     SG      2 @TIMECARD_LIB.TIMECARD(SCH_1):SG

CAPACITOR-G105-0B104-CK,0.1UF,A  I203  C106
   1 XP1R8V_FPGA_VCCAUX      1 @TIMECARD_LIB.TIMECARD(SCH_1):XP1R8V_FPGA_VCCAUX
   2     SG      2 @TIMECARD_LIB.TIMECARD(SCH_1):SG

CAPACITOR-G105-0B104-CK,0.1UF,A  I204  C113
   1 XP1R8V_FPGA_VCCAUX      1 @TIMECARD_LIB.TIMECARD(SCH_1):XP1R8V_FPGA_VCCAUX
   2     SG      2 @TIMECARD_LIB.TIMECARD(SCH_1):SG

CAPACITOR-G105-0B104-CK,0.1UF,A  I205  C202
   1 XP3R3V_FPGA      1 @TIMECARD_LIB.TIMECARD(SCH_1):XP3R3V_FPGA
   2     SG      2 @TIMECARD_LIB.TIMECARD(SCH_1):SG

CAPACITOR-G105-0B104-CK,0.1UF,A  I206  C210
   1 XP3R3V_FPGA      1 @TIMECARD_LIB.TIMECARD(SCH_1):XP3R3V_FPGA
   2     SG      2 @TIMECARD_LIB.TIMECARD(SCH_1):SG

CAPACITOR-G105-0B104-CK,0.1UF,A  I207  C215
   1 XP3R3V_FPGA      1 @TIMECARD_LIB.TIMECARD(SCH_1):XP3R3V_FPGA
   2     SG      2 @TIMECARD_LIB.TIMECARD(SCH_1):SG

CAPACITOR-G105-0B104-CK,0.1UF,A  I208  C103
   1 XP3R3V_FPGA      1 @TIMECARD_LIB.TIMECARD(SCH_1):XP3R3V_FPGA
   2     SG      2 @TIMECARD_LIB.TIMECARD(SCH_1):SG

CAPACITOR-G105-0B104-CK,0.1UF,A  I209  C112
   1 XP3R3V_FPGA      1 @TIMECARD_LIB.TIMECARD(SCH_1):XP3R3V_FPGA
   2     SG      2 @TIMECARD_LIB.TIMECARD(SCH_1):SG

CAPACITOR-G105-0B104-CK,0.1UF,A  I210  C119
   1 XP3R3V_FPGA      1 @TIMECARD_LIB.TIMECARD(SCH_1):XP3R3V_FPGA
   2     SG      2 @TIMECARD_LIB.TIMECARD(SCH_1):SG

CAPACITOR-G105-0B104-CK,0.1UF,A  I211  C126
   1 XP3R3V_FPGA      1 @TIMECARD_LIB.TIMECARD(SCH_1):XP3R3V_FPGA
   2     SG      2 @TIMECARD_LIB.TIMECARD(SCH_1):SG

CAPACITOR-G105-0B104-CK,0.1UF,A  I212  C132
   1 XP3R3V_FPGA      1 @TIMECARD_LIB.TIMECARD(SCH_1):XP3R3V_FPGA
   2     SG      2 @TIMECARD_LIB.TIMECARD(SCH_1):SG

CAPACITOR-G105-0B104-CK,0.1UF,A  I213  C139
   1 XP3R3V_FPGA      1 @TIMECARD_LIB.TIMECARD(SCH_1):XP3R3V_FPGA
   2     SG      2 @TIMECARD_LIB.TIMECARD(SCH_1):SG

CAPACITOR-G105-0B104-CK,0.1UF,A  I214  C144
   1 XP3R3V_FPGA      1 @TIMECARD_LIB.TIMECARD(SCH_1):XP3R3V_FPGA
   2     SG      2 @TIMECARD_LIB.TIMECARD(SCH_1):SG

CAPACITOR-G105-0B104-CK,0.1UF,A  I215  C149
   1 XP3R3V_FPGA      1 @TIMECARD_LIB.TIMECARD(SCH_1):XP3R3V_FPGA
   2     SG      2 @TIMECARD_LIB.TIMECARD(SCH_1):SG

CAPACITOR-G105-0B104-CK,0.1UF,A  I216  C203
   1 XP3R3V_FPGA      1 @TIMECARD_LIB.TIMECARD(SCH_1):XP3R3V_FPGA
   2     SG      2 @TIMECARD_LIB.TIMECARD(SCH_1):SG

CAPACITOR-G105-0B104-CK,0.1UF,A  I217  C211
   1 XP3R3V_FPGA      1 @TIMECARD_LIB.TIMECARD(SCH_1):XP3R3V_FPGA
   2     SG      2 @TIMECARD_LIB.TIMECARD(SCH_1):SG

CAPACITOR-G105-0B104-CK,0.1UF,A  I218  C216
   1 XP3R3V_FPGA      1 @TIMECARD_LIB.TIMECARD(SCH_1):XP3R3V_FPGA
   2     SG      2 @TIMECARD_LIB.TIMECARD(SCH_1):SG

CAPACITOR-G105-0B104-CK,0.1UF,A  I219  C221
   1 XP3R3V_FPGA      1 @TIMECARD_LIB.TIMECARD(SCH_1):XP3R3V_FPGA
   2     SG      2 @TIMECARD_LIB.TIMECARD(SCH_1):SG

CAPACITOR-G105-0B104-CK,0.1UF,A  I220  C107
   1 XP3R3V_FPGA      1 @TIMECARD_LIB.TIMECARD(SCH_1):XP3R3V_FPGA
   2     SG      2 @TIMECARD_LIB.TIMECARD(SCH_1):SG

CAPACITOR-G105-0B104-CK,0.1UF,A  I221  C115
   1 XP3R3V_FPGA      1 @TIMECARD_LIB.TIMECARD(SCH_1):XP3R3V_FPGA
   2     SG      2 @TIMECARD_LIB.TIMECARD(SCH_1):SG

CAPACITOR-G105-0B104-CK,0.1UF,A  I222  C223
   1 XP3R3V_FPGA      1 @TIMECARD_LIB.TIMECARD(SCH_1):XP3R3V_FPGA
   2     SG      2 @TIMECARD_LIB.TIMECARD(SCH_1):SG

CAPACITOR-G105-0B104-CK,0.1UF,A  I223  C130
   1 XP3R3V_FPGA      1 @TIMECARD_LIB.TIMECARD(SCH_1):XP3R3V_FPGA
   2     SG      2 @TIMECARD_LIB.TIMECARD(SCH_1):SG

CAPACITOR-G105-0B104-CK,0.1UF,A  I224  C134
   1 XP3R3V_FPGA      1 @TIMECARD_LIB.TIMECARD(SCH_1):XP3R3V_FPGA
   2     SG      2 @TIMECARD_LIB.TIMECARD(SCH_1):SG

CAPACITOR-G105-0B104-CK,0.1UF,A  I225  C140
   1 XP3R3V_FPGA      1 @TIMECARD_LIB.TIMECARD(SCH_1):XP3R3V_FPGA
   2     SG      2 @TIMECARD_LIB.TIMECARD(SCH_1):SG

CAPACITOR-G105-0B104-CK,0.1UF,A  I226  C145
   1 XP3R3V_FPGA      1 @TIMECARD_LIB.TIMECARD(SCH_1):XP3R3V_FPGA
   2     SG      2 @TIMECARD_LIB.TIMECARD(SCH_1):SG

CAPACITOR-G105-0B104-CK,0.1UF,A  I227  C153
   1 XP3R3V_FPGA      1 @TIMECARD_LIB.TIMECARD(SCH_1):XP3R3V_FPGA
   2     SG      2 @TIMECARD_LIB.TIMECARD(SCH_1):SG

CAPACITOR-G105-0B104-CK,0.1UF,A  I228  C157
   1 XP3R3V_FPGA      1 @TIMECARD_LIB.TIMECARD(SCH_1):XP3R3V_FPGA
   2     SG      2 @TIMECARD_LIB.TIMECARD(SCH_1):SG

CAPACITOR-G105-0B104-CK,0.1UF,A  I229  C162
   1 XP3R3V_FPGA      1 @TIMECARD_LIB.TIMECARD(SCH_1):XP3R3V_FPGA
   2     SG      2 @TIMECARD_LIB.TIMECARD(SCH_1):SG

CAPACITOR-G105-0B104-CK,0.1UF,A  I230  C165
   1 XP3R3V_FPGA      1 @TIMECARD_LIB.TIMECARD(SCH_1):XP3R3V_FPGA
   2     SG      2 @TIMECARD_LIB.TIMECARD(SCH_1):SG

CAPACITOR-G105-0B104-CK,0.1UF,A  I231  C204
   1 XP2R5V_FPGA      1 @TIMECARD_LIB.TIMECARD(SCH_1):XP2R5V_FPGA
   2     SG      2 @TIMECARD_LIB.TIMECARD(SCH_1):SG

CAPACITOR-G105-0B104-CK,0.1UF,A  I232  C208
   1 XP2R5V_FPGA      1 @TIMECARD_LIB.TIMECARD(SCH_1):XP2R5V_FPGA
   2     SG      2 @TIMECARD_LIB.TIMECARD(SCH_1):SG

CAPACITOR-G105-0B104-CK,0.1UF,A  I233  C213
   1 XP2R5V_FPGA      1 @TIMECARD_LIB.TIMECARD(SCH_1):XP2R5V_FPGA
   2     SG      2 @TIMECARD_LIB.TIMECARD(SCH_1):SG

CAPACITOR-G105-0B104-CK,0.1UF,A  I234  C220
   1 XP2R5V_FPGA      1 @TIMECARD_LIB.TIMECARD(SCH_1):XP2R5V_FPGA
   2     SG      2 @TIMECARD_LIB.TIMECARD(SCH_1):SG

CAPACITOR-G105-0B104-CK,0.1UF,A  I235  C108
   1 XP2R5V_FPGA      1 @TIMECARD_LIB.TIMECARD(SCH_1):XP2R5V_FPGA
   2     SG      2 @TIMECARD_LIB.TIMECARD(SCH_1):SG

CAPACITOR-G105-0B104-CK,0.1UF,A  I236  C116
   1 XP2R5V_FPGA      1 @TIMECARD_LIB.TIMECARD(SCH_1):XP2R5V_FPGA
   2     SG      2 @TIMECARD_LIB.TIMECARD(SCH_1):SG

CAPACITOR-G105-0B104-CK,0.1UF,A  I237  C122
   1 XP2R5V_FPGA      1 @TIMECARD_LIB.TIMECARD(SCH_1):XP2R5V_FPGA
   2     SG      2 @TIMECARD_LIB.TIMECARD(SCH_1):SG

CAPACITOR-G105-0B104-CK,0.1UF,A  I238  C127
   1 XP2R5V_FPGA      1 @TIMECARD_LIB.TIMECARD(SCH_1):XP2R5V_FPGA
   2     SG      2 @TIMECARD_LIB.TIMECARD(SCH_1):SG

CAPACITOR-G105-0B104-CK,0.1UF,A  I239  C135
   1 XP2R5V_FPGA      1 @TIMECARD_LIB.TIMECARD(SCH_1):XP2R5V_FPGA
   2     SG      2 @TIMECARD_LIB.TIMECARD(SCH_1):SG

CAPACITOR-G105-0B104-CK,0.1UF,A  I240  C142
   1 XP2R5V_FPGA      1 @TIMECARD_LIB.TIMECARD(SCH_1):XP2R5V_FPGA
   2     SG      2 @TIMECARD_LIB.TIMECARD(SCH_1):SG

CAPACITOR-G105-0B104-CK,0.1UF,A  I241  C146
   1 XP2R5V_FPGA      1 @TIMECARD_LIB.TIMECARD(SCH_1):XP2R5V_FPGA
   2     SG      2 @TIMECARD_LIB.TIMECARD(SCH_1):SG

CAPACITOR-G105-0B104-CK,0.1UF,A  I242  C151
   1 XP2R5V_FPGA      1 @TIMECARD_LIB.TIMECARD(SCH_1):XP2R5V_FPGA
   2     SG      2 @TIMECARD_LIB.TIMECARD(SCH_1):SG

CAPACITOR-G105-0F475-BM,4.7UF,A  I243  C128
   1 XP1R8V_FPGA_VCCAUX      1 @TIMECARD_LIB.TIMECARD(SCH_1):XP1R8V_FPGA_VCCAUX
   2     SG      2 @TIMECARD_LIB.TIMECARD(SCH_1):SG

CAPACITOR-G105-0F475-BM,4.7UF,A  I245  C160
   1 XP2R5V_FPGA      1 @TIMECARD_LIB.TIMECARD(SCH_1):XP2R5V_FPGA
   2     SG      2 @TIMECARD_LIB.TIMECARD(SCH_1):SG

CAPACITOR-G105-0F475-BM,4.7UF,A  I246  C117
   1 FPGA_MGTAVTT      1 @TIMECARD_LIB.TIMECARD(SCH_1):FPGA_MGTAVTT
   2     SG      2 @TIMECARD_LIB.TIMECARD(SCH_1):SG

CAPACITOR-G105-0F475-BM,4.7UF,A  I248  C131
   1 XP1R0V_FPGA_MGTAVCC      1 @TIMECARD_LIB.TIMECARD(SCH_1):XP1R0V_FPGA_MGTAVCC
   2     SG      2 @TIMECARD_LIB.TIMECARD(SCH_1):SG

CAPACITOR-G105-0B104-CK,0.1UF,A  I249  C136
   1 XP1R2V_FPGA      1 @TIMECARD_LIB.TIMECARD(SCH_1):XP1R2V_FPGA
   2     SG      2 @TIMECARD_LIB.TIMECARD(SCH_1):SG

CAPACITOR-G105-0B104-CK,0.1UF,A  I250  C148
   1 XP1R0V_FPGA      1 @TIMECARD_LIB.TIMECARD(SCH_1):XP1R0V_FPGA
   2     SG      2 @TIMECARD_LIB.TIMECARD(SCH_1):SG

CAPACITOR-G105-0B104-CK,0.1UF,A  I251  C218
   1 XP1R0V_FPGA_MGTAVCC      1 @TIMECARD_LIB.TIMECARD(SCH_1):XP1R0V_FPGA_MGTAVCC
   2     SG      2 @TIMECARD_LIB.TIMECARD(SCH_1):SG

CAPACITOR-G105-0B104-CK,0.1UF,A  I252  C105
   1 XP1R0V_FPGA_MGTAVCC      1 @TIMECARD_LIB.TIMECARD(SCH_1):XP1R0V_FPGA_MGTAVCC
   2     SG      2 @TIMECARD_LIB.TIMECARD(SCH_1):SG

CAPACITOR-G105-0B104-CK,0.1UF,A  I253  C111
   1 XP1R0V_FPGA_MGTAVCC      1 @TIMECARD_LIB.TIMECARD(SCH_1):XP1R0V_FPGA_MGTAVCC
   2     SG      2 @TIMECARD_LIB.TIMECARD(SCH_1):SG

CAPACITOR-G105-0B104-CK,0.1UF,A  I254  C118
   1 XP1R0V_FPGA_MGTAVCC      1 @TIMECARD_LIB.TIMECARD(SCH_1):XP1R0V_FPGA_MGTAVCC
   2     SG      2 @TIMECARD_LIB.TIMECARD(SCH_1):SG

CAPACITOR-G105-0B104-CK,0.1UF,A  I255  C124
   1 XP1R0V_FPGA_MGTAVCC      1 @TIMECARD_LIB.TIMECARD(SCH_1):XP1R0V_FPGA_MGTAVCC
   2     SG      2 @TIMECARD_LIB.TIMECARD(SCH_1):SG

CAPACITOR-G105-0B104-CK,0.1UF,A  I256  C110
   1 FPGA_MGTAVTT      1 @TIMECARD_LIB.TIMECARD(SCH_1):FPGA_MGTAVTT
   2     SG      2 @TIMECARD_LIB.TIMECARD(SCH_1):SG

CAPACITOR-G105-0B104-CK,0.1UF,A  I257  C104
   1 FPGA_MGTAVTT      1 @TIMECARD_LIB.TIMECARD(SCH_1):FPGA_MGTAVTT
   2     SG      2 @TIMECARD_LIB.TIMECARD(SCH_1):SG

CAPACITOR-G105-0B104-CK,0.1UF,A  I258  C217
   1 FPGA_MGTAVTT      1 @TIMECARD_LIB.TIMECARD(SCH_1):FPGA_MGTAVTT
   2     SG      2 @TIMECARD_LIB.TIMECARD(SCH_1):SG

CAPACITOR-G105-0B104-CK,0.1UF,A  I259  C209
   1 FPGA_MGTAVTT      1 @TIMECARD_LIB.TIMECARD(SCH_1):FPGA_MGTAVTT
   2     SG      2 @TIMECARD_LIB.TIMECARD(SCH_1):SG

CAPACITOR-G105-0B104-CK,0.1UF,A  I260  C205
   1 FPGA_MGTAVTT      1 @TIMECARD_LIB.TIMECARD(SCH_1):FPGA_MGTAVTT
   2     SG      2 @TIMECARD_LIB.TIMECARD(SCH_1):SG

CAPACITOR-G107-0F476-AM,47UF,2A  I264  C125
   1 FPGA_MGTAVTT      1 @TIMECARD_LIB.TIMECARD(SCH_1):FPGA_MGTAVTT
   2     SG      2 @TIMECARD_LIB.TIMECARD(SCH_1):SG

CAPACITOR-G107-0F476-AM,47UF,2A  I265  C143
   1 XP1R2V_FPGA      1 @TIMECARD_LIB.TIMECARD(SCH_1):XP1R2V_FPGA
   2     SG      2 @TIMECARD_LIB.TIMECARD(SCH_1):SG

CAPACITOR-G107-0F476-AM,47UF,2A  I266  C155
   1 XP1R0V_FPGA      1 @TIMECARD_LIB.TIMECARD(SCH_1):XP1R0V_FPGA
   2     SG      2 @TIMECARD_LIB.TIMECARD(SCH_1):SG

CAPACITOR-G107-0F226-CM,22UF,2A  I267  C168
   1 XP2R5V_FPGA      1 @TIMECARD_LIB.TIMECARD(SCH_1):XP2R5V_FPGA
   2     SG      2 @TIMECARD_LIB.TIMECARD(SCH_1):SG

CAPACITOR-G107-0F226-CM,22UF,2A  I268  C164
   1 XP2R5V_FPGA      1 @TIMECARD_LIB.TIMECARD(SCH_1):XP2R5V_FPGA
   2     SG      2 @TIMECARD_LIB.TIMECARD(SCH_1):SG

CAPACITOR-G105-0F475-BM,4.7UF,A  I270  C154
   1 XP3R3V_FPGA      1 @TIMECARD_LIB.TIMECARD(SCH_1):XP3R3V_FPGA
   2     SG      2 @TIMECARD_LIB.TIMECARD(SCH_1):SG

CAPACITOR-G105-0F475-BM,4.7UF,A  I271  C159
   1 XP3R3V_FPGA      1 @TIMECARD_LIB.TIMECARD(SCH_1):XP3R3V_FPGA
   2     SG      2 @TIMECARD_LIB.TIMECARD(SCH_1):SG

CAPACITOR-G105-0F475-BM,4.7UF,A  I272  C163
   1 XP3R3V_FPGA      1 @TIMECARD_LIB.TIMECARD(SCH_1):XP3R3V_FPGA
   2     SG      2 @TIMECARD_LIB.TIMECARD(SCH_1):SG

CAPACITOR-G105-0F475-BM,4.7UF,A  I273  C167
   1 XP3R3V_FPGA      1 @TIMECARD_LIB.TIMECARD(SCH_1):XP3R3V_FPGA
   2     SG      2 @TIMECARD_LIB.TIMECARD(SCH_1):SG

CAPACITOR-G107-0F476-AM,47UF,2A  I274  C179
   1 XP1R0V_FPGA      1 @TIMECARD_LIB.TIMECARD(SCH_1):XP1R0V_FPGA
   2     SG      2 @TIMECARD_LIB.TIMECARD(SCH_1):SG

CAPACITOR-G105-0F475-BM,4.7UF,A  I275  C138
   1 XP1R8V_FPGA_VCCAUX      1 @TIMECARD_LIB.TIMECARD(SCH_1):XP1R8V_FPGA_VCCAUX
   2     SG      2 @TIMECARD_LIB.TIMECARD(SCH_1):SG

CAPACITOR-G105-0B104-CK,0.1UF,A  I276  C150
   1 XP1R8V_FPGA      1 @TIMECARD_LIB.TIMECARD(SCH_1):XP1R8V_FPGA
   2     SG      2 @TIMECARD_LIB.TIMECARD(SCH_1):SG

CAPACITOR-G109-0G107-BM,100UF,A  I277  C177
   1 XP1R0V_FPGA_VCCINT      1 @TIMECARD_LIB.TIMECARD(SCH_1):XP1R0V_FPGA_VCCINT
   2     SG      2 @TIMECARD_LIB.TIMECARD(SCH_1):SG

CAPACITOR-G107-0F476-AM,47UF,2A  I280  C173
   1 XP1R0V_FPGA_VCCINT      1 @TIMECARD_LIB.TIMECARD(SCH_1):XP1R0V_FPGA_VCCINT
   2     SG      2 @TIMECARD_LIB.TIMECARD(SCH_1):SG

CAPACITOR-G107-0F476-AM,47UF,2A  I281  C137
   1 XP1R0V_FPGA_MGTAVCC      1 @TIMECARD_LIB.TIMECARD(SCH_1):XP1R0V_FPGA_MGTAVCC
   2     SG      2 @TIMECARD_LIB.TIMECARD(SCH_1):SG

CAPACITOR-G105-0F475-BM,4.7UF,A  I282  C170
   1 XP3R3V_FPGA      1 @TIMECARD_LIB.TIMECARD(SCH_1):XP3R3V_FPGA
   2     SG      2 @TIMECARD_LIB.TIMECARD(SCH_1):SG

CAPACITOR-G105-0B104-CK,0.1UF,A  I283  C178
   1 XP1R0V_FPGA      1 @TIMECARD_LIB.TIMECARD(SCH_1):XP1R0V_FPGA
   2     SG      2 @TIMECARD_LIB.TIMECARD(SCH_1):SG

CAPACITOR-G107-0F226-CM,22UF,2A  I290  C291
   1 XP2R5V_FPGA      1 @TIMECARD_LIB.TIMECARD(SCH_1):XP2R5V_FPGA
   2     SG      2 @TIMECARD_LIB.TIMECARD(SCH_1):SG

CAPACITOR-G107-0F226-CM,22UF,2A  I291  C292
   1 XP2R5V_FPGA      1 @TIMECARD_LIB.TIMECARD(SCH_1):XP2R5V_FPGA
   2     SG      2 @TIMECARD_LIB.TIMECARD(SCH_1):SG

CAPACITOR-G105-0F475-BM,4.7UF,A  I292  C93
   1 XP2R5V_FPGA      1 @TIMECARD_LIB.TIMECARD(SCH_1):XP2R5V_FPGA
   2     SG      2 @TIMECARD_LIB.TIMECARD(SCH_1):SG


DRAWING: @TIMECARD_LIB.TIMECARD(SCH_1):PAGE522 

CAPACITOR-G105-0B104-CK,0.1UF,A  I142  C254
   1 OSC_125M_CLKN      1 @TIMECARD_LIB.TIMECARD(SCH_1):OSC_125M_CLKN
   2 MHZ125CLKN_CLKIN      2 @TIMECARD_LIB.TIMECARD(SCH_1):MHZ125CLKN_CLKIN

CAPACITOR-G105-0B104-CK,0.1UF,A  I143  C253
   1 OSC_125M_CLKP      1 @TIMECARD_LIB.TIMECARD(SCH_1):OSC_125M_CLKP
   2 MHZ125CLKP_CLKIN      2 @TIMECARD_LIB.TIMECARD(SCH_1):MHZ125CLKP_CLKIN

OSC6P_V2-A130-00003-AW  I144  Y3
   1 CLK_200M_OE     OE @TIMECARD_LIB.TIMECARD(SCH_1):CLK_200M_OE
   2     NC     NC     NC
   3     SG    GND @TIMECARD_LIB.TIMECARD(SCH_1):SG
   4 OSC_200M_CLKP  OUT_P @TIMECARD_LIB.TIMECARD(SCH_1):OSC_200M_CLKP
   5 OSC_200M_CLKN  OUT_N @TIMECARD_LIB.TIMECARD(SCH_1):OSC_200M_CLKN
   6 VDD3V3_OSC_200M    VDD @TIMECARD_LIB.TIMECARD(SCH_1):VDD3V3_OSC_200M

OSC6P_V2-A130-00004-AW  I145  Y4
   1 CLK_125M_OE     OE @TIMECARD_LIB.TIMECARD(SCH_1):CLK_125M_OE
   2     NC     NC     NC
   3     SG    GND @TIMECARD_LIB.TIMECARD(SCH_1):SG
   4 OSC_125M_CLKP  OUT_P @TIMECARD_LIB.TIMECARD(SCH_1):OSC_125M_CLKP
   5 OSC_125M_CLKN  OUT_N @TIMECARD_LIB.TIMECARD(SCH_1):OSC_125M_CLKN
   6 VDD3V3_OSC_125M    VDD @TIMECARD_LIB.TIMECARD(SCH_1):VDD3V3_OSC_125M

FERRITEBEAD-G191-10097-01,600OA  I146  L14
   1 VDD3V3_OSC_200M      1 @TIMECARD_LIB.TIMECARD(SCH_1):VDD3V3_OSC_200M
   2 XP3R3V      2 @TIMECARD_LIB.TIMECARD(SCH_1):XP3R3V

CAPACITOR-G105-0B104-EK,0.1UF,A  I147  C248
   1 VDD3V3_OSC_200M      1 @TIMECARD_LIB.TIMECARD(SCH_1):VDD3V3_OSC_200M
   2     SG      2 @TIMECARD_LIB.TIMECARD(SCH_1):SG

RESISTOR-G155-14701-01,4.7KOHMA  I149  R235
   2 CLK_200M_OE      2 @TIMECARD_LIB.TIMECARD(SCH_1):CLK_200M_OE
   1 VDD3V3_OSC_200M      1 @TIMECARD_LIB.TIMECARD(SCH_1):VDD3V3_OSC_200M

CAPACITOR-G105-0C106-BM,10UF,2A  I151  C246
   1 VDD3V3_OSC_200M      1 @TIMECARD_LIB.TIMECARD(SCH_1):VDD3V3_OSC_200M
   2     SG      2 @TIMECARD_LIB.TIMECARD(SCH_1):SG

CAPACITOR-G105-0B104-EK,0.1UF,A  I152  C244
   1 XP3R3V      1 @TIMECARD_LIB.TIMECARD(SCH_1):XP3R3V
   2     SG      2 @TIMECARD_LIB.TIMECARD(SCH_1):SG

CAPACITOR-G105-0B104-EK,0.1UF,A  I153  C245
   1 XP3R3V      1 @TIMECARD_LIB.TIMECARD(SCH_1):XP3R3V
   2     SG      2 @TIMECARD_LIB.TIMECARD(SCH_1):SG

CAPACITOR-G105-0C106-BM,10UF,2A  I154  C247
   1 VDD3V3_OSC_125M      1 @TIMECARD_LIB.TIMECARD(SCH_1):VDD3V3_OSC_125M
   2     SG      2 @TIMECARD_LIB.TIMECARD(SCH_1):SG

RESISTOR-G155-14701-01,4.7KOHMA  I156  R236
   2 CLK_125M_OE      2 @TIMECARD_LIB.TIMECARD(SCH_1):CLK_125M_OE
   1 VDD3V3_OSC_125M      1 @TIMECARD_LIB.TIMECARD(SCH_1):VDD3V3_OSC_125M

CAPACITOR-G105-0B104-EK,0.1UF,A  I158  C249
   1 VDD3V3_OSC_125M      1 @TIMECARD_LIB.TIMECARD(SCH_1):VDD3V3_OSC_125M
   2     SG      2 @TIMECARD_LIB.TIMECARD(SCH_1):SG

FERRITEBEAD-G191-10097-01,600OA  I159  L10
   1 VDD3V3_OSC_125M      1 @TIMECARD_LIB.TIMECARD(SCH_1):VDD3V3_OSC_125M
   2 XP3R3V      2 @TIMECARD_LIB.TIMECARD(SCH_1):XP3R3V

CAPACITOR-G105-0B104-CK,0.1UF,A  I160  C252
   1 OSC_200M_CLKN      1 @TIMECARD_LIB.TIMECARD(SCH_1):OSC_200M_CLKN
   2 MHZ200CLKN_CLKIN      2 @TIMECARD_LIB.TIMECARD(SCH_1):MHZ200CLKN_CLKIN

CAPACITOR-G105-0B104-CK,0.1UF,A  I161  C251
   1 OSC_200M_CLKP      1 @TIMECARD_LIB.TIMECARD(SCH_1):OSC_200M_CLKP
   2 MHZ200CLKP_CLKIN      2 @TIMECARD_LIB.TIMECARD(SCH_1):MHZ200CLKP_CLKIN

RESISTOR-G155-11500-01,150OHM,A  I169  R239
   2     SG      2 @TIMECARD_LIB.TIMECARD(SCH_1):SG
   1 OSC_200M_CLKN      1 @TIMECARD_LIB.TIMECARD(SCH_1):OSC_200M_CLKN

RESISTOR-G155-11500-01,150OHM,A  I170  R241
   2     SG      2 @TIMECARD_LIB.TIMECARD(SCH_1):SG
   1 OSC_200M_CLKP      1 @TIMECARD_LIB.TIMECARD(SCH_1):OSC_200M_CLKP

RESISTOR-G155-11500-01,150OHM,A  I172  R240
   2     SG      2 @TIMECARD_LIB.TIMECARD(SCH_1):SG
   1 OSC_125M_CLKN      1 @TIMECARD_LIB.TIMECARD(SCH_1):OSC_125M_CLKN

RESISTOR-G155-11500-01,150OHM,A  I174  R242
   2     SG      2 @TIMECARD_LIB.TIMECARD(SCH_1):SG
   1 OSC_125M_CLKP      1 @TIMECARD_LIB.TIMECARD(SCH_1):OSC_125M_CLKP


DRAWING: @TIMECARD_LIB.TIMECARD(SCH_1):PAGE33 

MEC_MTH8-MTH125C236N_V8-MTH125A  I1  ME11
   2     SG      2 @TIMECARD_LIB.TIMECARD(SCH_1):SG
   3     SG      3 @TIMECARD_LIB.TIMECARD(SCH_1):SG
   1     SG      1 @TIMECARD_LIB.TIMECARD(SCH_1):SG
   4     SG      4 @TIMECARD_LIB.TIMECARD(SCH_1):SG
   6     SG      6 @TIMECARD_LIB.TIMECARD(SCH_1):SG
   5     SG      5 @TIMECARD_LIB.TIMECARD(SCH_1):SG
   7     SG      7 @TIMECARD_LIB.TIMECARD(SCH_1):SG
   8     SG      8 @TIMECARD_LIB.TIMECARD(SCH_1):SG

MEC_MTH8-MTH125C236N_V8-MTH125A  I2  ME12
   2     SG      2 @TIMECARD_LIB.TIMECARD(SCH_1):SG
   3     SG      3 @TIMECARD_LIB.TIMECARD(SCH_1):SG
   1     SG      1 @TIMECARD_LIB.TIMECARD(SCH_1):SG
   4     SG      4 @TIMECARD_LIB.TIMECARD(SCH_1):SG
   6     SG      6 @TIMECARD_LIB.TIMECARD(SCH_1):SG
   5     SG      5 @TIMECARD_LIB.TIMECARD(SCH_1):SG
   7     SG      7 @TIMECARD_LIB.TIMECARD(SCH_1):SG
   8     SG      8 @TIMECARD_LIB.TIMECARD(SCH_1):SG

MEC_MTH8-MTH125C236N_V8-MTH125A  I5  ME10
   2     SG      2 @TIMECARD_LIB.TIMECARD(SCH_1):SG
   3     SG      3 @TIMECARD_LIB.TIMECARD(SCH_1):SG
   1     SG      1 @TIMECARD_LIB.TIMECARD(SCH_1):SG
   4     SG      4 @TIMECARD_LIB.TIMECARD(SCH_1):SG
   6     SG      6 @TIMECARD_LIB.TIMECARD(SCH_1):SG
   5     SG      5 @TIMECARD_LIB.TIMECARD(SCH_1):SG
   7     SG      7 @TIMECARD_LIB.TIMECARD(SCH_1):SG
   8     SG      8 @TIMECARD_LIB.TIMECARD(SCH_1):SG

MEC_MTH8-MTH125C236N_V8-MTH125A  I7  ME9
   2     SG      2 @TIMECARD_LIB.TIMECARD(SCH_1):SG
   3     SG      3 @TIMECARD_LIB.TIMECARD(SCH_1):SG
   1     SG      1 @TIMECARD_LIB.TIMECARD(SCH_1):SG
   4     SG      4 @TIMECARD_LIB.TIMECARD(SCH_1):SG
   6     SG      6 @TIMECARD_LIB.TIMECARD(SCH_1):SG
   5     SG      5 @TIMECARD_LIB.TIMECARD(SCH_1):SG
   7     SG      7 @TIMECARD_LIB.TIMECARD(SCH_1):SG
   8     SG      8 @TIMECARD_LIB.TIMECARD(SCH_1):SG

NULL-G380-10013-01  I47  SP54
NULL-G380-10013-01  I48  SP55
NULL-G380-10013-01  I49  SP57
NULL-G380-10013-01  I50  SP56
NULL-G380-10013-01  I51  SP61
NULL-G380-10013-01  I52  SP60
NULL-G380-10013-01  I53  SP59
NULL-G380-10013-01  I54  SP58
NULL-G380-10013-01  I55  SP62
NULL-G380-10013-01  I56  SP63
NULL-G380-10013-01  I57  SP64
NULL-G380-10013-01  I58  SP65
NULL-G380-10013-01  I59  SP47
NULL-G380-10013-01  I60  SP48
NULL-G380-10013-01  I61  SP53
NULL-G380-10013-01  I62  SP52
NULL-G380-10013-01  I63  SP51
NULL-G380-10013-01  I64  SP50
NULL-G380-10013-01  I65  SP49
NULL-G380-10013-01  I66  SP46
NULL-G380-10013-01  I67  SP45
NULL-G380-10013-01  I68  SP44
NULL-G380-10013-01  I69  SP43
NULL-G380-10013-01  I70  SP42
NULL-G380-10013-01  I83  SP71
NULL-G380-10013-01  I84  SP70
NULL-G380-10013-01  I85  SP69
NULL-G380-10013-01  I89  SP68
NULL-G380-10013-01  I90  SP67
NULL-G380-10013-01  I93  SP66
MEC_NPTH-MTH100C240N-MTH100C24A  I120  ME8
MEC_NPTH-MTH100C240N-MTH100C24A  I121  ME7
MEC_NPTH-MTH100C240N-MTH100C24A  I122  ME6
MEC_NPTH-MTH100C240N-MTH100C24A  I123  ME5
NUT-G340-10437-01  I125  ME3
   1     SG      1 @TIMECARD_LIB.TIMECARD(SCH_1):SG

NUT-G340-10437-01  I126  ME4
   1     SG      1 @TIMECARD_LIB.TIMECARD(SCH_1):SG

NUT-G340-10437-01  I127  ME1
   1     SG      1 @TIMECARD_LIB.TIMECARD(SCH_1):SG

NUT-G340-10437-01  I129  ME2
   1     SG      1 @TIMECARD_LIB.TIMECARD(SCH_1):SG

SOLDER_PREFORM-G380-10015-01  I130  SP4
   1     NC      1     NC
   2     NC      2     NC

SOLDER_PREFORM-G380-10015-01  I131  SP5
   1     NC      1     NC
   2     NC      2     NC

SOLDER_PREFORM-G380-10015-01  I132  SP7
   1     NC      1     NC
   2     NC      2     NC

SOLDER_PREFORM-G380-10015-01  I133  SP6
   1     NC      1     NC
   2     NC      2     NC

SOLDER_PREFORM-G380-10015-01  I134  SP8
   1     NC      1     NC
   2     NC      2     NC

SOLDER_PREFORM-G380-10015-01  I135  SP9
   1     NC      1     NC
   2     NC      2     NC

SOLDER_PREFORM-G380-10015-01  I136  SP11
   1     NC      1     NC
   2     NC      2     NC

SOLDER_PREFORM-G380-10015-01  I137  SP10
   1     NC      1     NC
   2     NC      2     NC

SOLDER_PREFORM-G380-10015-01  I138  SP15
   1     NC      1     NC
   2     NC      2     NC

SOLDER_PREFORM-G380-10015-01  I139  SP14
   1     NC      1     NC
   2     NC      2     NC

SOLDER_PREFORM-G380-10015-01  I140  SP13
   1     NC      1     NC
   2     NC      2     NC

SOLDER_PREFORM-G380-10015-01  I141  SP12
   1     NC      1     NC
   2     NC      2     NC

SOLDER_PREFORM-G380-10015-01  I142  SP17
   1     NC      1     NC
   2     NC      2     NC

SOLDER_PREFORM-G380-10015-01  I143  SP27
   1     NC      1     NC
   2     NC      2     NC

SOLDER_PREFORM-G380-10015-01  I144  SP26
   1     NC      1     NC
   2     NC      2     NC

SOLDER_PREFORM-G380-10015-01  I145  SP25
   1     NC      1     NC
   2     NC      2     NC

SOLDER_PREFORM-G380-10015-01  I146  SP24
   1     NC      1     NC
   2     NC      2     NC

SOLDER_PREFORM-G380-10015-01  I147  SP23
   1     NC      1     NC
   2     NC      2     NC

SOLDER_PREFORM-G380-10015-01  I148  SP22
   1     NC      1     NC
   2     NC      2     NC

SOLDER_PREFORM-G380-10015-01  I149  SP20
   1     NC      1     NC
   2     NC      2     NC

SOLDER_PREFORM-G380-10015-01  I150  SP21
   1     NC      1     NC
   2     NC      2     NC

SOLDER_PREFORM-G380-10015-01  I151  SP19
   1     NC      1     NC
   2     NC      2     NC

SOLDER_PREFORM-G380-10015-01  I152  SP18
   1     NC      1     NC
   2     NC      2     NC

SOLDER_PREFORM-G380-10015-01  I153  SP16
   1     NC      1     NC
   2     NC      2     NC

SOLDER_PREFORM-G380-10015-01  I155  SP41
   1     NC      1     NC
   2     NC      2     NC

SOLDER_PREFORM-G380-10015-01  I159  SP38
   1     NC      1     NC
   2     NC      2     NC

SOLDER_PREFORM-G380-10015-01  I161  SP37
   1     NC      1     NC
   2     NC      2     NC

SOLDER_PREFORM-G380-10015-01  I163  SP36
   1     NC      1     NC
   2     NC      2     NC

SOLDER_PREFORM-G380-10015-01  I165  SP35
   1     NC      1     NC
   2     NC      2     NC

SOLDER_PREFORM-G380-10015-01  I167  SP34
   1     NC      1     NC
   2     NC      2     NC

SOLDER_PREFORM-G380-10015-01  I169  SP33
   1     NC      1     NC
   2     NC      2     NC

SOLDER_PREFORM-G380-10015-01  I171  SP32
   1     NC      1     NC
   2     NC      2     NC

SOLDER_PREFORM-G380-10015-01  I172  SP31
   1     NC      1     NC
   2     NC      2     NC

SOLDER_PREFORM-G380-10015-01  I173  SP30
   1     NC      1     NC
   2     NC      2     NC

SOLDER_PREFORM-G380-10015-01  I174  SP29
   1     NC      1     NC
   2     NC      2     NC

SOLDER_PREFORM-G380-10015-01  I175  SP28
   1     NC      1     NC
   2     NC      2     NC

SOLDER_PREFORM-G380-10015-01  I176  SP40
   1     NC      1     NC
   2     NC      2     NC

SOLDER_PREFORM-G380-10015-01  I177  SP39
   1     NC      1     NC
   2     NC      2     NC

END LOGICAL PART CROSS REFERENCE
GLOBAL SIGNAL CROSS REFERENCE - 05-Sep-2022 AT 15:23:30
ANALOG_TUNING_IN @TIMECARD_LIB.TIMECARD(SCH_1):ANALOG_TUNING_IN
   R91    1      1 RESISTOR-G155-133R0-01,33OHM,1%   I187 @TIMECARD_LIB.TIMECARD(SCH_1):PAGE527
MAC_PIN1    1      1 NUT-A200-00029-FB   I227 @TIMECARD_LIB.TIMECARD(SCH_1):PAGE527

ANT1_IN @TIMECARD_LIB.TIMECARD(SCH_1):ANT1_IN
   U24 AA21 IO_L8N_T1_D12_14 XC7A200T_2FBG484C_FBG484-G240-A     I2 @TIMECARD_LIB.TIMECARD(SCH_1):PAGE161
  R371    2      2 RESISTOR-G155-149R9-01,49.9OHMA   I258 @TIMECARD_LIB.TIMECARD(SCH_1):PAGE12
  R504    1      1 RESISTOR-G155-14701-01,4.7KOHMA   I244 @TIMECARD_LIB.TIMECARD(SCH_1):PAGE161

ANT1_OUT @TIMECARD_LIB.TIMECARD(SCH_1):ANT1_OUT
   U24  V10 IO_L10P_T1_13 XC7A200T_2FBG484C_FBG484-G240-A     I2 @TIMECARD_LIB.TIMECARD(SCH_1):PAGE161
  R120    1      1 RESISTOR-G155-11000-01,100OHM,A   I265 @TIMECARD_LIB.TIMECARD(SCH_1):PAGE12

ANT2_IN @TIMECARD_LIB.TIMECARD(SCH_1):ANT2_IN
   U24 AA20 IO_L8P_T1_D11_14 XC7A200T_2FBG484C_FBG484-G240-A     I2 @TIMECARD_LIB.TIMECARD(SCH_1):PAGE161
  R372    2      2 RESISTOR-G155-149R9-01,49.9OHMA   I275 @TIMECARD_LIB.TIMECARD(SCH_1):PAGE12
  R503    1      1 RESISTOR-G155-14701-01,4.7KOHMA   I246 @TIMECARD_LIB.TIMECARD(SCH_1):PAGE161

ANT2_OUT @TIMECARD_LIB.TIMECARD(SCH_1):ANT2_OUT
   U24  W10 IO_L10N_T1_13 XC7A200T_2FBG484C_FBG484-G240-A     I2 @TIMECARD_LIB.TIMECARD(SCH_1):PAGE161
  R121    1      1 RESISTOR-G155-11000-01,100OHM,A   I284 @TIMECARD_LIB.TIMECARD(SCH_1):PAGE12

ANT3_IN @TIMECARD_LIB.TIMECARD(SCH_1):ANT3_IN
   U24  Y11 IO_L11P_T1_SRCC_13 XC7A200T_2FBG484C_FBG484-G240-A     I2 @TIMECARD_LIB.TIMECARD(SCH_1):PAGE161
  R367    2      2 RESISTOR-G155-149R9-01,49.9OHMA   I209 @TIMECARD_LIB.TIMECARD(SCH_1):PAGE12
  R500    2      2 RESISTOR-G155-14701-01,4.7KOHMA   I242 @TIMECARD_LIB.TIMECARD(SCH_1):PAGE161

ANT3_OUT @TIMECARD_LIB.TIMECARD(SCH_1):ANT3_OUT
  R156    1      1 RESISTOR-G155-11000-01,100OHM,A    I63 @TIMECARD_LIB.TIMECARD(SCH_1):PAGE12
   U24  W11 IO_L12P_T1_MRCC_13 XC7A200T_2FBG484C_FBG484-G240-A     I2 @TIMECARD_LIB.TIMECARD(SCH_1):PAGE161

ANT4_IN @TIMECARD_LIB.TIMECARD(SCH_1):ANT4_IN
   U24  Y12 IO_L11N_T1_SRCC_13 XC7A200T_2FBG484C_FBG484-G240-A     I2 @TIMECARD_LIB.TIMECARD(SCH_1):PAGE161
  R370    2      2 RESISTOR-G155-149R9-01,49.9OHMA   I229 @TIMECARD_LIB.TIMECARD(SCH_1):PAGE12
  R501    2      2 RESISTOR-G155-14701-01,4.7KOHMA   I241 @TIMECARD_LIB.TIMECARD(SCH_1):PAGE161

ANT4_OUT @TIMECARD_LIB.TIMECARD(SCH_1):ANT4_OUT
   U24  W12 IO_L12N_T1_MRCC_13 XC7A200T_2FBG484C_FBG484-G240-A     I2 @TIMECARD_LIB.TIMECARD(SCH_1):PAGE161
  R157    1      1 RESISTOR-G155-11000-01,100OHM,A   I237 @TIMECARD_LIB.TIMECARD(SCH_1):PAGE12

BF_ANT1_IN @TIMECARD_LIB.TIMECARD(SCH_1):BF_ANT1_IN
   U15    3     2Y 74HCT2G125DP_TSSOP8-G220-00055A   I255 @TIMECARD_LIB.TIMECARD(SCH_1):PAGE12
  R371    1      1 RESISTOR-G155-149R9-01,49.9OHMA   I258 @TIMECARD_LIB.TIMECARD(SCH_1):PAGE12

BF_ANT2_IN @TIMECARD_LIB.TIMECARD(SCH_1):BF_ANT2_IN
   U16    3     2Y 74HCT2G125DP_TSSOP8-G220-00055A   I273 @TIMECARD_LIB.TIMECARD(SCH_1):PAGE12
  R372    1      1 RESISTOR-G155-149R9-01,49.9OHMA   I275 @TIMECARD_LIB.TIMECARD(SCH_1):PAGE12

BF_ANT3_IN @TIMECARD_LIB.TIMECARD(SCH_1):BF_ANT3_IN
   U13    3     2Y 74HCT2G125DP_TSSOP8-G220-00055A   I204 @TIMECARD_LIB.TIMECARD(SCH_1):PAGE12
  R367    1      1 RESISTOR-G155-149R9-01,49.9OHMA   I209 @TIMECARD_LIB.TIMECARD(SCH_1):PAGE12

BF_ANT4_IN @TIMECARD_LIB.TIMECARD(SCH_1):BF_ANT4_IN
   U14    3     2Y 74HCT2G125DP_TSSOP8-G220-00055A   I226 @TIMECARD_LIB.TIMECARD(SCH_1):PAGE12
  R370    1      1 RESISTOR-G155-149R9-01,49.9OHMA   I229 @TIMECARD_LIB.TIMECARD(SCH_1):PAGE12

BF_ICP10100_I2C_SCL @TIMECARD_LIB.TIMECARD(SCH_1):BF_ICP10100_I2C_SCL
   R71    2      2 RESISTOR-G155-14701-01,4.7KOHMA     I5 @TIMECARD_LIB.TIMECARD(SCH_1):PAGE8
   R73    1      1 RESISTOR-G155-133R0-01,33OHM,1%     I6 @TIMECARD_LIB.TIMECARD(SCH_1):PAGE8
   U32    2   SCLA PCA9508DP_TSSOP8-G223-10278-01    I51 @TIMECARD_LIB.TIMECARD(SCH_1):PAGE8
  R315    2      2 RESISTOR-G155-100R0-J0,0OHM,-    I63 @TIMECARD_LIB.TIMECARD(SCH_1):PAGE8

BF_ICP10100_I2C_SDA @TIMECARD_LIB.TIMECARD(SCH_1):BF_ICP10100_I2C_SDA
   R70    2      2 RESISTOR-G155-14701-01,4.7KOHMA     I3 @TIMECARD_LIB.TIMECARD(SCH_1):PAGE8
   R72    1      1 RESISTOR-G155-133R0-01,33OHM,1%     I7 @TIMECARD_LIB.TIMECARD(SCH_1):PAGE8
   U32    3   SDAA PCA9508DP_TSSOP8-G223-10278-01    I51 @TIMECARD_LIB.TIMECARD(SCH_1):PAGE8
  R316    2      2 RESISTOR-G155-100R0-J0,0OHM,-    I64 @TIMECARD_LIB.TIMECARD(SCH_1):PAGE8

BF_PCIE_PERST_N @TIMECARD_LIB.TIMECARD(SCH_1):BF_PCIE_PERST_N
  R356    1      1 RESISTOR-G155-100R0-J0,0OHM,-   I122 @TIMECARD_LIB.TIMECARD(SCH_1):PAGE3
    U3    4      Y 74LVC1G07_SC70_5-G220-10017-01   I134 @TIMECARD_LIB.TIMECARD(SCH_1):PAGE3
   R57    1      1 RESISTOR-G155-133R0-01,33OHM,1%   I153 @TIMECARD_LIB.TIMECARD(SCH_1):PAGE3

BF_SMA1_SIG_IO_CONN @TIMECARD_LIB.TIMECARD(SCH_1):BF_SMA1_SIG_IO_CONN
   U15    6     1Y 74HCT2G125DP_TSSOP8-G220-00055A   I255 @TIMECARD_LIB.TIMECARD(SCH_1):PAGE12
   U15    5     2A 74HCT2G125DP_TSSOP8-G220-00055A   I255 @TIMECARD_LIB.TIMECARD(SCH_1):PAGE12
  R127    1      1 RESISTOR-G155-149R9-01,49.9OHMA   I257 @TIMECARD_LIB.TIMECARD(SCH_1):PAGE12
  R498    2      2 RESISTOR-G155-11004-01,1MOHM,1%   I327 @TIMECARD_LIB.TIMECARD(SCH_1):PAGE12

BF_SMA2_SIG_IO_CONN @TIMECARD_LIB.TIMECARD(SCH_1):BF_SMA2_SIG_IO_CONN
   U16    6     1Y 74HCT2G125DP_TSSOP8-G220-00055A   I273 @TIMECARD_LIB.TIMECARD(SCH_1):PAGE12
   U16    5     2A 74HCT2G125DP_TSSOP8-G220-00055A   I273 @TIMECARD_LIB.TIMECARD(SCH_1):PAGE12
  R126    1      1 RESISTOR-G155-149R9-01,49.9OHMA   I276 @TIMECARD_LIB.TIMECARD(SCH_1):PAGE12
  R499    2      2 RESISTOR-G155-11004-01,1MOHM,1%   I331 @TIMECARD_LIB.TIMECARD(SCH_1):PAGE12

BF_SMA3_SIG_IO_CONN @TIMECARD_LIB.TIMECARD(SCH_1):BF_SMA3_SIG_IO_CONN
  R122    1      1 RESISTOR-G155-149R9-01,49.9OHMA   I197 @TIMECARD_LIB.TIMECARD(SCH_1):PAGE12
   U13    6     1Y 74HCT2G125DP_TSSOP8-G220-00055A   I204 @TIMECARD_LIB.TIMECARD(SCH_1):PAGE12
   U13    5     2A 74HCT2G125DP_TSSOP8-G220-00055A   I204 @TIMECARD_LIB.TIMECARD(SCH_1):PAGE12
  R496    2      2 RESISTOR-G155-11004-01,1MOHM,1%   I320 @TIMECARD_LIB.TIMECARD(SCH_1):PAGE12

BF_SMA4_SIG_IO_CONN @TIMECARD_LIB.TIMECARD(SCH_1):BF_SMA4_SIG_IO_CONN
   U14    6     1Y 74HCT2G125DP_TSSOP8-G220-00055A   I226 @TIMECARD_LIB.TIMECARD(SCH_1):PAGE12
   U14    5     2A 74HCT2G125DP_TSSOP8-G220-00055A   I226 @TIMECARD_LIB.TIMECARD(SCH_1):PAGE12
  R123    1      1 RESISTOR-G155-149R9-01,49.9OHMA   I228 @TIMECARD_LIB.TIMECARD(SCH_1):PAGE12
  R497    2      2 RESISTOR-G155-11004-01,1MOHM,1%   I322 @TIMECARD_LIB.TIMECARD(SCH_1):PAGE12

BNO080_EVN_SCL @TIMECARD_LIB.TIMECARD(SCH_1):BNO080_EVN_SCL
  R342    2      2 RESISTOR-G155-14701-01,4.7KOHMA    I66 @TIMECARD_LIB.TIMECARD(SCH_1):PAGE9
  R363    2      2 RESISTOR-G155-133R0-01,33OHM,1%    I67 @TIMECARD_LIB.TIMECARD(SCH_1):PAGE9
   TP2    1      1 TP_PIONT-TP010CT020B030_PTH-TPA    I72 @TIMECARD_LIB.TIMECARD(SCH_1):PAGE9

BNO080_EVN_SDA @TIMECARD_LIB.TIMECARD(SCH_1):BNO080_EVN_SDA
  R330    2      2 RESISTOR-G155-133R0-01,33OHM,1%    I64 @TIMECARD_LIB.TIMECARD(SCH_1):PAGE9
  R341    2      2 RESISTOR-G155-14701-01,4.7KOHMA    I65 @TIMECARD_LIB.TIMECARD(SCH_1):PAGE9
   TP1    1      1 TP_PIONT-TP010CT020B030_PTH-TPA    I71 @TIMECARD_LIB.TIMECARD(SCH_1):PAGE9

BNO080_I2C_SCL @TIMECARD_LIB.TIMECARD(SCH_1):BNO080_I2C_SCL
    U4   12    SC3 PCA9546APW_TSSOP16-G223-10280-A    I33 @TIMECARD_LIB.TIMECARD(SCH_1):PAGE5
   R75    2      2 RESISTOR-G155-14701-01,4.7KOHMA     I7 @TIMECARD_LIB.TIMECARD(SCH_1):PAGE9
   R77    1      1 RESISTOR-G155-133R0-01,33OHM,1%    I11 @TIMECARD_LIB.TIMECARD(SCH_1):PAGE9

BNO080_I2C_SDA @TIMECARD_LIB.TIMECARD(SCH_1):BNO080_I2C_SDA
    U4   11    SD3 PCA9546APW_TSSOP16-G223-10280-A    I33 @TIMECARD_LIB.TIMECARD(SCH_1):PAGE5
   R74    2      2 RESISTOR-G155-14701-01,4.7KOHMA     I6 @TIMECARD_LIB.TIMECARD(SCH_1):PAGE9
   R76    1      1 RESISTOR-G155-133R0-01,33OHM,1%    I12 @TIMECARD_LIB.TIMECARD(SCH_1):PAGE9

BNO080_SA0 @TIMECARD_LIB.TIMECARD(SCH_1):BNO080_SA0
   U29   17 SA0/H_MOSI BNO080_LGA_28-A246-00002-FB,BNA    I29 @TIMECARD_LIB.TIMECARD(SCH_1):PAGE9
  R290    2      2 RESISTOR-G155-14701-01,4.7KOHMA    I51 @TIMECARD_LIB.TIMECARD(SCH_1):PAGE9
  R302    1      1 RESISTOR-G155-11001-01,1KOHM,1%    I52 @TIMECARD_LIB.TIMECARD(SCH_1):PAGE9

CARD_PRESENT @TIMECARD_LIB.TIMECARD(SCH_1):CARD_PRESENT
   R23    1      1 RESISTOR-G155-100R0-J0,0OHM,-    I15 @TIMECARD_LIB.TIMECARD(SCH_1):PAGE3
   R22    1      1 RESISTOR-G155-100R0-J0,0OHM,-    I16 @TIMECARD_LIB.TIMECARD(SCH_1):PAGE3
   GF1   A1 PRSNT1* CONN_64P_GF-S_M_EF64_PCIE_P039A    I61 @TIMECARD_LIB.TIMECARD(SCH_1):PAGE3

CCLK_0 @TIMECARD_LIB.TIMECARD(SCH_1):CCLK_0
   U24  L12 CCLK_0 XC7A200T_2FBG484C_FBG484-G240-A   I232 @TIMECARD_LIB.TIMECARD(SCH_1):PAGE127
  R207    1      1 RESISTOR-G155-100R0-J0,0OHM,-   I337 @TIMECARD_LIB.TIMECARD(SCH_1):PAGE127

CFGBVS @TIMECARD_LIB.TIMECARD(SCH_1):CFGBVS
   U24   U8 CFGBVS_0 XC7A200T_2FBG484C_FBG484-G240-A   I232 @TIMECARD_LIB.TIMECARD(SCH_1):PAGE127
  R194    2      2 RESISTOR-G155-14701-01,4.7KOHMA   I329 @TIMECARD_LIB.TIMECARD(SCH_1):PAGE127

CLK_125M_OE @TIMECARD_LIB.TIMECARD(SCH_1):CLK_125M_OE
    Y4    1     OE OSC6P_V2-A130-00004-AW   I145 @TIMECARD_LIB.TIMECARD(SCH_1):PAGE522
  R236    2      2 RESISTOR-G155-14701-01,4.7KOHMA   I156 @TIMECARD_LIB.TIMECARD(SCH_1):PAGE522
  TP50    1      1 TP_PIONT-TP010CT020B030_PTH-TPA  I1701 @TIMECARD_LIB.TIMECARD(SCH_1):PAGE16

CLK_200M_OE @TIMECARD_LIB.TIMECARD(SCH_1):CLK_200M_OE
    Y3    1     OE OSC6P_V2-A130-00003-AW   I144 @TIMECARD_LIB.TIMECARD(SCH_1):PAGE522
  R235    2      2 RESISTOR-G155-14701-01,4.7KOHMA   I149 @TIMECARD_LIB.TIMECARD(SCH_1):PAGE522
  TP49    1      1 TP_PIONT-TP010CT020B030_PTH-TPA  I1699 @TIMECARD_LIB.TIMECARD(SCH_1):PAGE16

CONN_MICRO_USB_DM @TIMECARD_LIB.TIMECARD(SCH_1):CONN_MICRO_USB_DM
   J11    2      2 CONN_USB_1X5_G2_GH4_F_RA_SMT-GA     I2 @TIMECARD_LIB.TIMECARD(SCH_1):PAGE527
    U9    4      4 CL1001485A-G122-00019-01     I4 @TIMECARD_LIB.TIMECARD(SCH_1):PAGE527
   U11    6 USB2_N TS3USB3031RMGR_WQFN12-G220-103A   I108 @TIMECARD_LIB.TIMECARD(SCH_1):PAGE527

CONN_MICRO_USB_DP @TIMECARD_LIB.TIMECARD(SCH_1):CONN_MICRO_USB_DP
   J11    3      3 CONN_USB_1X5_G2_GH4_F_RA_SMT-GA     I2 @TIMECARD_LIB.TIMECARD(SCH_1):PAGE527
    U9    6      6 CL1001485A-G122-00019-01     I4 @TIMECARD_LIB.TIMECARD(SCH_1):PAGE527
   U11    5 USB2_P TS3USB3031RMGR_WQFN12-G220-103A   I108 @TIMECARD_LIB.TIMECARD(SCH_1):PAGE527

CPU_RX_PCIE_MGT0_TXN @TIMECARD_LIB.TIMECARD(SCH_1):CPU_RX_PCIE_MGT0_TXN
   U24   A4 MGTPTXN0_216 XC7A200T_2FBG484C_FBG484-G240-A   I232 @TIMECARD_LIB.TIMECARD(SCH_1):PAGE127
   C25    2      2 CAPACITOR-G105-0B104-CK,0.1UF,A   I115 @TIMECARD_LIB.TIMECARD(SCH_1):PAGE3

CPU_RX_PCIE_MGT0_TXP @TIMECARD_LIB.TIMECARD(SCH_1):CPU_RX_PCIE_MGT0_TXP
   C24    2      2 CAPACITOR-G105-0B104-CK,0.1UF,A    I35 @TIMECARD_LIB.TIMECARD(SCH_1):PAGE3
   U24   B4 MGTPTXP0_216 XC7A200T_2FBG484C_FBG484-G240-A   I232 @TIMECARD_LIB.TIMECARD(SCH_1):PAGE127

CPU_RX_PCIE_MGT1_TXN @TIMECARD_LIB.TIMECARD(SCH_1):CPU_RX_PCIE_MGT1_TXN
   U24   C5 MGTPTXN1_216 XC7A200T_2FBG484C_FBG484-G240-A   I232 @TIMECARD_LIB.TIMECARD(SCH_1):PAGE127
   C27    2      2 CAPACITOR-G105-0B104-CK,0.1UF,A   I117 @TIMECARD_LIB.TIMECARD(SCH_1):PAGE3

CPU_RX_PCIE_MGT1_TXP @TIMECARD_LIB.TIMECARD(SCH_1):CPU_RX_PCIE_MGT1_TXP
   U24   D5 MGTPTXP1_216 XC7A200T_2FBG484C_FBG484-G240-A   I232 @TIMECARD_LIB.TIMECARD(SCH_1):PAGE127
   C26    2      2 CAPACITOR-G105-0B104-CK,0.1UF,A   I116 @TIMECARD_LIB.TIMECARD(SCH_1):PAGE3

CPU_RX_PCIE_MGT2_TXN @TIMECARD_LIB.TIMECARD(SCH_1):CPU_RX_PCIE_MGT2_TXN
   U24   A6 MGTPTXN2_216 XC7A200T_2FBG484C_FBG484-G240-A   I232 @TIMECARD_LIB.TIMECARD(SCH_1):PAGE127
   C34    2      2 CAPACITOR-G105-0B104-CK,0.1UF,A   I119 @TIMECARD_LIB.TIMECARD(SCH_1):PAGE3

CPU_RX_PCIE_MGT2_TXP @TIMECARD_LIB.TIMECARD(SCH_1):CPU_RX_PCIE_MGT2_TXP
   U24   B6 MGTPTXP2_216 XC7A200T_2FBG484C_FBG484-G240-A   I232 @TIMECARD_LIB.TIMECARD(SCH_1):PAGE127
   C28    2      2 CAPACITOR-G105-0B104-CK,0.1UF,A   I118 @TIMECARD_LIB.TIMECARD(SCH_1):PAGE3

CPU_RX_PCIE_MGT3_TXN @TIMECARD_LIB.TIMECARD(SCH_1):CPU_RX_PCIE_MGT3_TXN
   U24   C7 MGTPTXN3_216 XC7A200T_2FBG484C_FBG484-G240-A   I232 @TIMECARD_LIB.TIMECARD(SCH_1):PAGE127
   C36    2      2 CAPACITOR-G105-0B104-CK,0.1UF,A   I121 @TIMECARD_LIB.TIMECARD(SCH_1):PAGE3

CPU_RX_PCIE_MGT3_TXP @TIMECARD_LIB.TIMECARD(SCH_1):CPU_RX_PCIE_MGT3_TXP
   U24   D7 MGTPTXP3_216 XC7A200T_2FBG484C_FBG484-G240-A   I232 @TIMECARD_LIB.TIMECARD(SCH_1):PAGE127
   C35    2      2 CAPACITOR-G105-0B104-CK,0.1UF,A   I120 @TIMECARD_LIB.TIMECARD(SCH_1):PAGE3

CPU_TX_PCIE_MGT_0_RXN @TIMECARD_LIB.TIMECARD(SCH_1):CPU_TX_PCIE_MGT_0_RXN
   GF1  B15  PETN0 CONN_64P_GF-S_M_EF64_PCIE_P039A    I61 @TIMECARD_LIB.TIMECARD(SCH_1):PAGE3
   U24   A8 MGTPRXN0_216 XC7A200T_2FBG484C_FBG484-G240-A   I232 @TIMECARD_LIB.TIMECARD(SCH_1):PAGE127

CPU_TX_PCIE_MGT_0_RXP @TIMECARD_LIB.TIMECARD(SCH_1):CPU_TX_PCIE_MGT_0_RXP
   GF1  B14  PETP0 CONN_64P_GF-S_M_EF64_PCIE_P039A    I61 @TIMECARD_LIB.TIMECARD(SCH_1):PAGE3
   U24   B8 MGTPRXP0_216 XC7A200T_2FBG484C_FBG484-G240-A   I232 @TIMECARD_LIB.TIMECARD(SCH_1):PAGE127

CPU_TX_PCIE_MGT_1_RXN @TIMECARD_LIB.TIMECARD(SCH_1):CPU_TX_PCIE_MGT_1_RXN
   GF1  B20  PETN1 CONN_64P_GF-S_M_EF64_PCIE_P039A    I61 @TIMECARD_LIB.TIMECARD(SCH_1):PAGE3
   U24  C11 MGTPRXN1_216 XC7A200T_2FBG484C_FBG484-G240-A   I232 @TIMECARD_LIB.TIMECARD(SCH_1):PAGE127

CPU_TX_PCIE_MGT_1_RXP @TIMECARD_LIB.TIMECARD(SCH_1):CPU_TX_PCIE_MGT_1_RXP
   GF1  B19  PETP1 CONN_64P_GF-S_M_EF64_PCIE_P039A    I61 @TIMECARD_LIB.TIMECARD(SCH_1):PAGE3
   U24  D11 MGTPRXP1_216 XC7A200T_2FBG484C_FBG484-G240-A   I232 @TIMECARD_LIB.TIMECARD(SCH_1):PAGE127

CPU_TX_PCIE_MGT_2_RXN @TIMECARD_LIB.TIMECARD(SCH_1):CPU_TX_PCIE_MGT_2_RXN
   GF1  B24  PETN2 CONN_64P_GF-S_M_EF64_PCIE_P039A    I61 @TIMECARD_LIB.TIMECARD(SCH_1):PAGE3
   U24  A10 MGTPRXN2_216 XC7A200T_2FBG484C_FBG484-G240-A   I232 @TIMECARD_LIB.TIMECARD(SCH_1):PAGE127

CPU_TX_PCIE_MGT_2_RXP @TIMECARD_LIB.TIMECARD(SCH_1):CPU_TX_PCIE_MGT_2_RXP
   GF1  B23  PETP2 CONN_64P_GF-S_M_EF64_PCIE_P039A    I61 @TIMECARD_LIB.TIMECARD(SCH_1):PAGE3
   U24  B10 MGTPRXP2_216 XC7A200T_2FBG484C_FBG484-G240-A   I232 @TIMECARD_LIB.TIMECARD(SCH_1):PAGE127

CPU_TX_PCIE_MGT_3_RXN @TIMECARD_LIB.TIMECARD(SCH_1):CPU_TX_PCIE_MGT_3_RXN
   GF1  B28  PETN3 CONN_64P_GF-S_M_EF64_PCIE_P039A    I61 @TIMECARD_LIB.TIMECARD(SCH_1):PAGE3
   U24   C9 MGTPRXN3_216 XC7A200T_2FBG484C_FBG484-G240-A   I232 @TIMECARD_LIB.TIMECARD(SCH_1):PAGE127

CPU_TX_PCIE_MGT_3_RXP @TIMECARD_LIB.TIMECARD(SCH_1):CPU_TX_PCIE_MGT_3_RXP
   GF1  B27  PETP3 CONN_64P_GF-S_M_EF64_PCIE_P039A    I61 @TIMECARD_LIB.TIMECARD(SCH_1):PAGE3
   U24   D9 MGTPRXP3_216 XC7A200T_2FBG484C_FBG484-G240-A   I232 @TIMECARD_LIB.TIMECARD(SCH_1):PAGE127

C_CPU_RX_PCIE_MGT0_TXN @TIMECARD_LIB.TIMECARD(SCH_1):C_CPU_RX_PCIE_MGT0_TXN
   GF1  A17  PERN0 CONN_64P_GF-S_M_EF64_PCIE_P039A    I61 @TIMECARD_LIB.TIMECARD(SCH_1):PAGE3
   C25    1      1 CAPACITOR-G105-0B104-CK,0.1UF,A   I115 @TIMECARD_LIB.TIMECARD(SCH_1):PAGE3

C_CPU_RX_PCIE_MGT0_TXP @TIMECARD_LIB.TIMECARD(SCH_1):C_CPU_RX_PCIE_MGT0_TXP
   C24    1      1 CAPACITOR-G105-0B104-CK,0.1UF,A    I35 @TIMECARD_LIB.TIMECARD(SCH_1):PAGE3
   GF1  A16  PERP0 CONN_64P_GF-S_M_EF64_PCIE_P039A    I61 @TIMECARD_LIB.TIMECARD(SCH_1):PAGE3

C_CPU_RX_PCIE_MGT1_TXN @TIMECARD_LIB.TIMECARD(SCH_1):C_CPU_RX_PCIE_MGT1_TXN
   GF1  A22  PERN1 CONN_64P_GF-S_M_EF64_PCIE_P039A    I61 @TIMECARD_LIB.TIMECARD(SCH_1):PAGE3
   C27    1      1 CAPACITOR-G105-0B104-CK,0.1UF,A   I117 @TIMECARD_LIB.TIMECARD(SCH_1):PAGE3

C_CPU_RX_PCIE_MGT1_TXP @TIMECARD_LIB.TIMECARD(SCH_1):C_CPU_RX_PCIE_MGT1_TXP
   GF1  A21  PERP1 CONN_64P_GF-S_M_EF64_PCIE_P039A    I61 @TIMECARD_LIB.TIMECARD(SCH_1):PAGE3
   C26    1      1 CAPACITOR-G105-0B104-CK,0.1UF,A   I116 @TIMECARD_LIB.TIMECARD(SCH_1):PAGE3

C_CPU_RX_PCIE_MGT2_TXN @TIMECARD_LIB.TIMECARD(SCH_1):C_CPU_RX_PCIE_MGT2_TXN
   GF1  A26  PERN2 CONN_64P_GF-S_M_EF64_PCIE_P039A    I61 @TIMECARD_LIB.TIMECARD(SCH_1):PAGE3
   C34    1      1 CAPACITOR-G105-0B104-CK,0.1UF,A   I119 @TIMECARD_LIB.TIMECARD(SCH_1):PAGE3

C_CPU_RX_PCIE_MGT2_TXP @TIMECARD_LIB.TIMECARD(SCH_1):C_CPU_RX_PCIE_MGT2_TXP
   GF1  A25  PERP2 CONN_64P_GF-S_M_EF64_PCIE_P039A    I61 @TIMECARD_LIB.TIMECARD(SCH_1):PAGE3
   C28    1      1 CAPACITOR-G105-0B104-CK,0.1UF,A   I118 @TIMECARD_LIB.TIMECARD(SCH_1):PAGE3

C_CPU_RX_PCIE_MGT3_TXN @TIMECARD_LIB.TIMECARD(SCH_1):C_CPU_RX_PCIE_MGT3_TXN
   GF1  A30  PERN3 CONN_64P_GF-S_M_EF64_PCIE_P039A    I61 @TIMECARD_LIB.TIMECARD(SCH_1):PAGE3
   C36    1      1 CAPACITOR-G105-0B104-CK,0.1UF,A   I121 @TIMECARD_LIB.TIMECARD(SCH_1):PAGE3

C_CPU_RX_PCIE_MGT3_TXP @TIMECARD_LIB.TIMECARD(SCH_1):C_CPU_RX_PCIE_MGT3_TXP
   GF1  A29  PERP3 CONN_64P_GF-S_M_EF64_PCIE_P039A    I61 @TIMECARD_LIB.TIMECARD(SCH_1):PAGE3
   C35    1      1 CAPACITOR-G105-0B104-CK,0.1UF,A   I120 @TIMECARD_LIB.TIMECARD(SCH_1):PAGE3

C_PCIEREFCLKN @TIMECARD_LIB.TIMECARD(SCH_1):C_PCIEREFCLKN
   C23    1      1 CAPACITOR-G105-0B104-CK,0.1UF,A    I37 @TIMECARD_LIB.TIMECARD(SCH_1):PAGE3
   GF1  A14 REFCLK_N CONN_64P_GF-S_M_EF64_PCIE_P039A    I61 @TIMECARD_LIB.TIMECARD(SCH_1):PAGE3

C_PCIEREFCLKP @TIMECARD_LIB.TIMECARD(SCH_1):C_PCIEREFCLKP
   C19    1      1 CAPACITOR-G105-0B104-CK,0.1UF,A    I36 @TIMECARD_LIB.TIMECARD(SCH_1):PAGE3
   GF1  A13 REFCLK_P CONN_64P_GF-S_M_EF64_PCIE_P039A    I61 @TIMECARD_LIB.TIMECARD(SCH_1):PAGE3

DBG_UART_GPS_RXD @TIMECARD_LIB.TIMECARD(SCH_1):DBG_UART_GPS_RXD
  R113    1      1 RESISTOR-G155-133R0-01,33OHM,1%     I7 @TIMECARD_LIB.TIMECARD(SCH_1):PAGE11
   J10    4      4 G200_10283_01-G200-10283-01   I173 @TIMECARD_LIB.TIMECARD(SCH_1):PAGE524

DBG_UART_GPS_TXD @TIMECARD_LIB.TIMECARD(SCH_1):DBG_UART_GPS_TXD
  R112    1      1 RESISTOR-G155-133R0-01,33OHM,1%     I8 @TIMECARD_LIB.TIMECARD(SCH_1):PAGE11
   J10    8      8 G200_10283_01-G200-10283-01   I173 @TIMECARD_LIB.TIMECARD(SCH_1):PAGE524

DBG_UART_MAC_RX @TIMECARD_LIB.TIMECARD(SCH_1):DBG_UART_MAC_RX
   J10    2      2 G200_10283_01-G200-10283-01   I173 @TIMECARD_LIB.TIMECARD(SCH_1):PAGE524
   R81    2      2 RESISTOR-G155-133R0-01,33OHM,1%   I240 @TIMECARD_LIB.TIMECARD(SCH_1):PAGE527

DBG_UART_MAC_TX @TIMECARD_LIB.TIMECARD(SCH_1):DBG_UART_MAC_TX
   J10    6      6 G200_10283_01-G200-10283-01   I173 @TIMECARD_LIB.TIMECARD(SCH_1):PAGE524
   R82    2      2 RESISTOR-G155-133R0-01,33OHM,1%   I241 @TIMECARD_LIB.TIMECARD(SCH_1):PAGE527

EEPROM_I2C_SCL @TIMECARD_LIB.TIMECARD(SCH_1):EEPROM_I2C_SCL
  R184    1      1 RESISTOR-G155-133R0-01,33OHM,1%   I103 @TIMECARD_LIB.TIMECARD(SCH_1):PAGE5
   U37   12   COM4 TS3A5018PWR_TSSOP16-G220-10324A   I448 @TIMECARD_LIB.TIMECARD(SCH_1):PAGE524

EEPROM_I2C_SDA @TIMECARD_LIB.TIMECARD(SCH_1):EEPROM_I2C_SDA
  R183    1      1 RESISTOR-G155-133R0-01,33OHM,1%   I101 @TIMECARD_LIB.TIMECARD(SCH_1):PAGE5
   U37    9   COM3 TS3A5018PWR_TSSOP16-G220-10324A   I448 @TIMECARD_LIB.TIMECARD(SCH_1):PAGE524

EEPROM_SCL @TIMECARD_LIB.TIMECARD(SCH_1):EEPROM_SCL
    U7    1    SCL AT24MAC402_SOT23_5-A221-00002-A    I89 @TIMECARD_LIB.TIMECARD(SCH_1):PAGE5
   R19    2      2 RESISTOR-G155-11002-01,10KOHM,A    I95 @TIMECARD_LIB.TIMECARD(SCH_1):PAGE5
  R176    2      2 RESISTOR-G155-133R0-01,33OHM,1%   I102 @TIMECARD_LIB.TIMECARD(SCH_1):PAGE5
  R184    2      2 RESISTOR-G155-133R0-01,33OHM,1%   I103 @TIMECARD_LIB.TIMECARD(SCH_1):PAGE5
  R313    2      2 RESISTOR-G155-100R0-J0,0OHM,-   I111 @TIMECARD_LIB.TIMECARD(SCH_1):PAGE5
    J9    4      4 CONN_HDR_2X2_M_S_SMT-G200-1068A   I126 @TIMECARD_LIB.TIMECARD(SCH_1):PAGE5
   U19    6    SCL 24LC16BT_I_ST_TSSOP8-G221-1017A   I151 @TIMECARD_LIB.TIMECARD(SCH_1):PAGE5

EEPROM_SDA @TIMECARD_LIB.TIMECARD(SCH_1):EEPROM_SDA
  R345    1      1 RESISTOR-G155-133R0-01,33OHM,1%    I90 @TIMECARD_LIB.TIMECARD(SCH_1):PAGE5
 R1991    2      2 RESISTOR-G155-11002-01,10KOHM,A    I96 @TIMECARD_LIB.TIMECARD(SCH_1):PAGE5
  R175    2      2 RESISTOR-G155-133R0-01,33OHM,1%   I100 @TIMECARD_LIB.TIMECARD(SCH_1):PAGE5
  R183    2      2 RESISTOR-G155-133R0-01,33OHM,1%   I101 @TIMECARD_LIB.TIMECARD(SCH_1):PAGE5
  R312    2      2 RESISTOR-G155-100R0-J0,0OHM,-   I112 @TIMECARD_LIB.TIMECARD(SCH_1):PAGE5
    J9    2      2 CONN_HDR_2X2_M_S_SMT-G200-1068A   I126 @TIMECARD_LIB.TIMECARD(SCH_1):PAGE5
   R45    1      1 RESISTOR-G155-133R0-01,33OHM,1%   I162 @TIMECARD_LIB.TIMECARD(SCH_1):PAGE5

FLASH_CLK @TIMECARD_LIB.TIMECARD(SCH_1):FLASH_CLK
   U38    4   COM1 TS3A5018PWR_TSSOP16-G220-10324A   I400 @TIMECARD_LIB.TIMECARD(SCH_1):PAGE524
   U23    6      C MT25QL128ABA1ESE_SOP8-G221-102A   I456 @TIMECARD_LIB.TIMECARD(SCH_1):PAGE127
  R192    1      1 RESISTOR-G155-14701-01,4.7KOHMA   I470 @TIMECARD_LIB.TIMECARD(SCH_1):PAGE127

FLASH_CS_N @TIMECARD_LIB.TIMECARD(SCH_1):FLASH_CS_N
   U38   12   COM4 TS3A5018PWR_TSSOP16-G220-10324A   I400 @TIMECARD_LIB.TIMECARD(SCH_1):PAGE524
   U23    1     S* MT25QL128ABA1ESE_SOP8-G221-102A   I456 @TIMECARD_LIB.TIMECARD(SCH_1):PAGE127
  R191    2      2 RESISTOR-G155-14701-01,4.7KOHMA   I471 @TIMECARD_LIB.TIMECARD(SCH_1):PAGE127

FLASH_DQ0_MOSI @TIMECARD_LIB.TIMECARD(SCH_1):FLASH_DQ0_MOSI
   U38    7   COM2 TS3A5018PWR_TSSOP16-G220-10324A   I400 @TIMECARD_LIB.TIMECARD(SCH_1):PAGE524
  R203    2      2 RESISTOR-G155-133R0-01,33OHM,1%   I467 @TIMECARD_LIB.TIMECARD(SCH_1):PAGE127

FLASH_DQ1_MISO @TIMECARD_LIB.TIMECARD(SCH_1):FLASH_DQ1_MISO
   U38    9   COM3 TS3A5018PWR_TSSOP16-G220-10324A   I400 @TIMECARD_LIB.TIMECARD(SCH_1):PAGE524
  R204    2      2 RESISTOR-G155-133R0-01,33OHM,1%   I466 @TIMECARD_LIB.TIMECARD(SCH_1):PAGE127

FLASH_DQ2 @TIMECARD_LIB.TIMECARD(SCH_1):FLASH_DQ2
   U39    3     B0 NLASB3157DFT2G_SC88-G223-10187A   I407 @TIMECARD_LIB.TIMECARD(SCH_1):PAGE524
  R464    2      2 RESISTOR-G155-100R0-J0,0OHM,-   I493 @TIMECARD_LIB.TIMECARD(SCH_1):PAGE524
  R205    2      2 RESISTOR-G155-133R0-01,33OHM,1%   I468 @TIMECARD_LIB.TIMECARD(SCH_1):PAGE127

FLASH_DQ3 @TIMECARD_LIB.TIMECARD(SCH_1):FLASH_DQ3
   U40    3     B0 NLASB3157DFT2G_SC88-G223-10187A   I408 @TIMECARD_LIB.TIMECARD(SCH_1):PAGE524
  R465    2      2 RESISTOR-G155-100R0-J0,0OHM,-   I494 @TIMECARD_LIB.TIMECARD(SCH_1):PAGE524
  R206    2      2 RESISTOR-G155-133R0-01,33OHM,1%   I469 @TIMECARD_LIB.TIMECARD(SCH_1):PAGE127

FPGA_BRD_REV0 @TIMECARD_LIB.TIMECARD(SCH_1):FPGA_BRD_REV0
  R219    2      2 RESISTOR-G155-11002-01,10KOHM,A   I392 @TIMECARD_LIB.TIMECARD(SCH_1):PAGE127
  R220    1      1 RESISTOR-G155-11001-01,1KOHM,1%   I393 @TIMECARD_LIB.TIMECARD(SCH_1):PAGE127
   U24  N20 IO_L18P_T2_A24_15 XC7A200T_2FBG484C_FBG484-G240-A   I228 @TIMECARD_LIB.TIMECARD(SCH_1):PAGE162

FPGA_BRD_REV1 @TIMECARD_LIB.TIMECARD(SCH_1):FPGA_BRD_REV1
  R216    1      1 RESISTOR-G155-11001-01,1KOHM,1%   I391 @TIMECARD_LIB.TIMECARD(SCH_1):PAGE127
  R215    2      2 RESISTOR-G155-11002-01,10KOHM,A   I394 @TIMECARD_LIB.TIMECARD(SCH_1):PAGE127
   U24  N19 IO_L17N_T2_A25_15 XC7A200T_2FBG484C_FBG484-G240-A   I228 @TIMECARD_LIB.TIMECARD(SCH_1):PAGE162

FPGA_BRD_REV2 @TIMECARD_LIB.TIMECARD(SCH_1):FPGA_BRD_REV2
  R213    2      2 RESISTOR-G155-11002-01,10KOHM,A   I396 @TIMECARD_LIB.TIMECARD(SCH_1):PAGE127
  R214    1      1 RESISTOR-G155-11001-01,1KOHM,1%   I397 @TIMECARD_LIB.TIMECARD(SCH_1):PAGE127
   U24  N18 IO_L17P_T2_A26_15 XC7A200T_2FBG484C_FBG484-G240-A   I228 @TIMECARD_LIB.TIMECARD(SCH_1):PAGE162

FPGA_CFG_INIT_N @TIMECARD_LIB.TIMECARD(SCH_1):FPGA_CFG_INIT_N
   U24  U12 INIT_0* XC7A200T_2FBG484C_FBG484-G240-A   I232 @TIMECARD_LIB.TIMECARD(SCH_1):PAGE127
  R209    1      1 RESISTOR-G155-14701-01,4.7KOHMA   I339 @TIMECARD_LIB.TIMECARD(SCH_1):PAGE127
  R230    2      2 RESISTOR-G155-100R0-J0,0OHM,-   I140 @TIMECARD_LIB.TIMECARD(SCH_1):PAGE515
  R143    1      1 RESISTOR-G155-133R0-01,33OHM,1%   I167 @TIMECARD_LIB.TIMECARD(SCH_1):PAGE515
  R294    2      2 RESISTOR-G155-133R0-01,33OHM,1%    I45 @TIMECARD_LIB.TIMECARD(SCH_1):PAGE516
   J10   10     10 G200_10283_01-G200-10283-01   I173 @TIMECARD_LIB.TIMECARD(SCH_1):PAGE524
  TP46    1      1 TP_PIONT-TP010CT020B030_PTH-TPA  I1684 @TIMECARD_LIB.TIMECARD(SCH_1):PAGE16

FPGA_D00_MOSI @TIMECARD_LIB.TIMECARD(SCH_1):FPGA_D00_MOSI
   U24  P22 IO_L1P_T0_D00_MOSI_14 XC7A200T_2FBG484C_FBG484-G240-A     I2 @TIMECARD_LIB.TIMECARD(SCH_1):PAGE161
  R234    1      1 RESISTOR-G155-133R0-01,33OHM,1%   I258 @TIMECARD_LIB.TIMECARD(SCH_1):PAGE161

FPGA_D01 @TIMECARD_LIB.TIMECARD(SCH_1):FPGA_D01
   U24  R22 IO_L1N_T0_D01_DIN_14 XC7A200T_2FBG484C_FBG484-G240-A     I2 @TIMECARD_LIB.TIMECARD(SCH_1):PAGE161
  R238    1      1 RESISTOR-G155-133R0-01,33OHM,1%   I259 @TIMECARD_LIB.TIMECARD(SCH_1):PAGE161

FPGA_D02 @TIMECARD_LIB.TIMECARD(SCH_1):FPGA_D02
   U24  P21 IO_L2P_T0_D02_14 XC7A200T_2FBG484C_FBG484-G240-A     I2 @TIMECARD_LIB.TIMECARD(SCH_1):PAGE161
  R339    1      1 RESISTOR-G155-133R0-01,33OHM,1%   I261 @TIMECARD_LIB.TIMECARD(SCH_1):PAGE161

FPGA_D03 @TIMECARD_LIB.TIMECARD(SCH_1):FPGA_D03
   U24  R21 IO_L2N_T0_D03_14 XC7A200T_2FBG484C_FBG484-G240-A     I2 @TIMECARD_LIB.TIMECARD(SCH_1):PAGE161
  R348    1      1 RESISTOR-G155-133R0-01,33OHM,1%   I260 @TIMECARD_LIB.TIMECARD(SCH_1):PAGE161

FPGA_DONE @TIMECARD_LIB.TIMECARD(SCH_1):FPGA_DONE
   U24  G11 DONE_0 XC7A200T_2FBG484C_FBG484-G240-A   I232 @TIMECARD_LIB.TIMECARD(SCH_1):PAGE127
  R210    1      1 RESISTOR-G155-13300-01,330OHM,A   I338 @TIMECARD_LIB.TIMECARD(SCH_1):PAGE127
  TP44    1      1 TP_PIONT-TP010CT020B030_PTH-TPA  I1689 @TIMECARD_LIB.TIMECARD(SCH_1):PAGE16
  R208    2      2 RESISTOR-G155-13300-01,330OHM,A   I293 @TIMECARD_LIB.TIMECARD(SCH_1):PAGE14

FPGA_EEPROM_I2C_SCL @TIMECARD_LIB.TIMECARD(SCH_1):FPGA_EEPROM_I2C_SCL
   U24 AB16 IO_L2P_T0_13 XC7A200T_2FBG484C_FBG484-G240-A     I2 @TIMECARD_LIB.TIMECARD(SCH_1):PAGE161
   U37   14    NC4 TS3A5018PWR_TSSOP16-G220-10324A   I448 @TIMECARD_LIB.TIMECARD(SCH_1):PAGE524
  R477    2      2 RESISTOR-G155-11003-01,100KOHMA   I469 @TIMECARD_LIB.TIMECARD(SCH_1):PAGE524

FPGA_EEPROM_I2C_SDA @TIMECARD_LIB.TIMECARD(SCH_1):FPGA_EEPROM_I2C_SDA
   U24 AB17 IO_L2N_T0_13 XC7A200T_2FBG484C_FBG484-G240-A     I2 @TIMECARD_LIB.TIMECARD(SCH_1):PAGE161
   U37   11    NC3 TS3A5018PWR_TSSOP16-G220-10324A   I448 @TIMECARD_LIB.TIMECARD(SCH_1):PAGE524
  R476    2      2 RESISTOR-G155-11003-01,100KOHMA   I468 @TIMECARD_LIB.TIMECARD(SCH_1):PAGE524

FPGA_FCS_B @TIMECARD_LIB.TIMECARD(SCH_1):FPGA_FCS_B
   U24  T19 IO_L6P_T0_FCS_B_14 XC7A200T_2FBG484C_FBG484-G240-A     I2 @TIMECARD_LIB.TIMECARD(SCH_1):PAGE161
  R362    1      1 RESISTOR-G155-133R0-01,33OHM,1%   I263 @TIMECARD_LIB.TIMECARD(SCH_1):PAGE161

FPGA_FLASH_CLK @TIMECARD_LIB.TIMECARD(SCH_1):FPGA_FLASH_CLK
  R207    2      2 RESISTOR-G155-100R0-J0,0OHM,-   I337 @TIMECARD_LIB.TIMECARD(SCH_1):PAGE127
   U38    2    NC1 TS3A5018PWR_TSSOP16-G220-10324A   I400 @TIMECARD_LIB.TIMECARD(SCH_1):PAGE524

FPGA_FLASH_CS_N @TIMECARD_LIB.TIMECARD(SCH_1):FPGA_FLASH_CS_N
   U38   14    NC4 TS3A5018PWR_TSSOP16-G220-10324A   I400 @TIMECARD_LIB.TIMECARD(SCH_1):PAGE524
  R362    2      2 RESISTOR-G155-133R0-01,33OHM,1%   I263 @TIMECARD_LIB.TIMECARD(SCH_1):PAGE161

FPGA_FLASH_DQ0_MOSI @TIMECARD_LIB.TIMECARD(SCH_1):FPGA_FLASH_DQ0_MOSI
   U38    5    NC2 TS3A5018PWR_TSSOP16-G220-10324A   I400 @TIMECARD_LIB.TIMECARD(SCH_1):PAGE524
  R234    2      2 RESISTOR-G155-133R0-01,33OHM,1%   I258 @TIMECARD_LIB.TIMECARD(SCH_1):PAGE161

FPGA_FLASH_DQ1_MISO @TIMECARD_LIB.TIMECARD(SCH_1):FPGA_FLASH_DQ1_MISO
   U38   11    NC3 TS3A5018PWR_TSSOP16-G220-10324A   I400 @TIMECARD_LIB.TIMECARD(SCH_1):PAGE524
  R435    1      1 RESISTOR-G155-11003-01,100KOHMA   I251 @TIMECARD_LIB.TIMECARD(SCH_1):PAGE161
  R238    2      2 RESISTOR-G155-133R0-01,33OHM,1%   I259 @TIMECARD_LIB.TIMECARD(SCH_1):PAGE161

FPGA_FLASH_DQ2 @TIMECARD_LIB.TIMECARD(SCH_1):FPGA_FLASH_DQ2
   U39    4      A NLASB3157DFT2G_SC88-G223-10187A   I407 @TIMECARD_LIB.TIMECARD(SCH_1):PAGE524
  R464    1      1 RESISTOR-G155-100R0-J0,0OHM,-   I493 @TIMECARD_LIB.TIMECARD(SCH_1):PAGE524
  R339    2      2 RESISTOR-G155-133R0-01,33OHM,1%   I261 @TIMECARD_LIB.TIMECARD(SCH_1):PAGE161

FPGA_FLASH_DQ3 @TIMECARD_LIB.TIMECARD(SCH_1):FPGA_FLASH_DQ3
   U40    4      A NLASB3157DFT2G_SC88-G223-10187A   I408 @TIMECARD_LIB.TIMECARD(SCH_1):PAGE524
  R465    1      1 RESISTOR-G155-100R0-J0,0OHM,-   I494 @TIMECARD_LIB.TIMECARD(SCH_1):PAGE524
  R348    2      2 RESISTOR-G155-133R0-01,33OHM,1%   I260 @TIMECARD_LIB.TIMECARD(SCH_1):PAGE161

FPGA_IN_BNO080_INT_N @TIMECARD_LIB.TIMECARD(SCH_1):FPGA_IN_BNO080_INT_N
   U24  L14 IO_L22P_T3_A17_15 XC7A200T_2FBG484C_FBG484-G240-A   I228 @TIMECARD_LIB.TIMECARD(SCH_1):PAGE162
   R79    1      1 RESISTOR-G155-133R0-01,33OHM,1%    I31 @TIMECARD_LIB.TIMECARD(SCH_1):PAGE9
  R289    2      2 RESISTOR-G155-14701-01,4.7KOHMA    I38 @TIMECARD_LIB.TIMECARD(SCH_1):PAGE9

FPGA_IN_GPSTP1_OUT @TIMECARD_LIB.TIMECARD(SCH_1):FPGA_IN_GPSTP1_OUT
  R117    2      2 RESISTOR-G155-133R0-01,33OHM,1%    I20 @TIMECARD_LIB.TIMECARD(SCH_1):PAGE11
   U24  W14 IO_L6P_T0_13 XC7A200T_2FBG484C_FBG484-G240-A     I2 @TIMECARD_LIB.TIMECARD(SCH_1):PAGE161
  R270    2      2 RESISTOR-G155-14701-01,4.7KOHMA   I140 @TIMECARD_LIB.TIMECARD(SCH_1):PAGE161

FPGA_IN_GPSTP2_OUT @TIMECARD_LIB.TIMECARD(SCH_1):FPGA_IN_GPSTP2_OUT
  R111    1      1 RESISTOR-G155-133R0-01,33OHM,1%     I5 @TIMECARD_LIB.TIMECARD(SCH_1):PAGE11
   U24  Y14 IO_L6N_T0_VREF_13 XC7A200T_2FBG484C_FBG484-G240-A     I2 @TIMECARD_LIB.TIMECARD(SCH_1):PAGE161
  R271    2      2 RESISTOR-G155-14701-01,4.7KOHMA   I200 @TIMECARD_LIB.TIMECARD(SCH_1):PAGE161

FPGA_IN_LM75B_INT1_N @TIMECARD_LIB.TIMECARD(SCH_1):FPGA_IN_LM75B_INT1_N
    U8    3     OS LM75BDP_TSSOP8-G220-10215-01    I34 @TIMECARD_LIB.TIMECARD(SCH_1):PAGE6
  R340    2      2 RESISTOR-G155-14701-01,4.7KOHMA    I41 @TIMECARD_LIB.TIMECARD(SCH_1):PAGE6
   U24  N22 IO_L15P_T2_DQS_15 XC7A200T_2FBG484C_FBG484-G240-A   I228 @TIMECARD_LIB.TIMECARD(SCH_1):PAGE162
  TP24    1      1 TP_PIONT-TP010CT020B030_PTH-TPA  I1648 @TIMECARD_LIB.TIMECARD(SCH_1):PAGE16

FPGA_IN_LM75B_INT2_N @TIMECARD_LIB.TIMECARD(SCH_1):FPGA_IN_LM75B_INT2_N
   U24  M22 IO_L15N_T2_DQS_ADV_B_15 XC7A200T_2FBG484C_FBG484-G240-A   I228 @TIMECARD_LIB.TIMECARD(SCH_1):PAGE162
   U35    3     OS LM75BDP_TSSOP8-G220-10215-01    I59 @TIMECARD_LIB.TIMECARD(SCH_1):PAGE6
  R422    2      2 RESISTOR-G155-14701-01,4.7KOHMA    I64 @TIMECARD_LIB.TIMECARD(SCH_1):PAGE6
  TP23    1      1 TP_PIONT-TP010CT020B030_PTH-TPA  I1647 @TIMECARD_LIB.TIMECARD(SCH_1):PAGE16

FPGA_IN_LM75B_INT3_N @TIMECARD_LIB.TIMECARD(SCH_1):FPGA_IN_LM75B_INT3_N
   U24  M18 IO_L16P_T2_A28_15 XC7A200T_2FBG484C_FBG484-G240-A   I228 @TIMECARD_LIB.TIMECARD(SCH_1):PAGE162
   U36    3     OS LM75BDP_TSSOP8-G220-10215-01    I81 @TIMECARD_LIB.TIMECARD(SCH_1):PAGE6
  R423    2      2 RESISTOR-G155-14701-01,4.7KOHMA    I88 @TIMECARD_LIB.TIMECARD(SCH_1):PAGE6
  TP22    1      1 TP_PIONT-TP010CT020B030_PTH-TPA  I1646 @TIMECARD_LIB.TIMECARD(SCH_1):PAGE16

FPGA_IN_MAC_10MHZ_OUT @TIMECARD_LIB.TIMECARD(SCH_1):FPGA_IN_MAC_10MHZ_OUT
   U24  V13 IO_L13P_T2_MRCC_13 XC7A200T_2FBG484C_FBG484-G240-A     I2 @TIMECARD_LIB.TIMECARD(SCH_1):PAGE161
   R92    2      2 RESISTOR-G155-11000-01,100OHM,A    I55 @TIMECARD_LIB.TIMECARD(SCH_1):PAGE527
  R502    2      2 RESISTOR-G155-14701-01,4.7KOHMA   I247 @TIMECARD_LIB.TIMECARD(SCH_1):PAGE161

FPGA_IN_MAC_ALARM_OUT_N @TIMECARD_LIB.TIMECARD(SCH_1):FPGA_IN_MAC_ALARM_OUT_N
   U24 AB10 IO_L8N_T1_13 XC7A200T_2FBG484C_FBG484-G240-A     I2 @TIMECARD_LIB.TIMECARD(SCH_1):PAGE161
   R96    2      2 RESISTOR-G155-133R0-01,33OHM,1%    I23 @TIMECARD_LIB.TIMECARD(SCH_1):PAGE527
  R287    1      1 RESISTOR-G155-14701-01,4.7KOHMA   I211 @TIMECARD_LIB.TIMECARD(SCH_1):PAGE527

FPGA_IN_MAC_BITEOUT @TIMECARD_LIB.TIMECARD(SCH_1):FPGA_IN_MAC_BITE OUT
   U24  AA9 IO_L8P_T1_13 XC7A200T_2FBG484C_FBG484-G240-A     I2 @TIMECARD_LIB.TIMECARD(SCH_1):PAGE161
  R288    2      2 RESISTOR-G155-14701-01,4.7KOHMA   I201 @TIMECARD_LIB.TIMECARD(SCH_1):PAGE161
   R93    2      2 RESISTOR-G155-133R0-01,33OHM,1%    I53 @TIMECARD_LIB.TIMECARD(SCH_1):PAGE527

FPGA_IN_MAC_PPS_OUTN @TIMECARD_LIB.TIMECARD(SCH_1):FPGA_IN_MAC_PPS_OUTN
   U24   Y1 IO_L5N_T0_34 XC7A200T_2FBG484C_FBG484-G240-A     I1 @TIMECARD_LIB.TIMECARD(SCH_1):PAGE163
  R275    2      2 RESISTOR-G155-11000-01,100OHM,A    I39 @TIMECARD_LIB.TIMECARD(SCH_1):PAGE163
   R88    1      1 RESISTOR-G155-100R0-J0,0OHM,-    I13 @TIMECARD_LIB.TIMECARD(SCH_1):PAGE527
  R438    1      1 RESISTOR-G155-11002-01,10KOHM,A   I132 @TIMECARD_LIB.TIMECARD(SCH_1):PAGE163
  R441    1      1 RESISTOR-G155-11002-01,10KOHM,A   I134 @TIMECARD_LIB.TIMECARD(SCH_1):PAGE163

FPGA_IN_MAC_PPS_OUTP @TIMECARD_LIB.TIMECARD(SCH_1):FPGA_IN_MAC_PPS_OUTP
   U24   W1 IO_L5P_T0_34 XC7A200T_2FBG484C_FBG484-G240-A     I1 @TIMECARD_LIB.TIMECARD(SCH_1):PAGE163
  R275    1      1 RESISTOR-G155-11000-01,100OHM,A    I39 @TIMECARD_LIB.TIMECARD(SCH_1):PAGE163
   R87    1      1 RESISTOR-G155-100R0-J0,0OHM,-    I14 @TIMECARD_LIB.TIMECARD(SCH_1):PAGE527
  R439    1      1 RESISTOR-G155-11002-01,10KOHM,A   I133 @TIMECARD_LIB.TIMECARD(SCH_1):PAGE163
  R440    1      1 RESISTOR-G155-11002-01,10KOHM,A   I135 @TIMECARD_LIB.TIMECARD(SCH_1):PAGE163

FPGA_IN_MAC_USB_OC_N @TIMECARD_LIB.TIMECARD(SCH_1):FPGA_IN_MAC_USB_OC_N
   U24  M15 IO_L24P_T3_RS1_15 XC7A200T_2FBG484C_FBG484-G240-A   I228 @TIMECARD_LIB.TIMECARD(SCH_1):PAGE162
  R107    2      2 RESISTOR-G155-14701-01,4.7KOHMA    I83 @TIMECARD_LIB.TIMECARD(SCH_1):PAGE527
  R267    2      2 RESISTOR-G155-133R0-01,33OHM,1%   I206 @TIMECARD_LIB.TIMECARD(SCH_1):PAGE527

FPGA_IN_RST_DLY_N @TIMECARD_LIB.TIMECARD(SCH_1):FPGA_IN_RST_DLY_N
   U24  J20 IO_L11P_T1_SRCC_15 XC7A200T_2FBG484C_FBG484-G240-A   I228 @TIMECARD_LIB.TIMECARD(SCH_1):PAGE162
   U34    1 RESET* TPS3808G18DBVR_SOT23_6-G222-00A   I139 @TIMECARD_LIB.TIMECARD(SCH_1):PAGE3
  R167    2      2 RESISTOR-G155-11002-01,10KOHM,A   I148 @TIMECARD_LIB.TIMECARD(SCH_1):PAGE3

FPGA_IN_SHT3X_ALERT_N @TIMECARD_LIB.TIMECARD(SCH_1):FPGA_IN_SHT3X_ALERT_N
   U24  J19 IO_L12P_T1_MRCC_15 XC7A200T_2FBG484C_FBG484-G240-A   I228 @TIMECARD_LIB.TIMECARD(SCH_1):PAGE162
  R299    2      2 RESISTOR-G155-133R0-01,33OHM,1%    I40 @TIMECARD_LIB.TIMECARD(SCH_1):PAGE7
  R300    2      2 RESISTOR-G155-14701-01,4.7KOHMA    I41 @TIMECARD_LIB.TIMECARD(SCH_1):PAGE7

FPGA_IO_0 @TIMECARD_LIB.TIMECARD(SCH_1):FPGA_IO_0
   U24  J22 IO_L7P_T1_AD2P_15 XC7A200T_2FBG484C_FBG484-G240-A   I228 @TIMECARD_LIB.TIMECARD(SCH_1):PAGE162
  R171    2      2 RESISTOR-G155-14701-01,4.7KOHMA  I1542 @TIMECARD_LIB.TIMECARD(SCH_1):PAGE16
  R170    2      2 RESISTOR-G155-11002-01,10KOHM,A  I1608 @TIMECARD_LIB.TIMECARD(SCH_1):PAGE16
  R434    2      2 RESISTOR-G155-133R0-01,33OHM,1%  I1721 @TIMECARD_LIB.TIMECARD(SCH_1):PAGE16

FPGA_IO_1 @TIMECARD_LIB.TIMECARD(SCH_1):FPGA_IO_1
   U24  H22 IO_L7N_T1_AD2N_15 XC7A200T_2FBG484C_FBG484-G240-A   I228 @TIMECARD_LIB.TIMECARD(SCH_1):PAGE162
  R173    2      2 RESISTOR-G155-14701-01,4.7KOHMA  I1544 @TIMECARD_LIB.TIMECARD(SCH_1):PAGE16
  R172    2      2 RESISTOR-G155-11002-01,10KOHM,A  I1607 @TIMECARD_LIB.TIMECARD(SCH_1):PAGE16
  R433    2      2 RESISTOR-G155-133R0-01,33OHM,1%  I1720 @TIMECARD_LIB.TIMECARD(SCH_1):PAGE16

FPGA_IO_2 @TIMECARD_LIB.TIMECARD(SCH_1):FPGA_IO_2
   U24  H20 IO_L8P_T1_AD10P_15 XC7A200T_2FBG484C_FBG484-G240-A   I228 @TIMECARD_LIB.TIMECARD(SCH_1):PAGE162
  R284    2      2 RESISTOR-G155-14701-01,4.7KOHMA  I1547 @TIMECARD_LIB.TIMECARD(SCH_1):PAGE16
  R283    2      2 RESISTOR-G155-11002-01,10KOHM,A  I1609 @TIMECARD_LIB.TIMECARD(SCH_1):PAGE16
  R432    2      2 RESISTOR-G155-133R0-01,33OHM,1%  I1719 @TIMECARD_LIB.TIMECARD(SCH_1):PAGE16

FPGA_IO_3 @TIMECARD_LIB.TIMECARD(SCH_1):FPGA_IO_3
   U24  G20 IO_L8N_T1_AD10N_15 XC7A200T_2FBG484C_FBG484-G240-A   I228 @TIMECARD_LIB.TIMECARD(SCH_1):PAGE162
  R286    2      2 RESISTOR-G155-14701-01,4.7KOHMA  I1549 @TIMECARD_LIB.TIMECARD(SCH_1):PAGE16
  R285    2      2 RESISTOR-G155-11002-01,10KOHM,A  I1606 @TIMECARD_LIB.TIMECARD(SCH_1):PAGE16
  R431    2      2 RESISTOR-G155-133R0-01,33OHM,1%  I1718 @TIMECARD_LIB.TIMECARD(SCH_1):PAGE16

FPGA_IO_4 @TIMECARD_LIB.TIMECARD(SCH_1):FPGA_IO_4
   U24  K21 IO_L9P_T1_DQS_AD3P_15 XC7A200T_2FBG484C_FBG484-G240-A   I228 @TIMECARD_LIB.TIMECARD(SCH_1):PAGE162
  R293    2      2 RESISTOR-G155-14701-01,4.7KOHMA  I1555 @TIMECARD_LIB.TIMECARD(SCH_1):PAGE16
  R292    2      2 RESISTOR-G155-11002-01,10KOHM,A  I1605 @TIMECARD_LIB.TIMECARD(SCH_1):PAGE16
  R430    1      1 RESISTOR-G155-133R0-01,33OHM,1%  I1706 @TIMECARD_LIB.TIMECARD(SCH_1):PAGE16

FPGA_IO_5 @TIMECARD_LIB.TIMECARD(SCH_1):FPGA_IO_5
   U24  K22 IO_L9N_T1_DQS_AD3N_15 XC7A200T_2FBG484C_FBG484-G240-A   I228 @TIMECARD_LIB.TIMECARD(SCH_1):PAGE162
  R309    2      2 RESISTOR-G155-14701-01,4.7KOHMA  I1557 @TIMECARD_LIB.TIMECARD(SCH_1):PAGE16
  R308    2      2 RESISTOR-G155-11002-01,10KOHM,A  I1604 @TIMECARD_LIB.TIMECARD(SCH_1):PAGE16
  R429    1      1 RESISTOR-G155-133R0-01,33OHM,1%  I1709 @TIMECARD_LIB.TIMECARD(SCH_1):PAGE16

FPGA_IO_6 @TIMECARD_LIB.TIMECARD(SCH_1):FPGA_IO_6
   U24  M21 IO_L10P_T1_AD11P_15 XC7A200T_2FBG484C_FBG484-G240-A   I228 @TIMECARD_LIB.TIMECARD(SCH_1):PAGE162
  R326    2      2 RESISTOR-G155-14701-01,4.7KOHMA  I1552 @TIMECARD_LIB.TIMECARD(SCH_1):PAGE16
  R325    2      2 RESISTOR-G155-11002-01,10KOHM,A  I1602 @TIMECARD_LIB.TIMECARD(SCH_1):PAGE16
  R428    1      1 RESISTOR-G155-133R0-01,33OHM,1%  I1708 @TIMECARD_LIB.TIMECARD(SCH_1):PAGE16

FPGA_IO_7 @TIMECARD_LIB.TIMECARD(SCH_1):FPGA_IO_7
   U24  L21 IO_L10N_T1_AD11N_15 XC7A200T_2FBG484C_FBG484-G240-A   I228 @TIMECARD_LIB.TIMECARD(SCH_1):PAGE162
  R328    2      2 RESISTOR-G155-14701-01,4.7KOHMA  I1550 @TIMECARD_LIB.TIMECARD(SCH_1):PAGE16
  R327    2      2 RESISTOR-G155-11002-01,10KOHM,A  I1603 @TIMECARD_LIB.TIMECARD(SCH_1):PAGE16
  R329    1      1 RESISTOR-G155-133R0-01,33OHM,1%  I1707 @TIMECARD_LIB.TIMECARD(SCH_1):PAGE16

FPGA_IO_FT_USBDET_RST_N @TIMECARD_LIB.TIMECARD(SCH_1):FPGA_IO_FT_USBDET_RST_N
   U24 AA15 IO_L4P_T0_13 XC7A200T_2FBG484C_FBG484-G240-A     I2 @TIMECARD_LIB.TIMECARD(SCH_1):PAGE161
  R443    2      2 RESISTOR-G155-11000-01,100OHM,A   I446 @TIMECARD_LIB.TIMECARD(SCH_1):PAGE524

FPGA_M0 @TIMECARD_LIB.TIMECARD(SCH_1):FPGA_M0
   U24  U11   M0_0 XC7A200T_2FBG484C_FBG484-G240-A   I232 @TIMECARD_LIB.TIMECARD(SCH_1):PAGE127
  R211    2      2 RESISTOR-G155-11000-01,100OHM,A   I404 @TIMECARD_LIB.TIMECARD(SCH_1):PAGE127
  R212    1      1 RESISTOR-G155-11000-01,100OHM,A   I407 @TIMECARD_LIB.TIMECARD(SCH_1):PAGE127

FPGA_M1 @TIMECARD_LIB.TIMECARD(SCH_1):FPGA_M1
   U24  U10   M1_0 XC7A200T_2FBG484C_FBG484-G240-A   I232 @TIMECARD_LIB.TIMECARD(SCH_1):PAGE127
  R217    2      2 RESISTOR-G155-11000-01,100OHM,A   I402 @TIMECARD_LIB.TIMECARD(SCH_1):PAGE127
  R218    1      1 RESISTOR-G155-11000-01,100OHM,A   I406 @TIMECARD_LIB.TIMECARD(SCH_1):PAGE127

FPGA_M2 @TIMECARD_LIB.TIMECARD(SCH_1):FPGA_M2
   U24   U9   M2_0 XC7A200T_2FBG484C_FBG484-G240-A   I232 @TIMECARD_LIB.TIMECARD(SCH_1):PAGE127
  R221    2      2 RESISTOR-G155-11000-01,100OHM,A   I403 @TIMECARD_LIB.TIMECARD(SCH_1):PAGE127
  R222    1      1 RESISTOR-G155-11000-01,100OHM,A   I405 @TIMECARD_LIB.TIMECARD(SCH_1):PAGE127

FPGA_MGTAVTT @TIMECARD_LIB.TIMECARD(SCH_1):FPGA_MGTAVTT
  R196    1      1 RESISTOR-G155-11000-01,100OHM,A   I332 @TIMECARD_LIB.TIMECARD(SCH_1):PAGE127
   L35    1      1 FERRITEBEAD-G191-10100-01,120OA    I36 @TIMECARD_LIB.TIMECARD(SCH_1):PAGE164
   U24  B11 MGTAVTT_1 XC7A200T_2FBG484C_FBG484-G240-A   I138 @TIMECARD_LIB.TIMECARD(SCH_1):PAGE164
   U24   B5 MGTAVTT_2 XC7A200T_2FBG484C_FBG484-G240-A   I138 @TIMECARD_LIB.TIMECARD(SCH_1):PAGE164
   U24   B7 MGTAVTT_3 XC7A200T_2FBG484C_FBG484-G240-A   I138 @TIMECARD_LIB.TIMECARD(SCH_1):PAGE164
   U24   B9 MGTAVTT_4 XC7A200T_2FBG484C_FBG484-G240-A   I138 @TIMECARD_LIB.TIMECARD(SCH_1):PAGE164
   U24   C4 MGTAVTT_5 XC7A200T_2FBG484C_FBG484-G240-A   I138 @TIMECARD_LIB.TIMECARD(SCH_1):PAGE164
   U24   C8 MGTAVTT_6 XC7A200T_2FBG484C_FBG484-G240-A   I138 @TIMECARD_LIB.TIMECARD(SCH_1):PAGE164
  C117    1      1 CAPACITOR-G105-0F475-BM,4.7UF,A   I246 @TIMECARD_LIB.TIMECARD(SCH_1):PAGE164
  C110    1      1 CAPACITOR-G105-0B104-CK,0.1UF,A   I256 @TIMECARD_LIB.TIMECARD(SCH_1):PAGE164
  C104    1      1 CAPACITOR-G105-0B104-CK,0.1UF,A   I257 @TIMECARD_LIB.TIMECARD(SCH_1):PAGE164
  C217    1      1 CAPACITOR-G105-0B104-CK,0.1UF,A   I258 @TIMECARD_LIB.TIMECARD(SCH_1):PAGE164
  C209    1      1 CAPACITOR-G105-0B104-CK,0.1UF,A   I259 @TIMECARD_LIB.TIMECARD(SCH_1):PAGE164
  C205    1      1 CAPACITOR-G105-0B104-CK,0.1UF,A   I260 @TIMECARD_LIB.TIMECARD(SCH_1):PAGE164
  C125    1      1 CAPACITOR-G107-0F476-AM,47UF,2A   I264 @TIMECARD_LIB.TIMECARD(SCH_1):PAGE164

FPGA_MGTRREF @TIMECARD_LIB.TIMECARD(SCH_1):FPGA_MGTRREF
   U24   F8 MGTRREF_216 XC7A200T_2FBG484C_FBG484-G240-A   I232 @TIMECARD_LIB.TIMECARD(SCH_1):PAGE127
  R196    2      2 RESISTOR-G155-11000-01,100OHM,A   I332 @TIMECARD_LIB.TIMECARD(SCH_1):PAGE127
  TP47    1      1 TP_PIONT-TP010CT020B030_PTH-TPA  I1693 @TIMECARD_LIB.TIMECARD(SCH_1):PAGE16

FPGA_M_RGB_LED_I2C_SCL @TIMECARD_LIB.TIMECARD(SCH_1):FPGA_M_RGB_LED_I2C_SCL
   U24  W20 IO_L12N_T1_MRCC_14 XC7A200T_2FBG484C_FBG484-G240-A     I2 @TIMECARD_LIB.TIMECARD(SCH_1):PAGE161
  R322    1      1 RESISTOR-G155-133R0-01,33OHM,1%   I257 @TIMECARD_LIB.TIMECARD(SCH_1):PAGE14

FPGA_M_RGB_LED_I2C_SDA @TIMECARD_LIB.TIMECARD(SCH_1):FPGA_M_RGB_LED_I2C_SDA
   U24  W19 IO_L12P_T1_MRCC_14 XC7A200T_2FBG484C_FBG484-G240-A     I2 @TIMECARD_LIB.TIMECARD(SCH_1):PAGE161
  R321    1      1 RESISTOR-G155-133R0-01,33OHM,1%   I258 @TIMECARD_LIB.TIMECARD(SCH_1):PAGE14

FPGA_OUT_BNO080_BOOT_N @TIMECARD_LIB.TIMECARD(SCH_1):FPGA_OUT_BNO080_BOOT_N
   U24  L15 IO_L22N_T3_A16_15 XC7A200T_2FBG484C_FBG484-G240-A   I228 @TIMECARD_LIB.TIMECARD(SCH_1):PAGE162
   R80    1      1 RESISTOR-G155-133R0-01,33OHM,1%    I32 @TIMECARD_LIB.TIMECARD(SCH_1):PAGE9

FPGA_OUT_BNO080_RST_N @TIMECARD_LIB.TIMECARD(SCH_1):FPGA_OUT_BNO080_RST_N
   U24  J17 IO_L21N_T3_DQS_A18_15 XC7A200T_2FBG484C_FBG484-G240-A   I228 @TIMECARD_LIB.TIMECARD(SCH_1):PAGE162
   R78    2      2 RESISTOR-G155-133R0-01,33OHM,1%    I41 @TIMECARD_LIB.TIMECARD(SCH_1):PAGE9

FPGA_OUT_GPS_LED_BLUE_N @TIMECARD_LIB.TIMECARD(SCH_1):FPGA_OUT_GPS_LED_BLUE_N
   U24  B20 IO_L16P_T2_16 XC7A200T_2FBG484C_FBG484-G240-A   I228 @TIMECARD_LIB.TIMECARD(SCH_1):PAGE162
  R425    1      1 RESISTOR-G155-11000-01,100OHM,A   I170 @TIMECARD_LIB.TIMECARD(SCH_1):PAGE14

FPGA_OUT_GPS_LED_GREEN_N @TIMECARD_LIB.TIMECARD(SCH_1):FPGA_OUT_GPS_LED_GREEN_N
   U24  A20 IO_L16N_T2_16 XC7A200T_2FBG484C_FBG484-G240-A   I228 @TIMECARD_LIB.TIMECARD(SCH_1):PAGE162
  R426    1      1 RESISTOR-G155-11000-01,100OHM,A   I179 @TIMECARD_LIB.TIMECARD(SCH_1):PAGE14

FPGA_OUT_GPS_LED_RED_N @TIMECARD_LIB.TIMECARD(SCH_1):FPGA_OUT_GPS_LED_RED_N
   U24  A18 IO_L17P_T2_16 XC7A200T_2FBG484C_FBG484-G240-A   I228 @TIMECARD_LIB.TIMECARD(SCH_1):PAGE162
  R427    1      1 RESISTOR-G155-11000-01,100OHM,A   I188 @TIMECARD_LIB.TIMECARD(SCH_1):PAGE14

FPGA_OUT_GPS_RST_N @TIMECARD_LIB.TIMECARD(SCH_1):FPGA_OUT_GPS_RST_N
  R116    2      2 RESISTOR-G155-133R0-01,33OHM,1%    I25 @TIMECARD_LIB.TIMECARD(SCH_1):PAGE11
   U24  Y16 IO_L1P_T0_13 XC7A200T_2FBG484C_FBG484-G240-A     I2 @TIMECARD_LIB.TIMECARD(SCH_1):PAGE161

FPGA_OUT_I2C_BUFFER_EN @TIMECARD_LIB.TIMECARD(SCH_1):FPGA_OUT_I2C_BUFFER_EN
   U24  K16 IO_L23N_T3_FWE_B_15 XC7A200T_2FBG484C_FBG484-G240-A   I228 @TIMECARD_LIB.TIMECARD(SCH_1):PAGE162
  R354    1      1 RESISTOR-G155-133R0-01,33OHM,1%   I114 @TIMECARD_LIB.TIMECARD(SCH_1):PAGE3

FPGA_OUT_MACUSBPOWER_EN @TIMECARD_LIB.TIMECARD(SCH_1):FPGA_OUT_MACUSBPOWER_EN
   U24  V15 IO_L14N_T2_SRCC_13 XC7A200T_2FBG484C_FBG484-G240-A     I2 @TIMECARD_LIB.TIMECARD(SCH_1):PAGE161
   U10    1      A CL5003148A-G220-10019-01   I147 @TIMECARD_LIB.TIMECARD(SCH_1):PAGE527
   R99    1      1 RESISTOR-G155-14701-01,4.7KOHMA   I149 @TIMECARD_LIB.TIMECARD(SCH_1):PAGE527
  R100    1      1 RESISTOR-G155-133R0-01,33OHM,1%   I155 @TIMECARD_LIB.TIMECARD(SCH_1):PAGE527

FPGA_OUT_MAC_PPS_IN0N @TIMECARD_LIB.TIMECARD(SCH_1):FPGA_OUT_MAC_PPS_IN0N
   U24  AB2 IO_L8N_T1_34 XC7A200T_2FBG484C_FBG484-G240-A     I1 @TIMECARD_LIB.TIMECARD(SCH_1):PAGE163
  R276    2      2 RESISTOR-G155-11000-01,100OHM,A    I38 @TIMECARD_LIB.TIMECARD(SCH_1):PAGE163
   R86    1      1 RESISTOR-G155-100R0-J0,0OHM,-    I29 @TIMECARD_LIB.TIMECARD(SCH_1):PAGE527

FPGA_OUT_MAC_PPS_IN0P @TIMECARD_LIB.TIMECARD(SCH_1):FPGA_OUT_MAC_PPS_IN0P
   U24  AB3 IO_L8P_T1_34 XC7A200T_2FBG484C_FBG484-G240-A     I1 @TIMECARD_LIB.TIMECARD(SCH_1):PAGE163
  R276    1      1 RESISTOR-G155-11000-01,100OHM,A    I38 @TIMECARD_LIB.TIMECARD(SCH_1):PAGE163
   R85    1      1 RESISTOR-G155-100R0-J0,0OHM,-    I30 @TIMECARD_LIB.TIMECARD(SCH_1):PAGE527

FPGA_OUT_MAC_PPS_IN1N @TIMECARD_LIB.TIMECARD(SCH_1):FPGA_OUT_MAC_PPS_IN1N
   U24  AB5 IO_L10N_T1_34 XC7A200T_2FBG484C_FBG484-G240-A     I1 @TIMECARD_LIB.TIMECARD(SCH_1):PAGE163
  R277    2      2 RESISTOR-G155-11000-01,100OHM,A    I37 @TIMECARD_LIB.TIMECARD(SCH_1):PAGE163
   R84    1      1 RESISTOR-G155-100R0-J0,0OHM,-    I31 @TIMECARD_LIB.TIMECARD(SCH_1):PAGE527

FPGA_OUT_MAC_PPS_IN1P @TIMECARD_LIB.TIMECARD(SCH_1):FPGA_OUT_MAC_PPS_IN1P
   U24  AA5 IO_L10P_T1_34 XC7A200T_2FBG484C_FBG484-G240-A     I1 @TIMECARD_LIB.TIMECARD(SCH_1):PAGE163
  R277    1      1 RESISTOR-G155-11000-01,100OHM,A    I37 @TIMECARD_LIB.TIMECARD(SCH_1):PAGE163
   R83    1      1 RESISTOR-G155-100R0-J0,0OHM,-    I32 @TIMECARD_LIB.TIMECARD(SCH_1):PAGE527

FPGA_OUT_MUX1_SEL @TIMECARD_LIB.TIMECARD(SCH_1):FPGA_OUT_MUX1_SEL
   U24  H13 IO_L1P_T0_AD0P_15 XC7A200T_2FBG484C_FBG484-G240-A   I228 @TIMECARD_LIB.TIMECARD(SCH_1):PAGE162
  R448    2      2 RESISTOR-G155-133R0-01,33OHM,1%   I423 @TIMECARD_LIB.TIMECARD(SCH_1):PAGE524

FPGA_OUT_MUX2_SEL @TIMECARD_LIB.TIMECARD(SCH_1):FPGA_OUT_MUX2_SEL
   U24  G13 IO_L1N_T0_AD0N_15 XC7A200T_2FBG484C_FBG484-G240-A   I228 @TIMECARD_LIB.TIMECARD(SCH_1):PAGE162
  R461    1      1 RESISTOR-G155-133R0-01,33OHM,1%   I411 @TIMECARD_LIB.TIMECARD(SCH_1):PAGE524

FPGA_OUT_MUX3_SEL @TIMECARD_LIB.TIMECARD(SCH_1):FPGA_OUT_MUX3_SEL
   U24  G15 IO_L2P_T0_AD8P_15 XC7A200T_2FBG484C_FBG484-G240-A   I228 @TIMECARD_LIB.TIMECARD(SCH_1):PAGE162
  R485    1      1 RESISTOR-G155-133R0-01,33OHM,1%   I459 @TIMECARD_LIB.TIMECARD(SCH_1):PAGE524

FPGA_OUT_PCA9546_RST_N @TIMECARD_LIB.TIMECARD(SCH_1):FPGA_OUT_PCA9546_RST_N
   U24  U16 IO_L17N_T2_13 XC7A200T_2FBG484C_FBG484-G240-A     I2 @TIMECARD_LIB.TIMECARD(SCH_1):PAGE161
   R60    1      1 RESISTOR-G155-133R0-01,33OHM,1%   I125 @TIMECARD_LIB.TIMECARD(SCH_1):PAGE5

FPGA_OUT_RGB_LED_SHUTDOWN_N @TIMECARD_LIB.TIMECARD(SCH_1):FPGA_OUT_RGB_LED_SHUTDOWN_N
   U24  Y18 IO_L13P_T2_MRCC_14 XC7A200T_2FBG484C_FBG484-G240-A     I2 @TIMECARD_LIB.TIMECARD(SCH_1):PAGE161
  R319    1      1 RESISTOR-G155-133R0-01,33OHM,1%   I249 @TIMECARD_LIB.TIMECARD(SCH_1):PAGE14

FPGA_OUT_SEC_EEPROM_WP @TIMECARD_LIB.TIMECARD(SCH_1):FPGA_OUT_SEC_EEPROM_WP
   U24 AB13 IO_L3N_T0_DQS_13 XC7A200T_2FBG484C_FBG484-G240-A     I2 @TIMECARD_LIB.TIMECARD(SCH_1):PAGE161
    R2    1      1 RESISTOR-G155-13300-01,330OHM,A   I173 @TIMECARD_LIB.TIMECARD(SCH_1):PAGE5

FPGA_OUT_SHT3X_RST_N @TIMECARD_LIB.TIMECARD(SCH_1):FPGA_OUT_SHT3X_RST_N
   U24  H19 IO_L12N_T1_MRCC_15 XC7A200T_2FBG484C_FBG484-G240-A   I228 @TIMECARD_LIB.TIMECARD(SCH_1):PAGE162
  R298    2      2 RESISTOR-G155-133R0-01,33OHM,1%    I33 @TIMECARD_LIB.TIMECARD(SCH_1):PAGE7

FPGA_OUT_SMA1_LED_BLUE_N @TIMECARD_LIB.TIMECARD(SCH_1):FPGA_OUT_SMA1_LED_BLUE_N
   U24  F13 IO_L1P_T0_16 XC7A200T_2FBG484C_FBG484-G240-A   I228 @TIMECARD_LIB.TIMECARD(SCH_1):PAGE162
  R124    1      1 RESISTOR-G155-11000-01,100OHM,A   I160 @TIMECARD_LIB.TIMECARD(SCH_1):PAGE14

FPGA_OUT_SMA1_LED_GREEN_N @TIMECARD_LIB.TIMECARD(SCH_1):FPGA_OUT_SMA1_LED_GREEN_N
   U24  F14 IO_L1N_T0_16 XC7A200T_2FBG484C_FBG484-G240-A   I228 @TIMECARD_LIB.TIMECARD(SCH_1):PAGE162
  R125    1      1 RESISTOR-G155-11000-01,100OHM,A   I161 @TIMECARD_LIB.TIMECARD(SCH_1):PAGE14

FPGA_OUT_SMA1_LED_RED_N @TIMECARD_LIB.TIMECARD(SCH_1):FPGA_OUT_SMA1_LED_RED_N
   U24  F16 IO_L2P_T0_16 XC7A200T_2FBG484C_FBG484-G240-A   I228 @TIMECARD_LIB.TIMECARD(SCH_1):PAGE162
  R272    1      1 RESISTOR-G155-11000-01,100OHM,A   I163 @TIMECARD_LIB.TIMECARD(SCH_1):PAGE14

FPGA_OUT_SMA2_LED_BLUE_N @TIMECARD_LIB.TIMECARD(SCH_1):FPGA_OUT_SMA2_LED_BLUE_N
   U24  C14 IO_L3P_T0_DQS_16 XC7A200T_2FBG484C_FBG484-G240-A   I228 @TIMECARD_LIB.TIMECARD(SCH_1):PAGE162
  R273    1      1 RESISTOR-G155-11000-01,100OHM,A   I165 @TIMECARD_LIB.TIMECARD(SCH_1):PAGE14

FPGA_OUT_SMA2_LED_GREEN_N @TIMECARD_LIB.TIMECARD(SCH_1):FPGA_OUT_SMA2_LED_GREEN_N
   U24  C15 IO_L3N_T0_DQS_16 XC7A200T_2FBG484C_FBG484-G240-A   I228 @TIMECARD_LIB.TIMECARD(SCH_1):PAGE162
  R274    1      1 RESISTOR-G155-11000-01,100OHM,A   I171 @TIMECARD_LIB.TIMECARD(SCH_1):PAGE14

FPGA_OUT_SMA2_LED_RED_N @TIMECARD_LIB.TIMECARD(SCH_1):FPGA_OUT_SMA2_LED_RED_N
   U24  E13 IO_L4P_T0_16 XC7A200T_2FBG484C_FBG484-G240-A   I228 @TIMECARD_LIB.TIMECARD(SCH_1):PAGE162
  R373    1      1 RESISTOR-G155-11000-01,100OHM,A   I181 @TIMECARD_LIB.TIMECARD(SCH_1):PAGE14

FPGA_OUT_SMA3_LED_BLUE_N @TIMECARD_LIB.TIMECARD(SCH_1):FPGA_OUT_SMA3_LED_BLUE_N
   U24  D17 IO_L12P_T1_MRCC_16 XC7A200T_2FBG484C_FBG484-G240-A   I228 @TIMECARD_LIB.TIMECARD(SCH_1):PAGE162
  R374    1      1 RESISTOR-G155-11000-01,100OHM,A   I168 @TIMECARD_LIB.TIMECARD(SCH_1):PAGE14

FPGA_OUT_SMA3_LED_GREEN_N @TIMECARD_LIB.TIMECARD(SCH_1):FPGA_OUT_SMA3_LED_GREEN_N
   U24  C17 IO_L12N_T1_MRCC_16 XC7A200T_2FBG484C_FBG484-G240-A   I228 @TIMECARD_LIB.TIMECARD(SCH_1):PAGE162
  R375    1      1 RESISTOR-G155-11000-01,100OHM,A   I174 @TIMECARD_LIB.TIMECARD(SCH_1):PAGE14

FPGA_OUT_SMA3_LED_RED_N @TIMECARD_LIB.TIMECARD(SCH_1):FPGA_OUT_SMA3_LED_RED_N
   U24  C18 IO_L13P_T2_MRCC_16 XC7A200T_2FBG484C_FBG484-G240-A   I228 @TIMECARD_LIB.TIMECARD(SCH_1):PAGE162
  R376    1      1 RESISTOR-G155-11000-01,100OHM,A   I184 @TIMECARD_LIB.TIMECARD(SCH_1):PAGE14

FPGA_OUT_SMA4_LED_BLUE_N @TIMECARD_LIB.TIMECARD(SCH_1):FPGA_OUT_SMA4_LED_BLUE_N
   U24  E19 IO_L14P_T2_SRCC_16 XC7A200T_2FBG484C_FBG484-G240-A   I228 @TIMECARD_LIB.TIMECARD(SCH_1):PAGE162
  R400    1      1 RESISTOR-G155-11000-01,100OHM,A   I177 @TIMECARD_LIB.TIMECARD(SCH_1):PAGE14

FPGA_OUT_SMA4_LED_GREEN_N @TIMECARD_LIB.TIMECARD(SCH_1):FPGA_OUT_SMA4_LED_GREEN_N
   U24  D19 IO_L14N_T2_SRCC_16 XC7A200T_2FBG484C_FBG484-G240-A   I228 @TIMECARD_LIB.TIMECARD(SCH_1):PAGE162
  R401    1      1 RESISTOR-G155-11000-01,100OHM,A   I176 @TIMECARD_LIB.TIMECARD(SCH_1):PAGE14

FPGA_OUT_SMA4_LED_RED_N @TIMECARD_LIB.TIMECARD(SCH_1):FPGA_OUT_SMA4_LED_RED_N
   U24  F18 IO_L15P_T2_DQS_16 XC7A200T_2FBG484C_FBG484-G240-A   I228 @TIMECARD_LIB.TIMECARD(SCH_1):PAGE162
  R424    1      1 RESISTOR-G155-11000-01,100OHM,A   I186 @TIMECARD_LIB.TIMECARD(SCH_1):PAGE14

FPGA_OUT_SN_EEPROM_WP @TIMECARD_LIB.TIMECARD(SCH_1):FPGA_OUT_SN_EEPROM_WP
   U24 AA13 IO_L3P_T0_DQS_13 XC7A200T_2FBG484C_FBG484-G240-A     I2 @TIMECARD_LIB.TIMECARD(SCH_1):PAGE161
    R1    1      1 RESISTOR-G155-13300-01,330OHM,A   I130 @TIMECARD_LIB.TIMECARD(SCH_1):PAGE5

FPGA_PCA9546_I2C_SCL @TIMECARD_LIB.TIMECARD(SCH_1):FPGA_PCA9546_I2C_SCL
   U24  N17 IO_L21P_T3_DQS_14 XC7A200T_2FBG484C_FBG484-G240-A     I2 @TIMECARD_LIB.TIMECARD(SCH_1):PAGE161
   U37    5    NC2 TS3A5018PWR_TSSOP16-G220-10324A   I448 @TIMECARD_LIB.TIMECARD(SCH_1):PAGE524
  R475    2      2 RESISTOR-G155-11003-01,100KOHMA   I467 @TIMECARD_LIB.TIMECARD(SCH_1):PAGE524

FPGA_PCA9546_I2C_SDA @TIMECARD_LIB.TIMECARD(SCH_1):FPGA_PCA9546_I2C_SDA
   U24  T16 IO_L17P_T2_13 XC7A200T_2FBG484C_FBG484-G240-A     I2 @TIMECARD_LIB.TIMECARD(SCH_1):PAGE161
   U37    2    NC1 TS3A5018PWR_TSSOP16-G220-10324A   I448 @TIMECARD_LIB.TIMECARD(SCH_1):PAGE524
  R474    2      2 RESISTOR-G155-11003-01,100KOHMA   I466 @TIMECARD_LIB.TIMECARD(SCH_1):PAGE524

FPGA_PROGRAM_N @TIMECARD_LIB.TIMECARD(SCH_1):FPGA_PROGRAM_N
   U24  N12 PROGRAM_0* XC7A200T_2FBG484C_FBG484-G240-A   I232 @TIMECARD_LIB.TIMECARD(SCH_1):PAGE127
  R193    2      2 RESISTOR-G155-14701-01,4.7KOHMA   I330 @TIMECARD_LIB.TIMECARD(SCH_1):PAGE127
  R356    2      2 RESISTOR-G155-100R0-J0,0OHM,-   I122 @TIMECARD_LIB.TIMECARD(SCH_1):PAGE3
  TP45    1      1 TP_PIONT-TP010CT020B030_PTH-TPA  I1690 @TIMECARD_LIB.TIMECARD(SCH_1):PAGE16

FPGA_TCK @TIMECARD_LIB.TIMECARD(SCH_1):FPGA_TCK
   R28    2      2 RESISTOR-G155-100R0-J0,0OHM,-    I54 @TIMECARD_LIB.TIMECARD(SCH_1):PAGE3
   U24  V12  TCK_0 XC7A200T_2FBG484C_FBG484-G240-A   I232 @TIMECARD_LIB.TIMECARD(SCH_1):PAGE127
  R134    2      2 RESISTOR-G155-133R0-01,33OHM,1%   I436 @TIMECARD_LIB.TIMECARD(SCH_1):PAGE127
  R402    1      1 RESISTOR-G155-12201-01,2.2KOHMA   I440 @TIMECARD_LIB.TIMECARD(SCH_1):PAGE127

FPGA_TDI @TIMECARD_LIB.TIMECARD(SCH_1):FPGA_TDI
   R41    2      2 RESISTOR-G155-100R0-J0,0OHM,-    I53 @TIMECARD_LIB.TIMECARD(SCH_1):PAGE3
   U24  R13  TDI_0 XC7A200T_2FBG484C_FBG484-G240-A   I232 @TIMECARD_LIB.TIMECARD(SCH_1):PAGE127
  R405    2      2 RESISTOR-G155-11002-01,10KOHM,A   I432 @TIMECARD_LIB.TIMECARD(SCH_1):PAGE127
  R137    2      2 RESISTOR-G155-133R0-01,33OHM,1%   I439 @TIMECARD_LIB.TIMECARD(SCH_1):PAGE127

FPGA_TDO @TIMECARD_LIB.TIMECARD(SCH_1):FPGA_TDO
   R42    2      2 RESISTOR-G155-100R0-J0,0OHM,-    I52 @TIMECARD_LIB.TIMECARD(SCH_1):PAGE3
  R195    1      1 RESISTOR-G155-133R0-01,33OHM,1%   I331 @TIMECARD_LIB.TIMECARD(SCH_1):PAGE127
  R403    2      2 RESISTOR-G155-11002-01,10KOHM,A   I435 @TIMECARD_LIB.TIMECARD(SCH_1):PAGE127
  R135    2      2 RESISTOR-G155-100R0-J0,0OHM,-   I438 @TIMECARD_LIB.TIMECARD(SCH_1):PAGE127

FPGA_TMS @TIMECARD_LIB.TIMECARD(SCH_1):FPGA_TMS
   R43    2      2 RESISTOR-G155-100R0-J0,0OHM,-    I51 @TIMECARD_LIB.TIMECARD(SCH_1):PAGE3
   U24  T13  TMS_0 XC7A200T_2FBG484C_FBG484-G240-A   I232 @TIMECARD_LIB.TIMECARD(SCH_1):PAGE127
  R404    2      2 RESISTOR-G155-11002-01,10KOHM,A   I434 @TIMECARD_LIB.TIMECARD(SCH_1):PAGE127
  R136    2      2 RESISTOR-G155-133R0-01,33OHM,1%   I437 @TIMECARD_LIB.TIMECARD(SCH_1):PAGE127

FPGA_USR_LED0 @TIMECARD_LIB.TIMECARD(SCH_1):FPGA_USR_LED0
   U24  A14 IO_L10N_T1_16 XC7A200T_2FBG484C_FBG484-G240-A   I228 @TIMECARD_LIB.TIMECARD(SCH_1):PAGE162
  DS11    C      C OPTICAL-G170-10143-01   I139 @TIMECARD_LIB.TIMECARD(SCH_1):PAGE14

FPGA_USR_LED1 @TIMECARD_LIB.TIMECARD(SCH_1):FPGA_USR_LED1
   U24  A13 IO_L10P_T1_16 XC7A200T_2FBG484C_FBG484-G240-A   I228 @TIMECARD_LIB.TIMECARD(SCH_1):PAGE162
  DS10    C      C OPTICAL-G170-10143-01   I138 @TIMECARD_LIB.TIMECARD(SCH_1):PAGE14

FT4232_CHD_RX @TIMECARD_LIB.TIMECARD(SCH_1):FT4232_CHD_RX
   J10    5      5 G200_10283_01-G200-10283-01   I173 @TIMECARD_LIB.TIMECARD(SCH_1):PAGE524
   J10    7      7 G200_10283_01-G200-10283-01   I173 @TIMECARD_LIB.TIMECARD(SCH_1):PAGE524
  R132    2      2 RESISTOR-G155-11000-01,100OHM,A   I188 @TIMECARD_LIB.TIMECARD(SCH_1):PAGE524

FT4232_CHD_TX @TIMECARD_LIB.TIMECARD(SCH_1):FT4232_CHD_TX
   J10    1      1 G200_10283_01-G200-10283-01   I173 @TIMECARD_LIB.TIMECARD(SCH_1):PAGE524
   J10    3      3 G200_10283_01-G200-10283-01   I173 @TIMECARD_LIB.TIMECARD(SCH_1):PAGE524
  R131    2      2 RESISTOR-G155-11000-01,100OHM,A   I187 @TIMECARD_LIB.TIMECARD(SCH_1):PAGE524

FT4232_FPGA_TCK @TIMECARD_LIB.TIMECARD(SCH_1):FT4232_FPGA_TCK
   J14    1      1 G200_10283_01-G200-10283-01   I427 @TIMECARD_LIB.TIMECARD(SCH_1):PAGE127
  R134    1      1 RESISTOR-G155-133R0-01,33OHM,1%   I436 @TIMECARD_LIB.TIMECARD(SCH_1):PAGE127
   CR7    2    IO1 DIODE_4_V1-G122-10123-01   I442 @TIMECARD_LIB.TIMECARD(SCH_1):PAGE127
   U30    2    NC1 TS3A5018PWR_TSSOP16-G220-10324A   I425 @TIMECARD_LIB.TIMECARD(SCH_1):PAGE524

FT4232_FPGA_TDI @TIMECARD_LIB.TIMECARD(SCH_1):FT4232_FPGA_TDI
   J14    9      9 G200_10283_01-G200-10283-01   I427 @TIMECARD_LIB.TIMECARD(SCH_1):PAGE127
  R137    1      1 RESISTOR-G155-133R0-01,33OHM,1%   I439 @TIMECARD_LIB.TIMECARD(SCH_1):PAGE127
   CR6    3    IO2 DIODE_4_V1-G122-10123-01   I443 @TIMECARD_LIB.TIMECARD(SCH_1):PAGE127
   U30    5    NC2 TS3A5018PWR_TSSOP16-G220-10324A   I425 @TIMECARD_LIB.TIMECARD(SCH_1):PAGE524

FT4232_FPGA_TDO @TIMECARD_LIB.TIMECARD(SCH_1):FT4232_FPGA_TDO
   J14    3      3 G200_10283_01-G200-10283-01   I427 @TIMECARD_LIB.TIMECARD(SCH_1):PAGE127
  R135    1      1 RESISTOR-G155-100R0-J0,0OHM,-   I438 @TIMECARD_LIB.TIMECARD(SCH_1):PAGE127
   CR7    3    IO2 DIODE_4_V1-G122-10123-01   I442 @TIMECARD_LIB.TIMECARD(SCH_1):PAGE127
   U30   11    NC3 TS3A5018PWR_TSSOP16-G220-10324A   I425 @TIMECARD_LIB.TIMECARD(SCH_1):PAGE524

FT4232_FPGA_TMS @TIMECARD_LIB.TIMECARD(SCH_1):FT4232_FPGA_TMS
   J14    5      5 G200_10283_01-G200-10283-01   I427 @TIMECARD_LIB.TIMECARD(SCH_1):PAGE127
  R136    1      1 RESISTOR-G155-133R0-01,33OHM,1%   I437 @TIMECARD_LIB.TIMECARD(SCH_1):PAGE127
   CR6    2    IO1 DIODE_4_V1-G122-10123-01   I443 @TIMECARD_LIB.TIMECARD(SCH_1):PAGE127
   U30   14    NC4 TS3A5018PWR_TSSOP16-G220-10324A   I425 @TIMECARD_LIB.TIMECARD(SCH_1):PAGE524

FT4232_I2C_SCL @TIMECARD_LIB.TIMECARD(SCH_1):FT4232_I2C_SCL
  R471    2      2 RESISTOR-G155-100R0-J0,0OHM,-   I169 @TIMECARD_LIB.TIMECARD(SCH_1):PAGE524
  R478    1      1 RESISTOR-G155-11003-01,100KOHMA   I190 @TIMECARD_LIB.TIMECARD(SCH_1):PAGE524
   U37    6    NO2 TS3A5018PWR_TSSOP16-G220-10324A   I448 @TIMECARD_LIB.TIMECARD(SCH_1):PAGE524
   U37   13    NO4 TS3A5018PWR_TSSOP16-G220-10324A   I448 @TIMECARD_LIB.TIMECARD(SCH_1):PAGE524

FT4232_I2C_SDA @TIMECARD_LIB.TIMECARD(SCH_1):FT4232_I2C_SDA
  R472    2      2 RESISTOR-G155-100R0-J0,0OHM,-   I166 @TIMECARD_LIB.TIMECARD(SCH_1):PAGE524
  R473    2      2 RESISTOR-G155-100R0-J0,0OHM,-   I170 @TIMECARD_LIB.TIMECARD(SCH_1):PAGE524
  R479    1      1 RESISTOR-G155-11003-01,100KOHMA   I191 @TIMECARD_LIB.TIMECARD(SCH_1):PAGE524
   U37    3    NO1 TS3A5018PWR_TSSOP16-G220-10324A   I448 @TIMECARD_LIB.TIMECARD(SCH_1):PAGE524
   U37   10    NO3 TS3A5018PWR_TSSOP16-G220-10324A   I448 @TIMECARD_LIB.TIMECARD(SCH_1):PAGE524

FT4232_MUX1_SEL @TIMECARD_LIB.TIMECARD(SCH_1):FT4232_MUX1_SEL
   U18   21 ADBUS4 FT4232HL_REEL_QFP64-G223-10282A    I64 @TIMECARD_LIB.TIMECARD(SCH_1):PAGE524
  R449    2      2 RESISTOR-G155-133R0-01,33OHM,1%   I424 @TIMECARD_LIB.TIMECARD(SCH_1):PAGE524

FT4232_MUX2_SEL @TIMECARD_LIB.TIMECARD(SCH_1):FT4232_MUX2_SEL
   U18   22 ADBUS5 FT4232HL_REEL_QFP64-G223-10282A    I64 @TIMECARD_LIB.TIMECARD(SCH_1):PAGE524
  R462    1      1 RESISTOR-G155-133R0-01,33OHM,1%   I412 @TIMECARD_LIB.TIMECARD(SCH_1):PAGE524

FT4232_MUX3_SEL @TIMECARD_LIB.TIMECARD(SCH_1):FT4232_MUX3_SEL
   U18   23 ADBUS6 FT4232HL_REEL_QFP64-G223-10282A    I64 @TIMECARD_LIB.TIMECARD(SCH_1):PAGE524
  R486    1      1 RESISTOR-G155-133R0-01,33OHM,1%   I460 @TIMECARD_LIB.TIMECARD(SCH_1):PAGE524

FT4232_SPI_CLK @TIMECARD_LIB.TIMECARD(SCH_1):FT4232_SPI_CLK
   U38    3    NO1 TS3A5018PWR_TSSOP16-G220-10324A   I400 @TIMECARD_LIB.TIMECARD(SCH_1):PAGE524
   U30    3    NO1 TS3A5018PWR_TSSOP16-G220-10324A   I425 @TIMECARD_LIB.TIMECARD(SCH_1):PAGE524

FT4232_SPI_CS_N @TIMECARD_LIB.TIMECARD(SCH_1):FT4232_SPI_CS_N
   U38   13    NO4 TS3A5018PWR_TSSOP16-G220-10324A   I400 @TIMECARD_LIB.TIMECARD(SCH_1):PAGE524
   U30   13    NO4 TS3A5018PWR_TSSOP16-G220-10324A   I425 @TIMECARD_LIB.TIMECARD(SCH_1):PAGE524

FT4232_SPI_MISO @TIMECARD_LIB.TIMECARD(SCH_1):FT4232_SPI_MISO
   U38   10    NO3 TS3A5018PWR_TSSOP16-G220-10324A   I400 @TIMECARD_LIB.TIMECARD(SCH_1):PAGE524
   U30   10    NO3 TS3A5018PWR_TSSOP16-G220-10324A   I425 @TIMECARD_LIB.TIMECARD(SCH_1):PAGE524

FT4232_SPI_MOSI @TIMECARD_LIB.TIMECARD(SCH_1):FT4232_SPI_MOSI
   U38    6    NO2 TS3A5018PWR_TSSOP16-G220-10324A   I400 @TIMECARD_LIB.TIMECARD(SCH_1):PAGE524
   U30    6    NO2 TS3A5018PWR_TSSOP16-G220-10324A   I425 @TIMECARD_LIB.TIMECARD(SCH_1):PAGE524

FT4232_TCK_SCLK @TIMECARD_LIB.TIMECARD(SCH_1):FT4232_TCK_SCLK
  R467    2      2 RESISTOR-G155-133R0-01,33OHM,1%   I141 @TIMECARD_LIB.TIMECARD(SCH_1):PAGE524
   U30    4   COM1 TS3A5018PWR_TSSOP16-G220-10324A   I425 @TIMECARD_LIB.TIMECARD(SCH_1):PAGE524

FT4232_TDI_MOSI @TIMECARD_LIB.TIMECARD(SCH_1):FT4232_TDI_MOSI
  R468    2      2 RESISTOR-G155-133R0-01,33OHM,1%   I140 @TIMECARD_LIB.TIMECARD(SCH_1):PAGE524
   U30    7   COM2 TS3A5018PWR_TSSOP16-G220-10324A   I425 @TIMECARD_LIB.TIMECARD(SCH_1):PAGE524

FT4232_TDO_MISO @TIMECARD_LIB.TIMECARD(SCH_1):FT4232_TDO_MISO
  R469    2      2 RESISTOR-G155-133R0-01,33OHM,1%   I142 @TIMECARD_LIB.TIMECARD(SCH_1):PAGE524
   U30    9   COM3 TS3A5018PWR_TSSOP16-G220-10324A   I425 @TIMECARD_LIB.TIMECARD(SCH_1):PAGE524

FT4232_TMS_SPICS_N @TIMECARD_LIB.TIMECARD(SCH_1):FT4232_TMS_SPICS_N
  R470    2      2 RESISTOR-G155-133R0-01,33OHM,1%   I139 @TIMECARD_LIB.TIMECARD(SCH_1):PAGE524
   U30   12   COM4 TS3A5018PWR_TSSOP16-G220-10324A   I425 @TIMECARD_LIB.TIMECARD(SCH_1):PAGE524

FT4232_VREGOUT @TIMECARD_LIB.TIMECARD(SCH_1):FT4232_VREGOUT
   U18   64 VCORE_1 FT4232HL_REEL_QFP64-G223-10282A    I64 @TIMECARD_LIB.TIMECARD(SCH_1):PAGE524
   U18   37 VCORE_2 FT4232HL_REEL_QFP64-G223-10282A    I64 @TIMECARD_LIB.TIMECARD(SCH_1):PAGE524
   U18   12 VCORE_3 FT4232HL_REEL_QFP64-G223-10282A    I64 @TIMECARD_LIB.TIMECARD(SCH_1):PAGE524
   U18   49 VREGOUT FT4232HL_REEL_QFP64-G223-10282A    I64 @TIMECARD_LIB.TIMECARD(SCH_1):PAGE524
   C90    1      1 CAPACITOR-G105-0F475-BM,4.7UF,A   I123 @TIMECARD_LIB.TIMECARD(SCH_1):PAGE524
   C96    1      1 CAPACITOR-G105-0B104-EK,0.1UF,A   I376 @TIMECARD_LIB.TIMECARD(SCH_1):PAGE524

FTDI_EE_CLK @TIMECARD_LIB.TIMECARD(SCH_1):FTDI_EE_CLK
   U18   62  EECLK FT4232HL_REEL_QFP64-G223-10282A    I64 @TIMECARD_LIB.TIMECARD(SCH_1):PAGE524
   U31    2     SK CAT93C46VI_GT3_SOIC8-G221-1007A   I200 @TIMECARD_LIB.TIMECARD(SCH_1):PAGE524
  R447    2      2 RESISTOR-G155-11002-01,10KOHM,A   I206 @TIMECARD_LIB.TIMECARD(SCH_1):PAGE524

FTDI_EE_CS @TIMECARD_LIB.TIMECARD(SCH_1):FTDI_EE_CS
   U18   63   EECS FT4232HL_REEL_QFP64-G223-10282A    I64 @TIMECARD_LIB.TIMECARD(SCH_1):PAGE524
   U31    1     CS CAT93C46VI_GT3_SOIC8-G221-1007A   I200 @TIMECARD_LIB.TIMECARD(SCH_1):PAGE524
  R446    2      2 RESISTOR-G155-11002-01,10KOHM,A   I207 @TIMECARD_LIB.TIMECARD(SCH_1):PAGE524

FTDI_EE_DAT @TIMECARD_LIB.TIMECARD(SCH_1):FTDI_EE_DAT
   U18   61 EEDATA FT4232HL_REEL_QFP64-G223-10282A    I64 @TIMECARD_LIB.TIMECARD(SCH_1):PAGE524
   U31    3     DI CAT93C46VI_GT3_SOIC8-G221-1007A   I200 @TIMECARD_LIB.TIMECARD(SCH_1):PAGE524
  R454    1      1 RESISTOR-G155-12201-01,2.2KOHMA   I310 @TIMECARD_LIB.TIMECARD(SCH_1):PAGE524

FTDI_EE_DO @TIMECARD_LIB.TIMECARD(SCH_1):FTDI_EE_DO
   U31    4     DO CAT93C46VI_GT3_SOIC8-G221-1007A   I200 @TIMECARD_LIB.TIMECARD(SCH_1):PAGE524
  R444    2      2 RESISTOR-G155-11002-01,10KOHM,A   I208 @TIMECARD_LIB.TIMECARD(SCH_1):PAGE524
  R454    2      2 RESISTOR-G155-12201-01,2.2KOHMA   I310 @TIMECARD_LIB.TIMECARD(SCH_1):PAGE524

FT_USB_DETECT @TIMECARD_LIB.TIMECARD(SCH_1):FT_USB_DETECT
  R130    1      1 RESISTOR-G155-11002-01,10KOHM,A    I23 @TIMECARD_LIB.TIMECARD(SCH_1):PAGE524
   R18    2      2 RESISTOR-G155-14701-01,4.7KOHMA    I27 @TIMECARD_LIB.TIMECARD(SCH_1):PAGE524
  R460    1      1 RESISTOR-G155-11001-01,1KOHM,1%   I121 @TIMECARD_LIB.TIMECARD(SCH_1):PAGE524
  R456    2      2 RESISTOR-G155-11000-01,100OHM,A   I368 @TIMECARD_LIB.TIMECARD(SCH_1):PAGE524
    Q1    1      G POWERMOS_3P_NCH_V1-G121-10200-A   I445 @TIMECARD_LIB.TIMECARD(SCH_1):PAGE524
  R443    1      1 RESISTOR-G155-11000-01,100OHM,A   I446 @TIMECARD_LIB.TIMECARD(SCH_1):PAGE524
  TP11    1      1 TP_PIONT-TP010CT020B030_PTH-TPA  I1626 @TIMECARD_LIB.TIMECARD(SCH_1):PAGE16

FT_USB_DM @TIMECARD_LIB.TIMECARD(SCH_1):FT_USB_DM
   U17    4      4 CL1001485A-G122-00019-01     I3 @TIMECARD_LIB.TIMECARD(SCH_1):PAGE524
  R128    1      1 RESISTOR-G155-100R0-J0,0OHM,-    I28 @TIMECARD_LIB.TIMECARD(SCH_1):PAGE524
   J13   A7   D1_N CONN_USB_14P_GH4_F_RA_TH-G200-A   I495 @TIMECARD_LIB.TIMECARD(SCH_1):PAGE524
   J13   B7   D2_N CONN_USB_14P_GH4_F_RA_TH-G200-A   I495 @TIMECARD_LIB.TIMECARD(SCH_1):PAGE524

FT_USB_DP @TIMECARD_LIB.TIMECARD(SCH_1):FT_USB_DP
   U17    6      6 CL1001485A-G122-00019-01     I3 @TIMECARD_LIB.TIMECARD(SCH_1):PAGE524
  R129    1      1 RESISTOR-G155-100R0-J0,0OHM,-    I26 @TIMECARD_LIB.TIMECARD(SCH_1):PAGE524
   J13   A6   D1_P CONN_USB_14P_GH4_F_RA_TH-G200-A   I495 @TIMECARD_LIB.TIMECARD(SCH_1):PAGE524
   J13   B6   D2_P CONN_USB_14P_GH4_F_RA_TH-G200-A   I495 @TIMECARD_LIB.TIMECARD(SCH_1):PAGE524

GPSTP1_OUT @TIMECARD_LIB.TIMECARD(SCH_1):GPSTP1_OUT
  R117    1      1 RESISTOR-G155-133R0-01,33OHM,1%    I20 @TIMECARD_LIB.TIMECARD(SCH_1):PAGE11
    P2    6      6 CONN_HDR_2X4_F_S_SMT-G200-1307A    I36 @TIMECARD_LIB.TIMECARD(SCH_1):PAGE11

GPSTP2_OUT @TIMECARD_LIB.TIMECARD(SCH_1):GPSTP2_OUT
  R111    2      2 RESISTOR-G155-133R0-01,33OHM,1%     I5 @TIMECARD_LIB.TIMECARD(SCH_1):PAGE11
    P2    7      7 CONN_HDR_2X4_F_S_SMT-G200-1307A    I36 @TIMECARD_LIB.TIMECARD(SCH_1):PAGE11

GPS_RST_N @TIMECARD_LIB.TIMECARD(SCH_1):GPS_RST_N
  R114    1      1 RESISTOR-G155-14701-01,4.7KOHMA    I18 @TIMECARD_LIB.TIMECARD(SCH_1):PAGE11
  R115    2      2 RESISTOR-G155-14701-01,4.7KOHMA    I21 @TIMECARD_LIB.TIMECARD(SCH_1):PAGE11
  R116    1      1 RESISTOR-G155-133R0-01,33OHM,1%    I25 @TIMECARD_LIB.TIMECARD(SCH_1):PAGE11
    P2    4      4 CONN_HDR_2X4_F_S_SMT-G200-1307A    I36 @TIMECARD_LIB.TIMECARD(SCH_1):PAGE11
  TP15    1      1 TP_PIONT-TP010CT020B030_PTH-TPA  I1630 @TIMECARD_LIB.TIMECARD(SCH_1):PAGE16

GPS_SMA_LED_BLUE_N @TIMECARD_LIB.TIMECARD(SCH_1):GPS_SMA_LED_BLUE_N
  R397    1      1 RESISTOR-G155-133R0-01,33OHM,1%   I156 @TIMECARD_LIB.TIMECARD(SCH_1):PAGE14
   U33   24  OUT15 IS32FL3207_QWLA3_TR_QFN29-A223A   I219 @TIMECARD_LIB.TIMECARD(SCH_1):PAGE14

GPS_SMA_LED_GREEN_N @TIMECARD_LIB.TIMECARD(SCH_1):GPS_SMA_LED_GREEN_N
  R398    1      1 RESISTOR-G155-133R0-01,33OHM,1%   I155 @TIMECARD_LIB.TIMECARD(SCH_1):PAGE14
   U33   22  OUT13 IS32FL3207_QWLA3_TR_QFN29-A223A   I219 @TIMECARD_LIB.TIMECARD(SCH_1):PAGE14

GPS_SMA_LED_RED_N @TIMECARD_LIB.TIMECARD(SCH_1):GPS_SMA_LED_RED_N
  R399    1      1 RESISTOR-G155-133R0-01,33OHM,1%   I157 @TIMECARD_LIB.TIMECARD(SCH_1):PAGE14
   U33   23  OUT14 IS32FL3207_QWLA3_TR_QFN29-A223A   I219 @TIMECARD_LIB.TIMECARD(SCH_1):PAGE14

GPS_UART_RXD @TIMECARD_LIB.TIMECARD(SCH_1):GPS_UART_RXD
  R113    2      2 RESISTOR-G155-133R0-01,33OHM,1%     I7 @TIMECARD_LIB.TIMECARD(SCH_1):PAGE11
  R110    2      2 RESISTOR-G155-133R0-01,33OHM,1%    I29 @TIMECARD_LIB.TIMECARD(SCH_1):PAGE11
    P2    5      5 CONN_HDR_2X4_F_S_SMT-G200-1307A    I36 @TIMECARD_LIB.TIMECARD(SCH_1):PAGE11
  R268    2      2 RESISTOR-G155-11003-01,100KOHMA    I38 @TIMECARD_LIB.TIMECARD(SCH_1):PAGE11

GPS_UART_TXD @TIMECARD_LIB.TIMECARD(SCH_1):GPS_UART_TXD
  R112    2      2 RESISTOR-G155-133R0-01,33OHM,1%     I8 @TIMECARD_LIB.TIMECARD(SCH_1):PAGE11
  R109    2      2 RESISTOR-G155-133R0-01,33OHM,1%    I11 @TIMECARD_LIB.TIMECARD(SCH_1):PAGE11
    P2    3      3 CONN_HDR_2X4_F_S_SMT-G200-1307A    I36 @TIMECARD_LIB.TIMECARD(SCH_1):PAGE11

ICP10100_I2C_SCL @TIMECARD_LIB.TIMECARD(SCH_1):ICP10100_I2C_SCL
    U4   10    SC2 PCA9546APW_TSSOP16-G223-10280-A    I33 @TIMECARD_LIB.TIMECARD(SCH_1):PAGE5
   U32    7   SCLB PCA9508DP_TSSOP8-G223-10278-01    I51 @TIMECARD_LIB.TIMECARD(SCH_1):PAGE8
  R315    1      1 RESISTOR-G155-100R0-J0,0OHM,-    I63 @TIMECARD_LIB.TIMECARD(SCH_1):PAGE8
  R282    2      2 RESISTOR-G155-14701-01,4.7KOHMA    I69 @TIMECARD_LIB.TIMECARD(SCH_1):PAGE8

ICP10100_I2C_SDA @TIMECARD_LIB.TIMECARD(SCH_1):ICP10100_I2C_SDA
    U4    9    SD2 PCA9546APW_TSSOP16-G223-10280-A    I33 @TIMECARD_LIB.TIMECARD(SCH_1):PAGE5
   U32    6   SDAB PCA9508DP_TSSOP8-G223-10278-01    I51 @TIMECARD_LIB.TIMECARD(SCH_1):PAGE8
  R316    1      1 RESISTOR-G155-100R0-J0,0OHM,-    I64 @TIMECARD_LIB.TIMECARD(SCH_1):PAGE8
  R281    2      2 RESISTOR-G155-14701-01,4.7KOHMA    I70 @TIMECARD_LIB.TIMECARD(SCH_1):PAGE8

IO_L20N_16 @TIMECARD_LIB.TIMECARD(SCH_1):IO_L20N_16
   U24  B22 IO_L20N_T3_16 XC7A200T_2FBG484C_FBG484-G240-A   I228 @TIMECARD_LIB.TIMECARD(SCH_1):PAGE162
 TP180    1      1 TP_PIONT-TP010CT020B030_PTH-TPA  I1511 @TIMECARD_LIB.TIMECARD(SCH_1):PAGE16

IO_L20N_34 @TIMECARD_LIB.TIMECARD(SCH_1):IO_L20N_34
   U24  AB6 IO_L20N_T3_34 XC7A200T_2FBG484C_FBG484-G240-A     I1 @TIMECARD_LIB.TIMECARD(SCH_1):PAGE163
 TP133    1      1 TP_PIONT-TP010CT020B030_PTH-TPA  I1015 @TIMECARD_LIB.TIMECARD(SCH_1):PAGE16

IO_L20N_35 @TIMECARD_LIB.TIMECARD(SCH_1):IO_L20N_35
   U24   P1 IO_L20N_T3_35 XC7A200T_2FBG484C_FBG484-G240-A     I1 @TIMECARD_LIB.TIMECARD(SCH_1):PAGE163
 TP200    1      1 TP_PIONT-TP010CT020B030_PTH-TPA  I1528 @TIMECARD_LIB.TIMECARD(SCH_1):PAGE16

IO_L20P_16 @TIMECARD_LIB.TIMECARD(SCH_1):IO_L20P_16
   U24  C22 IO_L20P_T3_16 XC7A200T_2FBG484C_FBG484-G240-A   I228 @TIMECARD_LIB.TIMECARD(SCH_1):PAGE162
  TP78    1      1 TP_PIONT-TP010CT020B030_PTH-TPA  I1516 @TIMECARD_LIB.TIMECARD(SCH_1):PAGE16

IO_L20P_34 @TIMECARD_LIB.TIMECARD(SCH_1):IO_L20P_34
   U24  AB7 IO_L20P_T3_34 XC7A200T_2FBG484C_FBG484-G240-A     I1 @TIMECARD_LIB.TIMECARD(SCH_1):PAGE163
 TP132    1      1 TP_PIONT-TP010CT020B030_PTH-TPA  I1014 @TIMECARD_LIB.TIMECARD(SCH_1):PAGE16

IO_L20P_35 @TIMECARD_LIB.TIMECARD(SCH_1):IO_L20P_35
   U24   R1 IO_L20P_T3_35 XC7A200T_2FBG484C_FBG484-G240-A     I1 @TIMECARD_LIB.TIMECARD(SCH_1):PAGE163
 TP199    1      1 TP_PIONT-TP010CT020B030_PTH-TPA  I1527 @TIMECARD_LIB.TIMECARD(SCH_1):PAGE16

IO_L21N_16 @TIMECARD_LIB.TIMECARD(SCH_1):IO_L21N_16
   U24  A21 IO_L21N_T3_DQS_16 XC7A200T_2FBG484C_FBG484-G240-A   I228 @TIMECARD_LIB.TIMECARD(SCH_1):PAGE162
 TP182    1      1 TP_PIONT-TP010CT020B030_PTH-TPA  I1513 @TIMECARD_LIB.TIMECARD(SCH_1):PAGE16

IO_L21N_34 @TIMECARD_LIB.TIMECARD(SCH_1):IO_L21N_34
   U24   V8 IO_L21N_T3_DQS_34 XC7A200T_2FBG484C_FBG484-G240-A     I1 @TIMECARD_LIB.TIMECARD(SCH_1):PAGE163
 TP135    1      1 TP_PIONT-TP010CT020B030_PTH-TPA  I1017 @TIMECARD_LIB.TIMECARD(SCH_1):PAGE16

IO_L21N_35 @TIMECARD_LIB.TIMECARD(SCH_1):IO_L21N_35
   U24   P4 IO_L21N_T3_DQS_35 XC7A200T_2FBG484C_FBG484-G240-A     I1 @TIMECARD_LIB.TIMECARD(SCH_1):PAGE163
 TP194    1      1 TP_PIONT-TP010CT020B030_PTH-TPA  I1488 @TIMECARD_LIB.TIMECARD(SCH_1):PAGE16

IO_L21P_16 @TIMECARD_LIB.TIMECARD(SCH_1):IO_L21P_16
   U24  B21 IO_L21P_T3_DQS_16 XC7A200T_2FBG484C_FBG484-G240-A   I228 @TIMECARD_LIB.TIMECARD(SCH_1):PAGE162
 TP181    1      1 TP_PIONT-TP010CT020B030_PTH-TPA  I1512 @TIMECARD_LIB.TIMECARD(SCH_1):PAGE16

IO_L21P_34 @TIMECARD_LIB.TIMECARD(SCH_1):IO_L21P_34
   U24   V9 IO_L21P_T3_DQS_34 XC7A200T_2FBG484C_FBG484-G240-A     I1 @TIMECARD_LIB.TIMECARD(SCH_1):PAGE163
 TP134    1      1 TP_PIONT-TP010CT020B030_PTH-TPA  I1016 @TIMECARD_LIB.TIMECARD(SCH_1):PAGE16

IO_L21P_35 @TIMECARD_LIB.TIMECARD(SCH_1):IO_L21P_35
   U24   P5 IO_L21P_T3_DQS_35 XC7A200T_2FBG484C_FBG484-G240-A     I1 @TIMECARD_LIB.TIMECARD(SCH_1):PAGE163
 TP193    1      1 TP_PIONT-TP010CT020B030_PTH-TPA  I1487 @TIMECARD_LIB.TIMECARD(SCH_1):PAGE16

IO_L22N_16 @TIMECARD_LIB.TIMECARD(SCH_1):IO_L22N_16
   U24  D22 IO_L22N_T3_16 XC7A200T_2FBG484C_FBG484-G240-A   I228 @TIMECARD_LIB.TIMECARD(SCH_1):PAGE162
 TP184    1      1 TP_PIONT-TP010CT020B030_PTH-TPA  I1506 @TIMECARD_LIB.TIMECARD(SCH_1):PAGE16

IO_L22N_34 @TIMECARD_LIB.TIMECARD(SCH_1):IO_L22N_34
   U24  AB8 IO_L22N_T3_34 XC7A200T_2FBG484C_FBG484-G240-A     I1 @TIMECARD_LIB.TIMECARD(SCH_1):PAGE163
 TP137    1      1 TP_PIONT-TP010CT020B030_PTH-TPA  I1019 @TIMECARD_LIB.TIMECARD(SCH_1):PAGE16

IO_L22N_35 @TIMECARD_LIB.TIMECARD(SCH_1):IO_L22N_35
   U24   N2 IO_L22N_T3_35 XC7A200T_2FBG484C_FBG484-G240-A     I1 @TIMECARD_LIB.TIMECARD(SCH_1):PAGE163
 TP202    1      1 TP_PIONT-TP010CT020B030_PTH-TPA  I1530 @TIMECARD_LIB.TIMECARD(SCH_1):PAGE16

IO_L22P_16 @TIMECARD_LIB.TIMECARD(SCH_1):IO_L22P_16
   U24  E22 IO_L22P_T3_16 XC7A200T_2FBG484C_FBG484-G240-A   I228 @TIMECARD_LIB.TIMECARD(SCH_1):PAGE162
 TP183    1      1 TP_PIONT-TP010CT020B030_PTH-TPA  I1505 @TIMECARD_LIB.TIMECARD(SCH_1):PAGE16

IO_L22P_34 @TIMECARD_LIB.TIMECARD(SCH_1):IO_L22P_34
   U24  AA8 IO_L22P_T3_34 XC7A200T_2FBG484C_FBG484-G240-A     I1 @TIMECARD_LIB.TIMECARD(SCH_1):PAGE163
 TP136    1      1 TP_PIONT-TP010CT020B030_PTH-TPA  I1018 @TIMECARD_LIB.TIMECARD(SCH_1):PAGE16

IO_L22P_35 @TIMECARD_LIB.TIMECARD(SCH_1):IO_L22P_35
   U24   P2 IO_L22P_T3_35 XC7A200T_2FBG484C_FBG484-G240-A     I1 @TIMECARD_LIB.TIMECARD(SCH_1):PAGE163
 TP201    1      1 TP_PIONT-TP010CT020B030_PTH-TPA  I1529 @TIMECARD_LIB.TIMECARD(SCH_1):PAGE16

IO_L23N_16 @TIMECARD_LIB.TIMECARD(SCH_1):IO_L23N_16
   U24  D21 IO_L23N_T3_16 XC7A200T_2FBG484C_FBG484-G240-A   I228 @TIMECARD_LIB.TIMECARD(SCH_1):PAGE162
 TP186    1      1 TP_PIONT-TP010CT020B030_PTH-TPA  I1508 @TIMECARD_LIB.TIMECARD(SCH_1):PAGE16

IO_L23N_34 @TIMECARD_LIB.TIMECARD(SCH_1):IO_L23N_34
   U24   Y7 IO_L23N_T3_34 XC7A200T_2FBG484C_FBG484-G240-A     I1 @TIMECARD_LIB.TIMECARD(SCH_1):PAGE163
 TP139    1      1 TP_PIONT-TP010CT020B030_PTH-TPA  I1021 @TIMECARD_LIB.TIMECARD(SCH_1):PAGE16

IO_L23N_35 @TIMECARD_LIB.TIMECARD(SCH_1):IO_L23N_35
   U24   M5 IO_L23N_T3_35 XC7A200T_2FBG484C_FBG484-G240-A     I1 @TIMECARD_LIB.TIMECARD(SCH_1):PAGE163
 TP196    1      1 TP_PIONT-TP010CT020B030_PTH-TPA  I1490 @TIMECARD_LIB.TIMECARD(SCH_1):PAGE16

IO_L23P_16 @TIMECARD_LIB.TIMECARD(SCH_1):IO_L23P_16
   U24  E21 IO_L23P_T3_16 XC7A200T_2FBG484C_FBG484-G240-A   I228 @TIMECARD_LIB.TIMECARD(SCH_1):PAGE162
 TP185    1      1 TP_PIONT-TP010CT020B030_PTH-TPA  I1507 @TIMECARD_LIB.TIMECARD(SCH_1):PAGE16

IO_L23P_34 @TIMECARD_LIB.TIMECARD(SCH_1):IO_L23P_34
   U24   Y8 IO_L23P_T3_34 XC7A200T_2FBG484C_FBG484-G240-A     I1 @TIMECARD_LIB.TIMECARD(SCH_1):PAGE163
 TP138    1      1 TP_PIONT-TP010CT020B030_PTH-TPA  I1020 @TIMECARD_LIB.TIMECARD(SCH_1):PAGE16

IO_L23P_35 @TIMECARD_LIB.TIMECARD(SCH_1):IO_L23P_35
   U24   M6 IO_L23P_T3_35 XC7A200T_2FBG484C_FBG484-G240-A     I1 @TIMECARD_LIB.TIMECARD(SCH_1):PAGE163
 TP195    1      1 TP_PIONT-TP010CT020B030_PTH-TPA  I1489 @TIMECARD_LIB.TIMECARD(SCH_1):PAGE16

IO_L24N_16 @TIMECARD_LIB.TIMECARD(SCH_1):IO_L24N_16
   U24  G22 IO_L24N_T3_16 XC7A200T_2FBG484C_FBG484-G240-A   I228 @TIMECARD_LIB.TIMECARD(SCH_1):PAGE162
 TP188    1      1 TP_PIONT-TP010CT020B030_PTH-TPA  I1510 @TIMECARD_LIB.TIMECARD(SCH_1):PAGE16

IO_L24N_34 @TIMECARD_LIB.TIMECARD(SCH_1):IO_L24N_34
   U24   Y9 IO_L24N_T3_34 XC7A200T_2FBG484C_FBG484-G240-A     I1 @TIMECARD_LIB.TIMECARD(SCH_1):PAGE163
 TP141    1      1 TP_PIONT-TP010CT020B030_PTH-TPA  I1023 @TIMECARD_LIB.TIMECARD(SCH_1):PAGE16

IO_L24N_35 @TIMECARD_LIB.TIMECARD(SCH_1):IO_L24N_35
   U24   N5 IO_L24N_T3_35 XC7A200T_2FBG484C_FBG484-G240-A     I1 @TIMECARD_LIB.TIMECARD(SCH_1):PAGE163
 TP204    1      1 TP_PIONT-TP010CT020B030_PTH-TPA  I1524 @TIMECARD_LIB.TIMECARD(SCH_1):PAGE16

IO_L24P_16 @TIMECARD_LIB.TIMECARD(SCH_1):IO_L24P_16
   U24  G21 IO_L24P_T3_16 XC7A200T_2FBG484C_FBG484-G240-A   I228 @TIMECARD_LIB.TIMECARD(SCH_1):PAGE162
 TP187    1      1 TP_PIONT-TP010CT020B030_PTH-TPA  I1509 @TIMECARD_LIB.TIMECARD(SCH_1):PAGE16

IO_L24P_34 @TIMECARD_LIB.TIMECARD(SCH_1):IO_L24P_34
   U24   W9 IO_L24P_T3_34 XC7A200T_2FBG484C_FBG484-G240-A     I1 @TIMECARD_LIB.TIMECARD(SCH_1):PAGE163
 TP140    1      1 TP_PIONT-TP010CT020B030_PTH-TPA  I1022 @TIMECARD_LIB.TIMECARD(SCH_1):PAGE16

IO_L24P_35 @TIMECARD_LIB.TIMECARD(SCH_1):IO_L24P_35
   U24   P6 IO_L24P_T3_35 XC7A200T_2FBG484C_FBG484-G240-A     I1 @TIMECARD_LIB.TIMECARD(SCH_1):PAGE163
 TP203    1      1 TP_PIONT-TP010CT020B030_PTH-TPA  I1523 @TIMECARD_LIB.TIMECARD(SCH_1):PAGE16

LED_DATOUT0 @TIMECARD_LIB.TIMECARD(SCH_1):LED_DATOUT0
   U24  B13 IO_L8N_T1_16 XC7A200T_2FBG484C_FBG484-G240-A   I228 @TIMECARD_LIB.TIMECARD(SCH_1):PAGE162
   DS4    C      C OPTICAL-G170-10143-01   I137 @TIMECARD_LIB.TIMECARD(SCH_1):PAGE14

LED_DATOUT1 @TIMECARD_LIB.TIMECARD(SCH_1):LED_DATOUT1
   U24  C13 IO_L8P_T1_16 XC7A200T_2FBG484C_FBG484-G240-A   I228 @TIMECARD_LIB.TIMECARD(SCH_1):PAGE162
   DS3    C      C OPTICAL-G170-10143-01   I136 @TIMECARD_LIB.TIMECARD(SCH_1):PAGE14

LED_DATOUT2 @TIMECARD_LIB.TIMECARD(SCH_1):LED_DATOUT2
   DS2    C      C OPTICAL-G170-10143-01    I11 @TIMECARD_LIB.TIMECARD(SCH_1):PAGE14
   U24  D14 IO_L6P_T0_16 XC7A200T_2FBG484C_FBG484-G240-A   I228 @TIMECARD_LIB.TIMECARD(SCH_1):PAGE162

LED_DATOUT3 @TIMECARD_LIB.TIMECARD(SCH_1):LED_DATOUT3
   DS1    C      C OPTICAL-G170-10143-01    I12 @TIMECARD_LIB.TIMECARD(SCH_1):PAGE14
   U24  D15 IO_L6N_T0_VREF_16 XC7A200T_2FBG484C_FBG484-G240-A   I228 @TIMECARD_LIB.TIMECARD(SCH_1):PAGE162

LM75B_I2C_SCL @TIMECARD_LIB.TIMECARD(SCH_1):LM75B_I2C_SCL
    U4    5    SC0 PCA9546APW_TSSOP16-G223-10280-A    I33 @TIMECARD_LIB.TIMECARD(SCH_1):PAGE5
   R21    2      2 RESISTOR-G155-14701-01,4.7KOHMA    I16 @TIMECARD_LIB.TIMECARD(SCH_1):PAGE6
    U8    2    SCL LM75BDP_TSSOP8-G220-10215-01    I34 @TIMECARD_LIB.TIMECARD(SCH_1):PAGE6
   U35    2    SCL LM75BDP_TSSOP8-G220-10215-01    I59 @TIMECARD_LIB.TIMECARD(SCH_1):PAGE6
   U36    2    SCL LM75BDP_TSSOP8-G220-10215-01    I81 @TIMECARD_LIB.TIMECARD(SCH_1):PAGE6

LM75B_I2C_SDA @TIMECARD_LIB.TIMECARD(SCH_1):LM75B_I2C_SDA
    U4    4    SD0 PCA9546APW_TSSOP16-G223-10280-A    I33 @TIMECARD_LIB.TIMECARD(SCH_1):PAGE5
   R20    2      2 RESISTOR-G155-14701-01,4.7KOHMA    I14 @TIMECARD_LIB.TIMECARD(SCH_1):PAGE6
  R332    1      1 RESISTOR-G155-133R0-01,33OHM,1%    I15 @TIMECARD_LIB.TIMECARD(SCH_1):PAGE6
  R406    1      1 RESISTOR-G155-133R0-01,33OHM,1%    I76 @TIMECARD_LIB.TIMECARD(SCH_1):PAGE6
  R407    1      1 RESISTOR-G155-133R0-01,33OHM,1%   I100 @TIMECARD_LIB.TIMECARD(SCH_1):PAGE6

MAC_ALARM @TIMECARD_LIB.TIMECARD(SCH_1):MAC_ALARM
   R96    1      1 RESISTOR-G155-133R0-01,33OHM,1%    I23 @TIMECARD_LIB.TIMECARD(SCH_1):PAGE527
    P1   20     20 CONN_HDR_2X10_M_S_SMT-G200-130A   I193 @TIMECARD_LIB.TIMECARD(SCH_1):PAGE527
  TP51    1      1 TP_PIONT-TP010CT020B030_PTH-TPA  I1704 @TIMECARD_LIB.TIMECARD(SCH_1):PAGE16

MAC_USB_DM @TIMECARD_LIB.TIMECARD(SCH_1):MAC_USB_DM
   U24  R14 IO_L19N_T3_A09_D25_VREF_14 XC7A200T_2FBG484C_FBG484-G240-A     I2 @TIMECARD_LIB.TIMECARD(SCH_1):PAGE161
  R437    2      2 RESISTOR-G155-11502-01,15KOHM,A   I239 @TIMECARD_LIB.TIMECARD(SCH_1):PAGE161
   U11    4 USB1_N TS3USB3031RMGR_WQFN12-G220-103A   I108 @TIMECARD_LIB.TIMECARD(SCH_1):PAGE527
  R105    2      2 RESISTOR-G155-100R0-J0,0OHM,-   I123 @TIMECARD_LIB.TIMECARD(SCH_1):PAGE527

MAC_USB_DP @TIMECARD_LIB.TIMECARD(SCH_1):MAC_USB_DP
   U24  P14 IO_L19P_T3_A10_D26_14 XC7A200T_2FBG484C_FBG484-G240-A     I2 @TIMECARD_LIB.TIMECARD(SCH_1):PAGE161
  R436    2      2 RESISTOR-G155-11502-01,15KOHM,A   I240 @TIMECARD_LIB.TIMECARD(SCH_1):PAGE161
   U11    3 USB1_P TS3USB3031RMGR_WQFN12-G220-103A   I108 @TIMECARD_LIB.TIMECARD(SCH_1):PAGE527
  R106    2      2 RESISTOR-G155-100R0-J0,0OHM,-   I124 @TIMECARD_LIB.TIMECARD(SCH_1):PAGE527

MHZ125CLKN_CLKIN @TIMECARD_LIB.TIMECARD(SCH_1):MHZ125CLKN_CLKIN
   U24   E6 MGTREFCLK0N_216 XC7A200T_2FBG484C_FBG484-G240-A   I232 @TIMECARD_LIB.TIMECARD(SCH_1):PAGE127
  R197    2      2 RESISTOR-G155-11000-01,100OHM,A   I333 @TIMECARD_LIB.TIMECARD(SCH_1):PAGE127
  C254    2      2 CAPACITOR-G105-0B104-CK,0.1UF,A   I142 @TIMECARD_LIB.TIMECARD(SCH_1):PAGE522

MHZ125CLKP_CLKIN @TIMECARD_LIB.TIMECARD(SCH_1):MHZ125CLKP_CLKIN
   U24   F6 MGTREFCLK0P_216 XC7A200T_2FBG484C_FBG484-G240-A   I232 @TIMECARD_LIB.TIMECARD(SCH_1):PAGE127
  R197    1      1 RESISTOR-G155-11000-01,100OHM,A   I333 @TIMECARD_LIB.TIMECARD(SCH_1):PAGE127
  C253    2      2 CAPACITOR-G105-0B104-CK,0.1UF,A   I143 @TIMECARD_LIB.TIMECARD(SCH_1):PAGE522

MHZ200CLKN_CLKIN @TIMECARD_LIB.TIMECARD(SCH_1):MHZ200CLKN_CLKIN
   U24   T4 IO_L13N_T2_MRCC_34 XC7A200T_2FBG484C_FBG484-G240-A     I1 @TIMECARD_LIB.TIMECARD(SCH_1):PAGE163
  C252    2      2 CAPACITOR-G105-0B104-CK,0.1UF,A   I160 @TIMECARD_LIB.TIMECARD(SCH_1):PAGE522
  R278    2      2 RESISTOR-G155-11000-01,100OHM,A    I36 @TIMECARD_LIB.TIMECARD(SCH_1):PAGE163
  R355    1      1 RESISTOR-G155-11002-01,10KOHM,A   I120 @TIMECARD_LIB.TIMECARD(SCH_1):PAGE163
  R360    1      1 RESISTOR-G155-11002-01,10KOHM,A   I128 @TIMECARD_LIB.TIMECARD(SCH_1):PAGE163

MHZ200CLKP_CLKIN @TIMECARD_LIB.TIMECARD(SCH_1):MHZ200CLKP_CLKIN
   U24   R4 IO_L13P_T2_MRCC_34 XC7A200T_2FBG484C_FBG484-G240-A     I1 @TIMECARD_LIB.TIMECARD(SCH_1):PAGE163
  C251    2      2 CAPACITOR-G105-0B104-CK,0.1UF,A   I161 @TIMECARD_LIB.TIMECARD(SCH_1):PAGE522
  R278    1      1 RESISTOR-G155-11000-01,100OHM,A    I36 @TIMECARD_LIB.TIMECARD(SCH_1):PAGE163
  R358    1      1 RESISTOR-G155-11002-01,10KOHM,A   I126 @TIMECARD_LIB.TIMECARD(SCH_1):PAGE163
  R359    1      1 RESISTOR-G155-11002-01,10KOHM,A   I127 @TIMECARD_LIB.TIMECARD(SCH_1):PAGE163

MUX1_SEL @TIMECARD_LIB.TIMECARD(SCH_1):MUX1_SEL
  R448    1      1 RESISTOR-G155-133R0-01,33OHM,1%   I423 @TIMECARD_LIB.TIMECARD(SCH_1):PAGE524
  R449    1      1 RESISTOR-G155-133R0-01,33OHM,1%   I424 @TIMECARD_LIB.TIMECARD(SCH_1):PAGE524
   U30    1     IN TS3A5018PWR_TSSOP16-G220-10324A   I425 @TIMECARD_LIB.TIMECARD(SCH_1):PAGE524
  R450    1      1 RESISTOR-G155-14701-01,4.7KOHMA   I440 @TIMECARD_LIB.TIMECARD(SCH_1):PAGE524
  R451    1      1 RESISTOR-G155-11001-01,1KOHM,1%   I441 @TIMECARD_LIB.TIMECARD(SCH_1):PAGE524
  TP14    1      1 TP_PIONT-TP010CT020B030_PTH-TPA  I1629 @TIMECARD_LIB.TIMECARD(SCH_1):PAGE16

MUX2_SEL @TIMECARD_LIB.TIMECARD(SCH_1):MUX2_SEL
   U38    1     IN TS3A5018PWR_TSSOP16-G220-10324A   I400 @TIMECARD_LIB.TIMECARD(SCH_1):PAGE524
   U39    6 SELECT NLASB3157DFT2G_SC88-G223-10187A   I407 @TIMECARD_LIB.TIMECARD(SCH_1):PAGE524
   U40    6 SELECT NLASB3157DFT2G_SC88-G223-10187A   I408 @TIMECARD_LIB.TIMECARD(SCH_1):PAGE524
  R461    2      2 RESISTOR-G155-133R0-01,33OHM,1%   I411 @TIMECARD_LIB.TIMECARD(SCH_1):PAGE524
  R462    2      2 RESISTOR-G155-133R0-01,33OHM,1%   I412 @TIMECARD_LIB.TIMECARD(SCH_1):PAGE524
  R458    2      2 RESISTOR-G155-11001-01,1KOHM,1%   I430 @TIMECARD_LIB.TIMECARD(SCH_1):PAGE524
  R457    2      2 RESISTOR-G155-14701-01,4.7KOHMA   I431 @TIMECARD_LIB.TIMECARD(SCH_1):PAGE524
  TP13    1      1 TP_PIONT-TP010CT020B030_PTH-TPA  I1628 @TIMECARD_LIB.TIMECARD(SCH_1):PAGE16

MUX3_SEL @TIMECARD_LIB.TIMECARD(SCH_1):MUX3_SEL
   U37    1     IN TS3A5018PWR_TSSOP16-G220-10324A   I448 @TIMECARD_LIB.TIMECARD(SCH_1):PAGE524
  R485    2      2 RESISTOR-G155-133R0-01,33OHM,1%   I459 @TIMECARD_LIB.TIMECARD(SCH_1):PAGE524
  R486    2      2 RESISTOR-G155-133R0-01,33OHM,1%   I460 @TIMECARD_LIB.TIMECARD(SCH_1):PAGE524
  R483    2      2 RESISTOR-G155-11001-01,1KOHM,1%   I462 @TIMECARD_LIB.TIMECARD(SCH_1):PAGE524
  R482    2      2 RESISTOR-G155-14701-01,4.7KOHMA   I464 @TIMECARD_LIB.TIMECARD(SCH_1):PAGE524
  TP12    1      1 TP_PIONT-TP010CT020B030_PTH-TPA  I1627 @TIMECARD_LIB.TIMECARD(SCH_1):PAGE16

MUX_USB_DM @TIMECARD_LIB.TIMECARD(SCH_1):MUX_USB_DM
   U11   10    D_N TS3USB3031RMGR_WQFN12-G220-103A   I108 @TIMECARD_LIB.TIMECARD(SCH_1):PAGE527
  R105    1      1 RESISTOR-G155-100R0-J0,0OHM,-   I123 @TIMECARD_LIB.TIMECARD(SCH_1):PAGE527
   R98    2      2 RESISTOR-G155-100R0-J0,0OHM,-   I175 @TIMECARD_LIB.TIMECARD(SCH_1):PAGE527

MUX_USB_DP @TIMECARD_LIB.TIMECARD(SCH_1):MUX_USB_DP
   U11   11    D_P TS3USB3031RMGR_WQFN12-G220-103A   I108 @TIMECARD_LIB.TIMECARD(SCH_1):PAGE527
  R106    1      1 RESISTOR-G155-100R0-J0,0OHM,-   I124 @TIMECARD_LIB.TIMECARD(SCH_1):PAGE527
   R97    2      2 RESISTOR-G155-100R0-J0,0OHM,-   I176 @TIMECARD_LIB.TIMECARD(SCH_1):PAGE527

NC         NC
   GF1   B9  JTAG1 CONN_64P_GF-S_M_EF64_PCIE_P039A    I61 @TIMECARD_LIB.TIMECARD(SCH_1):PAGE3
   GF1  B12  RSVD1 CONN_64P_GF-S_M_EF64_PCIE_P039A    I61 @TIMECARD_LIB.TIMECARD(SCH_1):PAGE3
   GF1  A19  RSVD2 CONN_64P_GF-S_M_EF64_PCIE_P039A    I61 @TIMECARD_LIB.TIMECARD(SCH_1):PAGE3
   GF1  B30  RSVD3 CONN_64P_GF-S_M_EF64_PCIE_P039A    I61 @TIMECARD_LIB.TIMECARD(SCH_1):PAGE3
   GF1  A32  RSVD4 CONN_64P_GF-S_M_EF64_PCIE_P039A    I61 @TIMECARD_LIB.TIMECARD(SCH_1):PAGE3
   GF1  B11  WAKE* CONN_64P_GF-S_M_EF64_PCIE_P039A    I61 @TIMECARD_LIB.TIMECARD(SCH_1):PAGE3
   CR5    4    VDD DIODE_4_V1-G122-10123-01    I42 @TIMECARD_LIB.TIMECARD(SCH_1):PAGE12
    U2    5  READY G220_10198_01-G223-10197-01   I100 @TIMECARD_LIB.TIMECARD(SCH_1):PAGE3
   U20    8     NC ISL80101IRAJZ_DFN10-G222-10136A     I6 @TIMECARD_LIB.TIMECARD(SCH_1):PAGE68
   U21    8     NC ISL80101IRAJZ_DFN10-G222-10136A    I52 @TIMECARD_LIB.TIMECARD(SCH_1):PAGE68
   U24  Y17 IO_0_13 XC7A200T_2FBG484C_FBG484-G240-A     I2 @TIMECARD_LIB.TIMECARD(SCH_1):PAGE161
   U24 AA16 IO_L1N_T0_13 XC7A200T_2FBG484C_FBG484-G240-A     I2 @TIMECARD_LIB.TIMECARD(SCH_1):PAGE161
   U24  V22 IO_L3N_T0_DQS_EMCCLK_14 XC7A200T_2FBG484C_FBG484-G240-A     I2 @TIMECARD_LIB.TIMECARD(SCH_1):PAGE161
   U24 AB15 IO_L4N_T0_13 XC7A200T_2FBG484C_FBG484-G240-A     I2 @TIMECARD_LIB.TIMECARD(SCH_1):PAGE161
   U24  U21 IO_L4N_T0_D05_14 XC7A200T_2FBG484C_FBG484-G240-A     I2 @TIMECARD_LIB.TIMECARD(SCH_1):PAGE161
   U24  T21 IO_L4P_T0_D04_14 XC7A200T_2FBG484C_FBG484-G240-A     I2 @TIMECARD_LIB.TIMECARD(SCH_1):PAGE161
   U24 AA14 IO_L5N_T0_13 XC7A200T_2FBG484C_FBG484-G240-A     I2 @TIMECARD_LIB.TIMECARD(SCH_1):PAGE161
   U24  R19 IO_L5N_T0_D07_14 XC7A200T_2FBG484C_FBG484-G240-A     I2 @TIMECARD_LIB.TIMECARD(SCH_1):PAGE161
   U24  Y13 IO_L5P_T0_13 XC7A200T_2FBG484C_FBG484-G240-A     I2 @TIMECARD_LIB.TIMECARD(SCH_1):PAGE161
   U24  P19 IO_L5P_T0_D06_14 XC7A200T_2FBG484C_FBG484-G240-A     I2 @TIMECARD_LIB.TIMECARD(SCH_1):PAGE161
   U24  T20 IO_L6N_T0_D08_VREF_14 XC7A200T_2FBG484C_FBG484-G240-A     I2 @TIMECARD_LIB.TIMECARD(SCH_1):PAGE161
   U24 AB12 IO_L7N_T1_13 XC7A200T_2FBG484C_FBG484-G240-A     I2 @TIMECARD_LIB.TIMECARD(SCH_1):PAGE161
   U24  W22 IO_L7N_T1_D10_14 XC7A200T_2FBG484C_FBG484-G240-A     I2 @TIMECARD_LIB.TIMECARD(SCH_1):PAGE161
   U24 AB11 IO_L7P_T1_13 XC7A200T_2FBG484C_FBG484-G240-A     I2 @TIMECARD_LIB.TIMECARD(SCH_1):PAGE161
   U24  W21 IO_L7P_T1_D09_14 XC7A200T_2FBG484C_FBG484-G240-A     I2 @TIMECARD_LIB.TIMECARD(SCH_1):PAGE161
   U24 AA11 IO_L9N_T1_DQS_13 XC7A200T_2FBG484C_FBG484-G240-A     I2 @TIMECARD_LIB.TIMECARD(SCH_1):PAGE161
   U24  Y22 IO_L9N_T1_DQS_D13_14 XC7A200T_2FBG484C_FBG484-G240-A     I2 @TIMECARD_LIB.TIMECARD(SCH_1):PAGE161
   U24 AA10 IO_L9P_T1_DQS_13 XC7A200T_2FBG484C_FBG484-G240-A     I2 @TIMECARD_LIB.TIMECARD(SCH_1):PAGE161
   U24  Y21 IO_L9P_T1_DQS_14 XC7A200T_2FBG484C_FBG484-G240-A     I2 @TIMECARD_LIB.TIMECARD(SCH_1):PAGE161
   U24 AB22 IO_L10N_T1_D15_14 XC7A200T_2FBG484C_FBG484-G240-A     I2 @TIMECARD_LIB.TIMECARD(SCH_1):PAGE161
   U24 AB21 IO_L10P_T1_D14_14 XC7A200T_2FBG484C_FBG484-G240-A     I2 @TIMECARD_LIB.TIMECARD(SCH_1):PAGE161
   U24  V20 IO_L11N_T1_SRCC_14 XC7A200T_2FBG484C_FBG484-G240-A     I2 @TIMECARD_LIB.TIMECARD(SCH_1):PAGE161
   U24  U20 IO_L11P_T1_SRCC_14 XC7A200T_2FBG484C_FBG484-G240-A     I2 @TIMECARD_LIB.TIMECARD(SCH_1):PAGE161
   U24  V14 IO_L13N_T2_MRCC_13 XC7A200T_2FBG484C_FBG484-G240-A     I2 @TIMECARD_LIB.TIMECARD(SCH_1):PAGE161
   U24  Y19 IO_L13N_T2_MRCC_14 XC7A200T_2FBG484C_FBG484-G240-A     I2 @TIMECARD_LIB.TIMECARD(SCH_1):PAGE161
   U24  V19 IO_L14N_T2_SRCC_14 XC7A200T_2FBG484C_FBG484-G240-A     I2 @TIMECARD_LIB.TIMECARD(SCH_1):PAGE161
   U24  U15 IO_L14P_T2_SRCC_13 XC7A200T_2FBG484C_FBG484-G240-A     I2 @TIMECARD_LIB.TIMECARD(SCH_1):PAGE161
   U24  V18 IO_L14P_T2_SRCC_14 XC7A200T_2FBG484C_FBG484-G240-A     I2 @TIMECARD_LIB.TIMECARD(SCH_1):PAGE161
   U24  T15 IO_L15N_T2_DQS_13 XC7A200T_2FBG484C_FBG484-G240-A     I2 @TIMECARD_LIB.TIMECARD(SCH_1):PAGE161
   U24 AB20 IO_L15N_T2_DQS_DOUT_CSO_14* XC7A200T_2FBG484C_FBG484-G240-A     I2 @TIMECARD_LIB.TIMECARD(SCH_1):PAGE161
   U24  T14 IO_L15P_T2_DQS_13 XC7A200T_2FBG484C_FBG484-G240-A     I2 @TIMECARD_LIB.TIMECARD(SCH_1):PAGE161
   U24 AA19 IO_L15P_T2_DQS_RDWR_14* XC7A200T_2FBG484C_FBG484-G240-A     I2 @TIMECARD_LIB.TIMECARD(SCH_1):PAGE161
   U24  W16 IO_L16N_T2_13 XC7A200T_2FBG484C_FBG484-G240-A     I2 @TIMECARD_LIB.TIMECARD(SCH_1):PAGE161
   U24  W17 IO_L16N_T2_A15_D31_14 XC7A200T_2FBG484C_FBG484-G240-A     I2 @TIMECARD_LIB.TIMECARD(SCH_1):PAGE161
   U24  W15 IO_L16P_T2_13 XC7A200T_2FBG484C_FBG484-G240-A     I2 @TIMECARD_LIB.TIMECARD(SCH_1):PAGE161
   U24  V17 IO_L16P_T2_CSI_14* XC7A200T_2FBG484C_FBG484-G240-A     I2 @TIMECARD_LIB.TIMECARD(SCH_1):PAGE161
   U24  U18 IO_L18N_T2_A11_D27_14 XC7A200T_2FBG484C_FBG484-G240-A     I2 @TIMECARD_LIB.TIMECARD(SCH_1):PAGE161
   U24  U17 IO_L18P_T2_A12_D28_14 XC7A200T_2FBG484C_FBG484-G240-A     I2 @TIMECARD_LIB.TIMECARD(SCH_1):PAGE161
   U24  T18 IO_L20N_T3_A07_D23_14 XC7A200T_2FBG484C_FBG484-G240-A     I2 @TIMECARD_LIB.TIMECARD(SCH_1):PAGE161
   U24  R18 IO_L20P_T3_A08_D24_14 XC7A200T_2FBG484C_FBG484-G240-A     I2 @TIMECARD_LIB.TIMECARD(SCH_1):PAGE161
   U24  P17 IO_L21N_T3_DQS_A06_D22_14 XC7A200T_2FBG484C_FBG484-G240-A     I2 @TIMECARD_LIB.TIMECARD(SCH_1):PAGE161
   U24  R16 IO_L22N_T3_A04_D20_14 XC7A200T_2FBG484C_FBG484-G240-A     I2 @TIMECARD_LIB.TIMECARD(SCH_1):PAGE161
   U24  N14 IO_L23N_T3_A02_D18_14 XC7A200T_2FBG484C_FBG484-G240-A     I2 @TIMECARD_LIB.TIMECARD(SCH_1):PAGE161
   U24  N13 IO_L23P_T3_A03_D19_14 XC7A200T_2FBG484C_FBG484-G240-A     I2 @TIMECARD_LIB.TIMECARD(SCH_1):PAGE161
   U24  R17 IO_L24N_T3_A00_D16_14 XC7A200T_2FBG484C_FBG484-G240-A     I2 @TIMECARD_LIB.TIMECARD(SCH_1):PAGE161
   U24  J16 IO_0_15 XC7A200T_2FBG484C_FBG484-G240-A   I228 @TIMECARD_LIB.TIMECARD(SCH_1):PAGE162
   U24  F15 IO_0_16 XC7A200T_2FBG484C_FBG484-G240-A   I228 @TIMECARD_LIB.TIMECARD(SCH_1):PAGE162
   U24  M17 IO_25_15 XC7A200T_2FBG484C_FBG484-G240-A   I228 @TIMECARD_LIB.TIMECARD(SCH_1):PAGE162
   U24  F21 IO_25_16 XC7A200T_2FBG484C_FBG484-G240-A   I228 @TIMECARD_LIB.TIMECARD(SCH_1):PAGE162
   U24  E17 IO_L2N_T0_16 XC7A200T_2FBG484C_FBG484-G240-A   I228 @TIMECARD_LIB.TIMECARD(SCH_1):PAGE162
   U24  G16 IO_L2N_T0_AD8N_15 XC7A200T_2FBG484C_FBG484-G240-A   I228 @TIMECARD_LIB.TIMECARD(SCH_1):PAGE162
   U24  G18 IO_L4N_T0_15 XC7A200T_2FBG484C_FBG484-G240-A   I228 @TIMECARD_LIB.TIMECARD(SCH_1):PAGE162
   U24  E14 IO_L4N_T0_16 XC7A200T_2FBG484C_FBG484-G240-A   I228 @TIMECARD_LIB.TIMECARD(SCH_1):PAGE162
   U24  G17 IO_L4P_T0_15 XC7A200T_2FBG484C_FBG484-G240-A   I228 @TIMECARD_LIB.TIMECARD(SCH_1):PAGE162
   U24  D16 IO_L5N_T0_16 XC7A200T_2FBG484C_FBG484-G240-A   I228 @TIMECARD_LIB.TIMECARD(SCH_1):PAGE162
   U24  E16 IO_L5P_T0_16 XC7A200T_2FBG484C_FBG484-G240-A   I228 @TIMECARD_LIB.TIMECARD(SCH_1):PAGE162
   U24  H18 IO_L6N_T0_VREF_15 XC7A200T_2FBG484C_FBG484-G240-A   I228 @TIMECARD_LIB.TIMECARD(SCH_1):PAGE162
   U24  H17 IO_L6P_T0_15 XC7A200T_2FBG484C_FBG484-G240-A   I228 @TIMECARD_LIB.TIMECARD(SCH_1):PAGE162
   U24  B16 IO_L7N_T1_16 XC7A200T_2FBG484C_FBG484-G240-A   I228 @TIMECARD_LIB.TIMECARD(SCH_1):PAGE162
   U24  B15 IO_L7P_T1_16 XC7A200T_2FBG484C_FBG484-G240-A   I228 @TIMECARD_LIB.TIMECARD(SCH_1):PAGE162
   U24  A16 IO_L9N_T1_DQS_16 XC7A200T_2FBG484C_FBG484-G240-A   I228 @TIMECARD_LIB.TIMECARD(SCH_1):PAGE162
   U24  A15 IO_L9P_T1_DQS_16 XC7A200T_2FBG484C_FBG484-G240-A   I228 @TIMECARD_LIB.TIMECARD(SCH_1):PAGE162
   U24  J21 IO_L11N_T1_SRCC_15 XC7A200T_2FBG484C_FBG484-G240-A   I228 @TIMECARD_LIB.TIMECARD(SCH_1):PAGE162
   U24  B18 IO_L11N_T1_SRCC_16 XC7A200T_2FBG484C_FBG484-G240-A   I228 @TIMECARD_LIB.TIMECARD(SCH_1):PAGE162
   U24  B17 IO_L11P_T1_SRCC_16 XC7A200T_2FBG484C_FBG484-G240-A   I228 @TIMECARD_LIB.TIMECARD(SCH_1):PAGE162
   U24  K19 IO_L13N_T2_MRCC_15 XC7A200T_2FBG484C_FBG484-G240-A   I228 @TIMECARD_LIB.TIMECARD(SCH_1):PAGE162
   U24  C19 IO_L13N_T2_MRCC_16 XC7A200T_2FBG484C_FBG484-G240-A   I228 @TIMECARD_LIB.TIMECARD(SCH_1):PAGE162
   U24  K18 IO_L13P_T2_MRCC_15 XC7A200T_2FBG484C_FBG484-G240-A   I228 @TIMECARD_LIB.TIMECARD(SCH_1):PAGE162
   U24  L20 IO_L14N_T2_SRCC_15 XC7A200T_2FBG484C_FBG484-G240-A   I228 @TIMECARD_LIB.TIMECARD(SCH_1):PAGE162
   U24  L19 IO_L14P_T2_SRCC_15 XC7A200T_2FBG484C_FBG484-G240-A   I228 @TIMECARD_LIB.TIMECARD(SCH_1):PAGE162
   U24  E18 IO_L15N_T2_DQS_16 XC7A200T_2FBG484C_FBG484-G240-A   I228 @TIMECARD_LIB.TIMECARD(SCH_1):PAGE162
   U24  L18 IO_L16N_T2_A27_15 XC7A200T_2FBG484C_FBG484-G240-A   I228 @TIMECARD_LIB.TIMECARD(SCH_1):PAGE162
   U24  A19 IO_L17N_T2_16 XC7A200T_2FBG484C_FBG484-G240-A   I228 @TIMECARD_LIB.TIMECARD(SCH_1):PAGE162
   U24  F20 IO_L18N_T2_16 XC7A200T_2FBG484C_FBG484-G240-A   I228 @TIMECARD_LIB.TIMECARD(SCH_1):PAGE162
   U24  M20 IO_L18N_T2_A23_15 XC7A200T_2FBG484C_FBG484-G240-A   I228 @TIMECARD_LIB.TIMECARD(SCH_1):PAGE162
   U24  F19 IO_L18P_T2_16 XC7A200T_2FBG484C_FBG484-G240-A   I228 @TIMECARD_LIB.TIMECARD(SCH_1):PAGE162
   U24  C20 IO_L19N_T3_VREF_16 XC7A200T_2FBG484C_FBG484-G240-A   I228 @TIMECARD_LIB.TIMECARD(SCH_1):PAGE162
   U24  D20 IO_L19P_T3_16 XC7A200T_2FBG484C_FBG484-G240-A   I228 @TIMECARD_LIB.TIMECARD(SCH_1):PAGE162
   U24  K17 IO_L21P_T3_DQS_15 XC7A200T_2FBG484C_FBG484-G240-A   I228 @TIMECARD_LIB.TIMECARD(SCH_1):PAGE162
   U24  L16 IO_L23P_T3_FOE_B_15 XC7A200T_2FBG484C_FBG484-G240-A   I228 @TIMECARD_LIB.TIMECARD(SCH_1):PAGE162
   U24   T3 IO_0_34 XC7A200T_2FBG484C_FBG484-G240-A     I1 @TIMECARD_LIB.TIMECARD(SCH_1):PAGE163
   U24   F4 IO_0_35 XC7A200T_2FBG484C_FBG484-G240-A     I1 @TIMECARD_LIB.TIMECARD(SCH_1):PAGE163
   U24   U7 IO_25_34 XC7A200T_2FBG484C_FBG484-G240-A     I1 @TIMECARD_LIB.TIMECARD(SCH_1):PAGE163
   U24   L6 IO_25_35 XC7A200T_2FBG484C_FBG484-G240-A     I1 @TIMECARD_LIB.TIMECARD(SCH_1):PAGE163
   U24   U1 IO_L1N_T0_34 XC7A200T_2FBG484C_FBG484-G240-A     I1 @TIMECARD_LIB.TIMECARD(SCH_1):PAGE163
   U24   A1 IO_L1N_T0_AD4N_35 XC7A200T_2FBG484C_FBG484-G240-A     I1 @TIMECARD_LIB.TIMECARD(SCH_1):PAGE163
   U24   T1 IO_L1P_T0_34 XC7A200T_2FBG484C_FBG484-G240-A     I1 @TIMECARD_LIB.TIMECARD(SCH_1):PAGE163
   U24   B1 IO_L1P_T0_AD4P_35 XC7A200T_2FBG484C_FBG484-G240-A     I1 @TIMECARD_LIB.TIMECARD(SCH_1):PAGE163
   U24   V2 IO_L2N_T0_34 XC7A200T_2FBG484C_FBG484-G240-A     I1 @TIMECARD_LIB.TIMECARD(SCH_1):PAGE163
   U24   B2 IO_L2N_T0_AD12N_35 XC7A200T_2FBG484C_FBG484-G240-A     I1 @TIMECARD_LIB.TIMECARD(SCH_1):PAGE163
   U24   U2 IO_L2P_T0_34 XC7A200T_2FBG484C_FBG484-G240-A     I1 @TIMECARD_LIB.TIMECARD(SCH_1):PAGE163
   U24   C2 IO_L2P_T0_AD12P_35 XC7A200T_2FBG484C_FBG484-G240-A     I1 @TIMECARD_LIB.TIMECARD(SCH_1):PAGE163
   U24   R2 IO_L3N_T0_DQS_34 XC7A200T_2FBG484C_FBG484-G240-A     I1 @TIMECARD_LIB.TIMECARD(SCH_1):PAGE163
   U24   D1 IO_L3N_T0_DQS_AD5N_35 XC7A200T_2FBG484C_FBG484-G240-A     I1 @TIMECARD_LIB.TIMECARD(SCH_1):PAGE163
   U24   R3 IO_L3P_T0_DQS_34 XC7A200T_2FBG484C_FBG484-G240-A     I1 @TIMECARD_LIB.TIMECARD(SCH_1):PAGE163
   U24   E1 IO_L3P_T0_DQS_AD5P_35 XC7A200T_2FBG484C_FBG484-G240-A     I1 @TIMECARD_LIB.TIMECARD(SCH_1):PAGE163
   U24   Y2 IO_L4N_T0_34 XC7A200T_2FBG484C_FBG484-G240-A     I1 @TIMECARD_LIB.TIMECARD(SCH_1):PAGE163
   U24   D2 IO_L4N_T0_35 XC7A200T_2FBG484C_FBG484-G240-A     I1 @TIMECARD_LIB.TIMECARD(SCH_1):PAGE163
   U24   W2 IO_L4P_T0_34 XC7A200T_2FBG484C_FBG484-G240-A     I1 @TIMECARD_LIB.TIMECARD(SCH_1):PAGE163
   U24   E2 IO_L4P_T0_35 XC7A200T_2FBG484C_FBG484-G240-A     I1 @TIMECARD_LIB.TIMECARD(SCH_1):PAGE163
   U24   F1 IO_L5N_T0_AD13N_35 XC7A200T_2FBG484C_FBG484-G240-A     I1 @TIMECARD_LIB.TIMECARD(SCH_1):PAGE163
   U24   G1 IO_L5P_T0_AD13P_35 XC7A200T_2FBG484C_FBG484-G240-A     I1 @TIMECARD_LIB.TIMECARD(SCH_1):PAGE163
   U24   V3 IO_L6N_T0_VREF_34 XC7A200T_2FBG484C_FBG484-G240-A     I1 @TIMECARD_LIB.TIMECARD(SCH_1):PAGE163
   U24   E3 IO_L6N_T0_VREF_35 XC7A200T_2FBG484C_FBG484-G240-A     I1 @TIMECARD_LIB.TIMECARD(SCH_1):PAGE163
   U24   U3 IO_L6P_T0_34 XC7A200T_2FBG484C_FBG484-G240-A     I1 @TIMECARD_LIB.TIMECARD(SCH_1):PAGE163
   U24   F3 IO_L6P_T0_35 XC7A200T_2FBG484C_FBG484-G240-A     I1 @TIMECARD_LIB.TIMECARD(SCH_1):PAGE163
   U24  AB1 IO_L7N_T1_34 XC7A200T_2FBG484C_FBG484-G240-A     I1 @TIMECARD_LIB.TIMECARD(SCH_1):PAGE163
   U24   J1 IO_L7N_T1_AD6N_35 XC7A200T_2FBG484C_FBG484-G240-A     I1 @TIMECARD_LIB.TIMECARD(SCH_1):PAGE163
   U24  AA1 IO_L7P_T1_34 XC7A200T_2FBG484C_FBG484-G240-A     I1 @TIMECARD_LIB.TIMECARD(SCH_1):PAGE163
   U24   K1 IO_L7P_T1_AD6P_35 XC7A200T_2FBG484C_FBG484-G240-A     I1 @TIMECARD_LIB.TIMECARD(SCH_1):PAGE163
   U24   G2 IO_L8N_T1_AD14N_35 XC7A200T_2FBG484C_FBG484-G240-A     I1 @TIMECARD_LIB.TIMECARD(SCH_1):PAGE163
   U24   H2 IO_L8P_T1_AD14P_35 XC7A200T_2FBG484C_FBG484-G240-A     I1 @TIMECARD_LIB.TIMECARD(SCH_1):PAGE163
   U24  AA3 IO_L9N_T1_DQS_34 XC7A200T_2FBG484C_FBG484-G240-A     I1 @TIMECARD_LIB.TIMECARD(SCH_1):PAGE163
   U24   J2 IO_L9N_T1_DQS_AD7N_35 XC7A200T_2FBG484C_FBG484-G240-A     I1 @TIMECARD_LIB.TIMECARD(SCH_1):PAGE163
   U24   Y3 IO_L9P_T1_DQS_34 XC7A200T_2FBG484C_FBG484-G240-A     I1 @TIMECARD_LIB.TIMECARD(SCH_1):PAGE163
   U24   K2 IO_L9P_T1_DQS_AD7P_35 XC7A200T_2FBG484C_FBG484-G240-A     I1 @TIMECARD_LIB.TIMECARD(SCH_1):PAGE163
   U24   H5 IO_L10N_T1_AD15N_35 XC7A200T_2FBG484C_FBG484-G240-A     I1 @TIMECARD_LIB.TIMECARD(SCH_1):PAGE163
   U24   J5 IO_L10P_T1_AD15P_35 XC7A200T_2FBG484C_FBG484-G240-A     I1 @TIMECARD_LIB.TIMECARD(SCH_1):PAGE163
   U24  AA4 IO_L11N_T1_SRCC_34 XC7A200T_2FBG484C_FBG484-G240-A     I1 @TIMECARD_LIB.TIMECARD(SCH_1):PAGE163
   U24   G3 IO_L11N_T1_SRCC_35 XC7A200T_2FBG484C_FBG484-G240-A     I1 @TIMECARD_LIB.TIMECARD(SCH_1):PAGE163
   U24   Y4 IO_L11P_T1_SRCC_34 XC7A200T_2FBG484C_FBG484-G240-A     I1 @TIMECARD_LIB.TIMECARD(SCH_1):PAGE163
   U24   H3 IO_L11P_T1_SRCC_35 XC7A200T_2FBG484C_FBG484-G240-A     I1 @TIMECARD_LIB.TIMECARD(SCH_1):PAGE163
   U24   W4 IO_L12N_T1_MRCC_34 XC7A200T_2FBG484C_FBG484-G240-A     I1 @TIMECARD_LIB.TIMECARD(SCH_1):PAGE163
   U24   G4 IO_L12N_T1_MRCC_35 XC7A200T_2FBG484C_FBG484-G240-A     I1 @TIMECARD_LIB.TIMECARD(SCH_1):PAGE163
   U24   V4 IO_L12P_T1_MRCC_34 XC7A200T_2FBG484C_FBG484-G240-A     I1 @TIMECARD_LIB.TIMECARD(SCH_1):PAGE163
   U24   H4 IO_L12P_T1_MRCC_35 XC7A200T_2FBG484C_FBG484-G240-A     I1 @TIMECARD_LIB.TIMECARD(SCH_1):PAGE163
   U24   J4 IO_L13N_T2_MRCC_35 XC7A200T_2FBG484C_FBG484-G240-A     I1 @TIMECARD_LIB.TIMECARD(SCH_1):PAGE163
   U24   K4 IO_L13P_T2_MRCC_35 XC7A200T_2FBG484C_FBG484-G240-A     I1 @TIMECARD_LIB.TIMECARD(SCH_1):PAGE163
   U24   U5 IO_L14N_T2_SRCC_34 XC7A200T_2FBG484C_FBG484-G240-A     I1 @TIMECARD_LIB.TIMECARD(SCH_1):PAGE163
   U24   K3 IO_L14N_T2_SRCC_35 XC7A200T_2FBG484C_FBG484-G240-A     I1 @TIMECARD_LIB.TIMECARD(SCH_1):PAGE163
   U24   T5 IO_L14P_T2_SRCC_34 XC7A200T_2FBG484C_FBG484-G240-A     I1 @TIMECARD_LIB.TIMECARD(SCH_1):PAGE163
   U24   L3 IO_L14P_T2_SRCC_35 XC7A200T_2FBG484C_FBG484-G240-A     I1 @TIMECARD_LIB.TIMECARD(SCH_1):PAGE163
   U24   W5 IO_L15N_T2_DQS_34 XC7A200T_2FBG484C_FBG484-G240-A     I1 @TIMECARD_LIB.TIMECARD(SCH_1):PAGE163
   U24   L1 IO_L15N_T2_DQS_35 XC7A200T_2FBG484C_FBG484-G240-A     I1 @TIMECARD_LIB.TIMECARD(SCH_1):PAGE163
   U24   W6 IO_L15P_T2_DQS_34 XC7A200T_2FBG484C_FBG484-G240-A     I1 @TIMECARD_LIB.TIMECARD(SCH_1):PAGE163
   U24   M1 IO_L15P_T2_DQS_35 XC7A200T_2FBG484C_FBG484-G240-A     I1 @TIMECARD_LIB.TIMECARD(SCH_1):PAGE163
   U24   V5 IO_L16N_T2_34 XC7A200T_2FBG484C_FBG484-G240-A     I1 @TIMECARD_LIB.TIMECARD(SCH_1):PAGE163
   U24   M2 IO_L16N_T2_35 XC7A200T_2FBG484C_FBG484-G240-A     I1 @TIMECARD_LIB.TIMECARD(SCH_1):PAGE163
   U24   U6 IO_L16P_T2_34 XC7A200T_2FBG484C_FBG484-G240-A     I1 @TIMECARD_LIB.TIMECARD(SCH_1):PAGE163
   U24   M3 IO_L16P_T2_35 XC7A200T_2FBG484C_FBG484-G240-A     I1 @TIMECARD_LIB.TIMECARD(SCH_1):PAGE163
   U24   T6 IO_L17N_T2_34 XC7A200T_2FBG484C_FBG484-G240-A     I1 @TIMECARD_LIB.TIMECARD(SCH_1):PAGE163
   U24   J6 IO_L17N_T2_35 XC7A200T_2FBG484C_FBG484-G240-A     I1 @TIMECARD_LIB.TIMECARD(SCH_1):PAGE163
   U24   R6 IO_L17P_T2_34 XC7A200T_2FBG484C_FBG484-G240-A     I1 @TIMECARD_LIB.TIMECARD(SCH_1):PAGE163
   U24   K6 IO_L17P_T2_35 XC7A200T_2FBG484C_FBG484-G240-A     I1 @TIMECARD_LIB.TIMECARD(SCH_1):PAGE163
   U24  AA6 IO_L18N_T2_34 XC7A200T_2FBG484C_FBG484-G240-A     I1 @TIMECARD_LIB.TIMECARD(SCH_1):PAGE163
   U24   L4 IO_L18N_T2_35 XC7A200T_2FBG484C_FBG484-G240-A     I1 @TIMECARD_LIB.TIMECARD(SCH_1):PAGE163
   U24   Y6 IO_L18P_T2_34 XC7A200T_2FBG484C_FBG484-G240-A     I1 @TIMECARD_LIB.TIMECARD(SCH_1):PAGE163
   U24   L5 IO_L18P_T2_35 XC7A200T_2FBG484C_FBG484-G240-A     I1 @TIMECARD_LIB.TIMECARD(SCH_1):PAGE163
   U24   W7 IO_L19N_T3_VREF_34 XC7A200T_2FBG484C_FBG484-G240-A     I1 @TIMECARD_LIB.TIMECARD(SCH_1):PAGE163
   U24   N3 IO_L19N_T3_VREF_35 XC7A200T_2FBG484C_FBG484-G240-A     I1 @TIMECARD_LIB.TIMECARD(SCH_1):PAGE163
   U24   V7 IO_L19P_T3_34 XC7A200T_2FBG484C_FBG484-G240-A     I1 @TIMECARD_LIB.TIMECARD(SCH_1):PAGE163
   U24   N4 IO_L19P_T3_35 XC7A200T_2FBG484C_FBG484-G240-A     I1 @TIMECARD_LIB.TIMECARD(SCH_1):PAGE163
   U25    8     NC ISL80101IRAJZ_DFN10-G222-10136A   I151 @TIMECARD_LIB.TIMECARD(SCH_1):PAGE515
    Y3    2     NC OSC6P_V2-A130-00003-AW   I144 @TIMECARD_LIB.TIMECARD(SCH_1):PAGE522
    Y4    2     NC OSC6P_V2-A130-00004-AW   I145 @TIMECARD_LIB.TIMECARD(SCH_1):PAGE522
   U29    1 RESV_NC_1 BNO080_LGA_28-A246-00002-FB,BNA    I29 @TIMECARD_LIB.TIMECARD(SCH_1):PAGE9
   U29    7 RESV_NC_2 BNO080_LGA_28-A246-00002-FB,BNA    I29 @TIMECARD_LIB.TIMECARD(SCH_1):PAGE9
   U29    8 RESV_NC_3 BNO080_LGA_28-A246-00002-FB,BNA    I29 @TIMECARD_LIB.TIMECARD(SCH_1):PAGE9
   U29   12 RESV_NC_4 BNO080_LGA_28-A246-00002-FB,BNA    I29 @TIMECARD_LIB.TIMECARD(SCH_1):PAGE9
   U29   13 RESV_NC_5 BNO080_LGA_28-A246-00002-FB,BNA    I29 @TIMECARD_LIB.TIMECARD(SCH_1):PAGE9
   U29   21 RESV_NC_6 BNO080_LGA_28-A246-00002-FB,BNA    I29 @TIMECARD_LIB.TIMECARD(SCH_1):PAGE9
   U29   22 RESV_NC_7 BNO080_LGA_28-A246-00002-FB,BNA    I29 @TIMECARD_LIB.TIMECARD(SCH_1):PAGE9
   U29   23 RESV_NC_8 BNO080_LGA_28-A246-00002-FB,BNA    I29 @TIMECARD_LIB.TIMECARD(SCH_1):PAGE9
   U29   24 RESV_NC_9 BNO080_LGA_28-A246-00002-FB,BNA    I29 @TIMECARD_LIB.TIMECARD(SCH_1):PAGE9
   CR4    4    VDD DIODE_4_V1-G122-10123-01   I179 @TIMECARD_LIB.TIMECARD(SCH_1):PAGE12
   J14    6      6 G200_10283_01-G200-10283-01   I427 @TIMECARD_LIB.TIMECARD(SCH_1):PAGE127
   J14    7      7 G200_10283_01-G200-10283-01   I427 @TIMECARD_LIB.TIMECARD(SCH_1):PAGE127
   J14    8      8 G200_10283_01-G200-10283-01   I427 @TIMECARD_LIB.TIMECARD(SCH_1):PAGE127
   CR7    4    VDD DIODE_4_V1-G122-10123-01   I442 @TIMECARD_LIB.TIMECARD(SCH_1):PAGE127
   CR6    4    VDD DIODE_4_V1-G122-10123-01   I443 @TIMECARD_LIB.TIMECARD(SCH_1):PAGE127
   U33   26  OUT16 IS32FL3207_QWLA3_TR_QFN29-A223A   I219 @TIMECARD_LIB.TIMECARD(SCH_1):PAGE14
   U33   27  OUT17 IS32FL3207_QWLA3_TR_QFN29-A223A   I219 @TIMECARD_LIB.TIMECARD(SCH_1):PAGE14
   U33   28  OUT18 IS32FL3207_QWLA3_TR_QFN29-A223A   I219 @TIMECARD_LIB.TIMECARD(SCH_1):PAGE14
    U3    1     NC 74LVC1G07_SC70_5-G220-10017-01   I134 @TIMECARD_LIB.TIMECARD(SCH_1):PAGE3
   U17    1      1 CL1001485A-G122-00019-01     I3 @TIMECARD_LIB.TIMECARD(SCH_1):PAGE524
   U17    3      3 CL1001485A-G122-00019-01     I3 @TIMECARD_LIB.TIMECARD(SCH_1):PAGE524
   U18   40 CDBUS2 FT4232HL_REEL_QFP64-G223-10282A    I64 @TIMECARD_LIB.TIMECARD(SCH_1):PAGE524
   U18   41 CDBUS3 FT4232HL_REEL_QFP64-G223-10282A    I64 @TIMECARD_LIB.TIMECARD(SCH_1):PAGE524
   U18   43 CDBUS4 FT4232HL_REEL_QFP64-G223-10282A    I64 @TIMECARD_LIB.TIMECARD(SCH_1):PAGE524
   U18   44 CDBUS5 FT4232HL_REEL_QFP64-G223-10282A    I64 @TIMECARD_LIB.TIMECARD(SCH_1):PAGE524
   U18   45 CDBUS6 FT4232HL_REEL_QFP64-G223-10282A    I64 @TIMECARD_LIB.TIMECARD(SCH_1):PAGE524
   U18   46 CDBUS7 FT4232HL_REEL_QFP64-G223-10282A    I64 @TIMECARD_LIB.TIMECARD(SCH_1):PAGE524
   U18   53 DDBUS2 FT4232HL_REEL_QFP64-G223-10282A    I64 @TIMECARD_LIB.TIMECARD(SCH_1):PAGE524
   U18   54 DDBUS3 FT4232HL_REEL_QFP64-G223-10282A    I64 @TIMECARD_LIB.TIMECARD(SCH_1):PAGE524
   U18   55 DDBUS4 FT4232HL_REEL_QFP64-G223-10282A    I64 @TIMECARD_LIB.TIMECARD(SCH_1):PAGE524
   U18   57 DDBUS5 FT4232HL_REEL_QFP64-G223-10282A    I64 @TIMECARD_LIB.TIMECARD(SCH_1):PAGE524
   U18   58 DDBUS6 FT4232HL_REEL_QFP64-G223-10282A    I64 @TIMECARD_LIB.TIMECARD(SCH_1):PAGE524
   U18   59 DDBUS7 FT4232HL_REEL_QFP64-G223-10282A    I64 @TIMECARD_LIB.TIMECARD(SCH_1):PAGE524
   U18   60 PWREN* FT4232HL_REEL_QFP64-G223-10282A    I64 @TIMECARD_LIB.TIMECARD(SCH_1):PAGE524
   U18   36 SUSPEND* FT4232HL_REEL_QFP64-G223-10282A    I64 @TIMECARD_LIB.TIMECARD(SCH_1):PAGE524
   U31    7     NC CAT93C46VI_GT3_SOIC8-G221-1007A   I200 @TIMECARD_LIB.TIMECARD(SCH_1):PAGE524
   U41    8     NC ISL80101IRAJZ_DFN10-G222-10136A    I29 @TIMECARD_LIB.TIMECARD(SCH_1):PAGE525
   J11    4      4 CONN_USB_1X5_G2_GH4_F_RA_SMT-GA     I2 @TIMECARD_LIB.TIMECARD(SCH_1):PAGE527
    U9    1      1 CL1001485A-G122-00019-01     I4 @TIMECARD_LIB.TIMECARD(SCH_1):PAGE527
    U9    3      3 CL1001485A-G122-00019-01     I4 @TIMECARD_LIB.TIMECARD(SCH_1):PAGE527
   U11    8  MHL_N TS3USB3031RMGR_WQFN12-G220-103A   I108 @TIMECARD_LIB.TIMECARD(SCH_1):PAGE527
   U11    7  MHL_P TS3USB3031RMGR_WQFN12-G220-103A   I108 @TIMECARD_LIB.TIMECARD(SCH_1):PAGE527
    P1   10     10 CONN_HDR_2X10_M_S_SMT-G200-130A   I193 @TIMECARD_LIB.TIMECARD(SCH_1):PAGE527
    P1   11     11 CONN_HDR_2X10_M_S_SMT-G200-130A   I193 @TIMECARD_LIB.TIMECARD(SCH_1):PAGE527
    P1   12     12 CONN_HDR_2X10_M_S_SMT-G200-130A   I193 @TIMECARD_LIB.TIMECARD(SCH_1):PAGE527
    P1   13     13 CONN_HDR_2X10_M_S_SMT-G200-130A   I193 @TIMECARD_LIB.TIMECARD(SCH_1):PAGE527
    P1   14     14 CONN_HDR_2X10_M_S_SMT-G200-130A   I193 @TIMECARD_LIB.TIMECARD(SCH_1):PAGE527
    P1   16     16 CONN_HDR_2X10_M_S_SMT-G200-130A   I193 @TIMECARD_LIB.TIMECARD(SCH_1):PAGE527
    P1   18     18 CONN_HDR_2X10_M_S_SMT-G200-130A   I193 @TIMECARD_LIB.TIMECARD(SCH_1):PAGE527
   U39    1     B1 NLASB3157DFT2G_SC88-G223-10187A   I407 @TIMECARD_LIB.TIMECARD(SCH_1):PAGE524
   U40    1     B1 NLASB3157DFT2G_SC88-G223-10187A   I408 @TIMECARD_LIB.TIMECARD(SCH_1):PAGE524
   SP4    1      1 SOLDER_PREFORM-G380-10015-01   I130 @TIMECARD_LIB.TIMECARD(SCH_1):PAGE33
   SP4    2      2 SOLDER_PREFORM-G380-10015-01   I130 @TIMECARD_LIB.TIMECARD(SCH_1):PAGE33
   SP5    1      1 SOLDER_PREFORM-G380-10015-01   I131 @TIMECARD_LIB.TIMECARD(SCH_1):PAGE33
   SP5    2      2 SOLDER_PREFORM-G380-10015-01   I131 @TIMECARD_LIB.TIMECARD(SCH_1):PAGE33
   SP7    1      1 SOLDER_PREFORM-G380-10015-01   I132 @TIMECARD_LIB.TIMECARD(SCH_1):PAGE33
   SP7    2      2 SOLDER_PREFORM-G380-10015-01   I132 @TIMECARD_LIB.TIMECARD(SCH_1):PAGE33
   SP6    1      1 SOLDER_PREFORM-G380-10015-01   I133 @TIMECARD_LIB.TIMECARD(SCH_1):PAGE33
   SP6    2      2 SOLDER_PREFORM-G380-10015-01   I133 @TIMECARD_LIB.TIMECARD(SCH_1):PAGE33
   SP8    1      1 SOLDER_PREFORM-G380-10015-01   I134 @TIMECARD_LIB.TIMECARD(SCH_1):PAGE33
   SP8    2      2 SOLDER_PREFORM-G380-10015-01   I134 @TIMECARD_LIB.TIMECARD(SCH_1):PAGE33
   SP9    1      1 SOLDER_PREFORM-G380-10015-01   I135 @TIMECARD_LIB.TIMECARD(SCH_1):PAGE33
   SP9    2      2 SOLDER_PREFORM-G380-10015-01   I135 @TIMECARD_LIB.TIMECARD(SCH_1):PAGE33
  SP11    1      1 SOLDER_PREFORM-G380-10015-01   I136 @TIMECARD_LIB.TIMECARD(SCH_1):PAGE33
  SP11    2      2 SOLDER_PREFORM-G380-10015-01   I136 @TIMECARD_LIB.TIMECARD(SCH_1):PAGE33
  SP10    1      1 SOLDER_PREFORM-G380-10015-01   I137 @TIMECARD_LIB.TIMECARD(SCH_1):PAGE33
  SP10    2      2 SOLDER_PREFORM-G380-10015-01   I137 @TIMECARD_LIB.TIMECARD(SCH_1):PAGE33
  SP15    1      1 SOLDER_PREFORM-G380-10015-01   I138 @TIMECARD_LIB.TIMECARD(SCH_1):PAGE33
  SP15    2      2 SOLDER_PREFORM-G380-10015-01   I138 @TIMECARD_LIB.TIMECARD(SCH_1):PAGE33
  SP14    1      1 SOLDER_PREFORM-G380-10015-01   I139 @TIMECARD_LIB.TIMECARD(SCH_1):PAGE33
  SP14    2      2 SOLDER_PREFORM-G380-10015-01   I139 @TIMECARD_LIB.TIMECARD(SCH_1):PAGE33
  SP13    1      1 SOLDER_PREFORM-G380-10015-01   I140 @TIMECARD_LIB.TIMECARD(SCH_1):PAGE33
  SP13    2      2 SOLDER_PREFORM-G380-10015-01   I140 @TIMECARD_LIB.TIMECARD(SCH_1):PAGE33
  SP12    1      1 SOLDER_PREFORM-G380-10015-01   I141 @TIMECARD_LIB.TIMECARD(SCH_1):PAGE33
  SP12    2      2 SOLDER_PREFORM-G380-10015-01   I141 @TIMECARD_LIB.TIMECARD(SCH_1):PAGE33
  SP17    1      1 SOLDER_PREFORM-G380-10015-01   I142 @TIMECARD_LIB.TIMECARD(SCH_1):PAGE33
  SP17    2      2 SOLDER_PREFORM-G380-10015-01   I142 @TIMECARD_LIB.TIMECARD(SCH_1):PAGE33
  SP27    1      1 SOLDER_PREFORM-G380-10015-01   I143 @TIMECARD_LIB.TIMECARD(SCH_1):PAGE33
  SP27    2      2 SOLDER_PREFORM-G380-10015-01   I143 @TIMECARD_LIB.TIMECARD(SCH_1):PAGE33
  SP26    1      1 SOLDER_PREFORM-G380-10015-01   I144 @TIMECARD_LIB.TIMECARD(SCH_1):PAGE33
  SP26    2      2 SOLDER_PREFORM-G380-10015-01   I144 @TIMECARD_LIB.TIMECARD(SCH_1):PAGE33
  SP25    1      1 SOLDER_PREFORM-G380-10015-01   I145 @TIMECARD_LIB.TIMECARD(SCH_1):PAGE33
  SP25    2      2 SOLDER_PREFORM-G380-10015-01   I145 @TIMECARD_LIB.TIMECARD(SCH_1):PAGE33
  SP24    1      1 SOLDER_PREFORM-G380-10015-01   I146 @TIMECARD_LIB.TIMECARD(SCH_1):PAGE33
  SP24    2      2 SOLDER_PREFORM-G380-10015-01   I146 @TIMECARD_LIB.TIMECARD(SCH_1):PAGE33
  SP23    1      1 SOLDER_PREFORM-G380-10015-01   I147 @TIMECARD_LIB.TIMECARD(SCH_1):PAGE33
  SP23    2      2 SOLDER_PREFORM-G380-10015-01   I147 @TIMECARD_LIB.TIMECARD(SCH_1):PAGE33
  SP22    1      1 SOLDER_PREFORM-G380-10015-01   I148 @TIMECARD_LIB.TIMECARD(SCH_1):PAGE33
  SP22    2      2 SOLDER_PREFORM-G380-10015-01   I148 @TIMECARD_LIB.TIMECARD(SCH_1):PAGE33
  SP20    1      1 SOLDER_PREFORM-G380-10015-01   I149 @TIMECARD_LIB.TIMECARD(SCH_1):PAGE33
  SP20    2      2 SOLDER_PREFORM-G380-10015-01   I149 @TIMECARD_LIB.TIMECARD(SCH_1):PAGE33
  SP21    1      1 SOLDER_PREFORM-G380-10015-01   I150 @TIMECARD_LIB.TIMECARD(SCH_1):PAGE33
  SP21    2      2 SOLDER_PREFORM-G380-10015-01   I150 @TIMECARD_LIB.TIMECARD(SCH_1):PAGE33
  SP19    1      1 SOLDER_PREFORM-G380-10015-01   I151 @TIMECARD_LIB.TIMECARD(SCH_1):PAGE33
  SP19    2      2 SOLDER_PREFORM-G380-10015-01   I151 @TIMECARD_LIB.TIMECARD(SCH_1):PAGE33
  SP18    1      1 SOLDER_PREFORM-G380-10015-01   I152 @TIMECARD_LIB.TIMECARD(SCH_1):PAGE33
  SP18    2      2 SOLDER_PREFORM-G380-10015-01   I152 @TIMECARD_LIB.TIMECARD(SCH_1):PAGE33
  SP16    1      1 SOLDER_PREFORM-G380-10015-01   I153 @TIMECARD_LIB.TIMECARD(SCH_1):PAGE33
  SP16    2      2 SOLDER_PREFORM-G380-10015-01   I153 @TIMECARD_LIB.TIMECARD(SCH_1):PAGE33
  SP41    1      1 SOLDER_PREFORM-G380-10015-01   I155 @TIMECARD_LIB.TIMECARD(SCH_1):PAGE33
  SP41    2      2 SOLDER_PREFORM-G380-10015-01   I155 @TIMECARD_LIB.TIMECARD(SCH_1):PAGE33
  SP38    1      1 SOLDER_PREFORM-G380-10015-01   I159 @TIMECARD_LIB.TIMECARD(SCH_1):PAGE33
  SP38    2      2 SOLDER_PREFORM-G380-10015-01   I159 @TIMECARD_LIB.TIMECARD(SCH_1):PAGE33
  SP37    1      1 SOLDER_PREFORM-G380-10015-01   I161 @TIMECARD_LIB.TIMECARD(SCH_1):PAGE33
  SP37    2      2 SOLDER_PREFORM-G380-10015-01   I161 @TIMECARD_LIB.TIMECARD(SCH_1):PAGE33
  SP36    1      1 SOLDER_PREFORM-G380-10015-01   I163 @TIMECARD_LIB.TIMECARD(SCH_1):PAGE33
  SP36    2      2 SOLDER_PREFORM-G380-10015-01   I163 @TIMECARD_LIB.TIMECARD(SCH_1):PAGE33
  SP35    1      1 SOLDER_PREFORM-G380-10015-01   I165 @TIMECARD_LIB.TIMECARD(SCH_1):PAGE33
  SP35    2      2 SOLDER_PREFORM-G380-10015-01   I165 @TIMECARD_LIB.TIMECARD(SCH_1):PAGE33
  SP34    1      1 SOLDER_PREFORM-G380-10015-01   I167 @TIMECARD_LIB.TIMECARD(SCH_1):PAGE33
  SP34    2      2 SOLDER_PREFORM-G380-10015-01   I167 @TIMECARD_LIB.TIMECARD(SCH_1):PAGE33
  SP33    1      1 SOLDER_PREFORM-G380-10015-01   I169 @TIMECARD_LIB.TIMECARD(SCH_1):PAGE33
  SP33    2      2 SOLDER_PREFORM-G380-10015-01   I169 @TIMECARD_LIB.TIMECARD(SCH_1):PAGE33
  SP32    1      1 SOLDER_PREFORM-G380-10015-01   I171 @TIMECARD_LIB.TIMECARD(SCH_1):PAGE33
  SP32    2      2 SOLDER_PREFORM-G380-10015-01   I171 @TIMECARD_LIB.TIMECARD(SCH_1):PAGE33
  SP31    1      1 SOLDER_PREFORM-G380-10015-01   I172 @TIMECARD_LIB.TIMECARD(SCH_1):PAGE33
  SP31    2      2 SOLDER_PREFORM-G380-10015-01   I172 @TIMECARD_LIB.TIMECARD(SCH_1):PAGE33
  SP30    1      1 SOLDER_PREFORM-G380-10015-01   I173 @TIMECARD_LIB.TIMECARD(SCH_1):PAGE33
  SP30    2      2 SOLDER_PREFORM-G380-10015-01   I173 @TIMECARD_LIB.TIMECARD(SCH_1):PAGE33
  SP29    1      1 SOLDER_PREFORM-G380-10015-01   I174 @TIMECARD_LIB.TIMECARD(SCH_1):PAGE33
  SP29    2      2 SOLDER_PREFORM-G380-10015-01   I174 @TIMECARD_LIB.TIMECARD(SCH_1):PAGE33
  SP28    1      1 SOLDER_PREFORM-G380-10015-01   I175 @TIMECARD_LIB.TIMECARD(SCH_1):PAGE33
  SP28    2      2 SOLDER_PREFORM-G380-10015-01   I175 @TIMECARD_LIB.TIMECARD(SCH_1):PAGE33
  SP40    1      1 SOLDER_PREFORM-G380-10015-01   I176 @TIMECARD_LIB.TIMECARD(SCH_1):PAGE33
  SP40    2      2 SOLDER_PREFORM-G380-10015-01   I176 @TIMECARD_LIB.TIMECARD(SCH_1):PAGE33
  SP39    1      1 SOLDER_PREFORM-G380-10015-01   I177 @TIMECARD_LIB.TIMECARD(SCH_1):PAGE33
  SP39    2      2 SOLDER_PREFORM-G380-10015-01   I177 @TIMECARD_LIB.TIMECARD(SCH_1):PAGE33

OSC_125M_CLKN @TIMECARD_LIB.TIMECARD(SCH_1):OSC_125M_CLKN
  C254    1      1 CAPACITOR-G105-0B104-CK,0.1UF,A   I142 @TIMECARD_LIB.TIMECARD(SCH_1):PAGE522
    Y4    5  OUT_N OSC6P_V2-A130-00004-AW   I145 @TIMECARD_LIB.TIMECARD(SCH_1):PAGE522
  R240    1      1 RESISTOR-G155-11500-01,150OHM,A   I172 @TIMECARD_LIB.TIMECARD(SCH_1):PAGE522

OSC_125M_CLKP @TIMECARD_LIB.TIMECARD(SCH_1):OSC_125M_CLKP
  C253    1      1 CAPACITOR-G105-0B104-CK,0.1UF,A   I143 @TIMECARD_LIB.TIMECARD(SCH_1):PAGE522
    Y4    4  OUT_P OSC6P_V2-A130-00004-AW   I145 @TIMECARD_LIB.TIMECARD(SCH_1):PAGE522
  R242    1      1 RESISTOR-G155-11500-01,150OHM,A   I174 @TIMECARD_LIB.TIMECARD(SCH_1):PAGE522

OSC_200M_CLKN @TIMECARD_LIB.TIMECARD(SCH_1):OSC_200M_CLKN
    Y3    5  OUT_N OSC6P_V2-A130-00003-AW   I144 @TIMECARD_LIB.TIMECARD(SCH_1):PAGE522
  C252    1      1 CAPACITOR-G105-0B104-CK,0.1UF,A   I160 @TIMECARD_LIB.TIMECARD(SCH_1):PAGE522
  R239    1      1 RESISTOR-G155-11500-01,150OHM,A   I169 @TIMECARD_LIB.TIMECARD(SCH_1):PAGE522

OSC_200M_CLKP @TIMECARD_LIB.TIMECARD(SCH_1):OSC_200M_CLKP
    Y3    4  OUT_P OSC6P_V2-A130-00003-AW   I144 @TIMECARD_LIB.TIMECARD(SCH_1):PAGE522
  C251    1      1 CAPACITOR-G105-0B104-CK,0.1UF,A   I161 @TIMECARD_LIB.TIMECARD(SCH_1):PAGE522
  R241    1      1 RESISTOR-G155-11500-01,150OHM,A   I170 @TIMECARD_LIB.TIMECARD(SCH_1):PAGE522

PCA9546_I2C_SCL @TIMECARD_LIB.TIMECARD(SCH_1):PCA9546_I2C_SCL
  R145    1      1 RESISTOR-G155-133R0-01,33OHM,1%    I67 @TIMECARD_LIB.TIMECARD(SCH_1):PAGE5
   U37    7   COM2 TS3A5018PWR_TSSOP16-G220-10324A   I448 @TIMECARD_LIB.TIMECARD(SCH_1):PAGE524

PCA9546_I2C_SDA @TIMECARD_LIB.TIMECARD(SCH_1):PCA9546_I2C_SDA
  R144    1      1 RESISTOR-G155-133R0-01,33OHM,1%    I68 @TIMECARD_LIB.TIMECARD(SCH_1):PAGE5
   U37    4   COM1 TS3A5018PWR_TSSOP16-G220-10324A   I448 @TIMECARD_LIB.TIMECARD(SCH_1):PAGE524

PCA9546_RST_N @TIMECARD_LIB.TIMECARD(SCH_1):PCA9546_RST_N
    U4    3 RESET* PCA9546APW_TSSOP16-G223-10280-A    I33 @TIMECARD_LIB.TIMECARD(SCH_1):PAGE5
  R146    2      2 RESISTOR-G155-11002-01,10KOHM,A    I60 @TIMECARD_LIB.TIMECARD(SCH_1):PAGE5
  R155    2      2 RESISTOR-G155-14701-01,4.7KOHMA    I66 @TIMECARD_LIB.TIMECARD(SCH_1):PAGE5
   R60    2      2 RESISTOR-G155-133R0-01,33OHM,1%   I125 @TIMECARD_LIB.TIMECARD(SCH_1):PAGE5
  TP21    1      1 TP_PIONT-TP010CT020B030_PTH-TPA  I1645 @TIMECARD_LIB.TIMECARD(SCH_1):PAGE16

PCIE_CONN_PERST_N @TIMECARD_LIB.TIMECARD(SCH_1):PCIE_CONN_PERST_N
   GF1  A11 PERST* CONN_64P_GF-S_M_EF64_PCIE_P039A    I61 @TIMECARD_LIB.TIMECARD(SCH_1):PAGE3
   R55    1      1 RESISTOR-G155-14701-01,4.7KOHMA    I62 @TIMECARD_LIB.TIMECARD(SCH_1):PAGE3
   R56    2      2 RESISTOR-G155-14701-01,4.7KOHMA    I63 @TIMECARD_LIB.TIMECARD(SCH_1):PAGE3
    U3    2      A 74LVC1G07_SC70_5-G220-10017-01   I134 @TIMECARD_LIB.TIMECARD(SCH_1):PAGE3
  TP48    1      1 TP_PIONT-TP010CT020B030_PTH-TPA  I1695 @TIMECARD_LIB.TIMECARD(SCH_1):PAGE16

PCIE_CONN_SMCLK @TIMECARD_LIB.TIMECARD(SCH_1):PCIE_CONN_SMCLK
   GF1   B5  SMCLK CONN_64P_GF-S_M_EF64_PCIE_P039A    I61 @TIMECARD_LIB.TIMECARD(SCH_1):PAGE3
    U2    3  SCLIN G220_10198_01-G223-10197-01   I100 @TIMECARD_LIB.TIMECARD(SCH_1):PAGE3

PCIE_CONN_SMDAT @TIMECARD_LIB.TIMECARD(SCH_1):PCIE_CONN_SMDAT
   GF1   B6  SMDAT CONN_64P_GF-S_M_EF64_PCIE_P039A    I61 @TIMECARD_LIB.TIMECARD(SCH_1):PAGE3
    U2    6  SDAIN G220_10198_01-G223-10197-01   I100 @TIMECARD_LIB.TIMECARD(SCH_1):PAGE3

PCIE_CONN_TCK @TIMECARD_LIB.TIMECARD(SCH_1):PCIE_CONN_TCK
   R28    1      1 RESISTOR-G155-100R0-J0,0OHM,-    I54 @TIMECARD_LIB.TIMECARD(SCH_1):PAGE3
   GF1   A5  JTAG2 CONN_64P_GF-S_M_EF64_PCIE_P039A    I61 @TIMECARD_LIB.TIMECARD(SCH_1):PAGE3

PCIE_CONN_TDI @TIMECARD_LIB.TIMECARD(SCH_1):PCIE_CONN_TDI
   R41    1      1 RESISTOR-G155-100R0-J0,0OHM,-    I53 @TIMECARD_LIB.TIMECARD(SCH_1):PAGE3
   GF1   A6  JTAG3 CONN_64P_GF-S_M_EF64_PCIE_P039A    I61 @TIMECARD_LIB.TIMECARD(SCH_1):PAGE3

PCIE_CONN_TDO @TIMECARD_LIB.TIMECARD(SCH_1):PCIE_CONN_TDO
   R42    1      1 RESISTOR-G155-100R0-J0,0OHM,-    I52 @TIMECARD_LIB.TIMECARD(SCH_1):PAGE3
   GF1   A7  JTAG4 CONN_64P_GF-S_M_EF64_PCIE_P039A    I61 @TIMECARD_LIB.TIMECARD(SCH_1):PAGE3

PCIE_CONN_TMS @TIMECARD_LIB.TIMECARD(SCH_1):PCIE_CONN_TMS
   R43    1      1 RESISTOR-G155-100R0-J0,0OHM,-    I51 @TIMECARD_LIB.TIMECARD(SCH_1):PAGE3
   GF1   A8  JTAG5 CONN_64P_GF-S_M_EF64_PCIE_P039A    I61 @TIMECARD_LIB.TIMECARD(SCH_1):PAGE3

PCIE_PERST_N @TIMECARD_LIB.TIMECARD(SCH_1):PCIE_PERST_N
   U34    3    MR* TPS3808G18DBVR_SOT23_6-G222-00A   I139 @TIMECARD_LIB.TIMECARD(SCH_1):PAGE3
   R63    2      2 RESISTOR-G155-14701-01,4.7KOHMA   I144 @TIMECARD_LIB.TIMECARD(SCH_1):PAGE3
   R57    2      2 RESISTOR-G155-133R0-01,33OHM,1%   I153 @TIMECARD_LIB.TIMECARD(SCH_1):PAGE3

PCIE_REFCLKN @TIMECARD_LIB.TIMECARD(SCH_1):PCIE_REFCLKN
   C23    2      2 CAPACITOR-G105-0B104-CK,0.1UF,A    I37 @TIMECARD_LIB.TIMECARD(SCH_1):PAGE3
   U24  E10 MGTREFCLK1N_216 XC7A200T_2FBG484C_FBG484-G240-A   I232 @TIMECARD_LIB.TIMECARD(SCH_1):PAGE127
  R198    2      2 RESISTOR-G155-11000-01,100OHM,A   I334 @TIMECARD_LIB.TIMECARD(SCH_1):PAGE127

PCIE_REFCLKP @TIMECARD_LIB.TIMECARD(SCH_1):PCIE_REFCLKP
   C19    2      2 CAPACITOR-G105-0B104-CK,0.1UF,A    I36 @TIMECARD_LIB.TIMECARD(SCH_1):PAGE3
   U24  F10 MGTREFCLK1P_216 XC7A200T_2FBG484C_FBG484-G240-A   I232 @TIMECARD_LIB.TIMECARD(SCH_1):PAGE127
  R198    1      1 RESISTOR-G155-11000-01,100OHM,A   I334 @TIMECARD_LIB.TIMECARD(SCH_1):PAGE127

PCIE_SMCLK @TIMECARD_LIB.TIMECARD(SCH_1):PCIE_SMCLK
    U2    2 SCLOUT G220_10198_01-G223-10197-01   I100 @TIMECARD_LIB.TIMECARD(SCH_1):PAGE3
   R27    1      1 RESISTOR-G155-133R0-01,33OHM,1%    I72 @TIMECARD_LIB.TIMECARD(SCH_1):PAGE5
  R176    1      1 RESISTOR-G155-133R0-01,33OHM,1%   I102 @TIMECARD_LIB.TIMECARD(SCH_1):PAGE5

PCIE_SMDAT @TIMECARD_LIB.TIMECARD(SCH_1):PCIE_SMDAT
    U2    7 SDAOUT G220_10198_01-G223-10197-01   I100 @TIMECARD_LIB.TIMECARD(SCH_1):PAGE3
   R26    1      1 RESISTOR-G155-133R0-01,33OHM,1%    I69 @TIMECARD_LIB.TIMECARD(SCH_1):PAGE5
  R175    1      1 RESISTOR-G155-133R0-01,33OHM,1%   I100 @TIMECARD_LIB.TIMECARD(SCH_1):PAGE5

PRI_EEPROM_SDA @TIMECARD_LIB.TIMECARD(SCH_1):PRI_EEPROM_SDA
    U7    3    SDA AT24MAC402_SOT23_5-A221-00002-A    I89 @TIMECARD_LIB.TIMECARD(SCH_1):PAGE5
  R345    2      2 RESISTOR-G155-133R0-01,33OHM,1%    I90 @TIMECARD_LIB.TIMECARD(SCH_1):PAGE5

PUDC @TIMECARD_LIB.TIMECARD(SCH_1):PUDC
   U24  U22 IO_L3P_T0_DQS_PUDC_14* XC7A200T_2FBG484C_FBG484-G240-A     I2 @TIMECARD_LIB.TIMECARD(SCH_1):PAGE161
  R223    1      1 RESISTOR-G155-11001-01,1KOHM,1%   I252 @TIMECARD_LIB.TIMECARD(SCH_1):PAGE161
  R224    2      2 RESISTOR-G155-11001-01,1KOHM,1%   I253 @TIMECARD_LIB.TIMECARD(SCH_1):PAGE161

RGB_LED_I2C_SCL @TIMECARD_LIB.TIMECARD(SCH_1):RGB_LED_I2C_SCL
  R313    1      1 RESISTOR-G155-100R0-J0,0OHM,-   I111 @TIMECARD_LIB.TIMECARD(SCH_1):PAGE5
  R311    1      1 RESISTOR-G155-100R0-J0,0OHM,-   I115 @TIMECARD_LIB.TIMECARD(SCH_1):PAGE5
  R366    1      1 RESISTOR-G155-133R0-01,33OHM,1%   I299 @TIMECARD_LIB.TIMECARD(SCH_1):PAGE14

RGB_LED_I2C_SDA @TIMECARD_LIB.TIMECARD(SCH_1):RGB_LED_I2C_SDA
  R312    1      1 RESISTOR-G155-100R0-J0,0OHM,-   I112 @TIMECARD_LIB.TIMECARD(SCH_1):PAGE5
  R310    1      1 RESISTOR-G155-100R0-J0,0OHM,-   I116 @TIMECARD_LIB.TIMECARD(SCH_1):PAGE5
  R364    1      1 RESISTOR-G155-133R0-01,33OHM,1%   I298 @TIMECARD_LIB.TIMECARD(SCH_1):PAGE14

RGB_LED_SHUTDOWN_N @TIMECARD_LIB.TIMECARD(SCH_1):RGB_LED_SHUTDOWN_N
   U33    1   SDB* IS32FL3207_QWLA3_TR_QFN29-A223A   I219 @TIMECARD_LIB.TIMECARD(SCH_1):PAGE14
  R319    2      2 RESISTOR-G155-133R0-01,33OHM,1%   I249 @TIMECARD_LIB.TIMECARD(SCH_1):PAGE14
  C316    1      1 CAPACITOR-G105-0B104-EK,0.1UF,A   I250 @TIMECARD_LIB.TIMECARD(SCH_1):PAGE14
  R320    2      2 RESISTOR-G155-14701-01,4.7KOHMA   I264 @TIMECARD_LIB.TIMECARD(SCH_1):PAGE14
  TP25    1      1 TP_PIONT-TP010CT020B030_PTH-TPA  I1649 @TIMECARD_LIB.TIMECARD(SCH_1):PAGE16

RSVD_DBG_USB_MUX_SEL @TIMECARD_LIB.TIMECARD(SCH_1):RSVD_DBG_USB_MUX_SEL
   U24  M16 IO_L24N_T3_RS0_15 XC7A200T_2FBG484C_FBG484-G240-A   I228 @TIMECARD_LIB.TIMECARD(SCH_1):PAGE162
  R266    1      1 RESISTOR-G155-133R0-01,33OHM,1%   I204 @TIMECARD_LIB.TIMECARD(SCH_1):PAGE527

R_BNO080_BOOT_N @TIMECARD_LIB.TIMECARD(SCH_1):R_BNO080_BOOT_N
   U29    4  BOOTN BNO080_LGA_28-A246-00002-FB,BNA    I29 @TIMECARD_LIB.TIMECARD(SCH_1):PAGE9
   R80    2      2 RESISTOR-G155-133R0-01,33OHM,1%    I32 @TIMECARD_LIB.TIMECARD(SCH_1):PAGE9
  R304    2      2 RESISTOR-G155-14701-01,4.7KOHMA    I37 @TIMECARD_LIB.TIMECARD(SCH_1):PAGE9
  TP18    1      1 TP_PIONT-TP010CT020B030_PTH-TPA  I1633 @TIMECARD_LIB.TIMECARD(SCH_1):PAGE16

R_BNO080_EVN_SCL @TIMECARD_LIB.TIMECARD(SCH_1):R_BNO080_EVN_SCL
   U29   15 ENV_SCL BNO080_LGA_28-A246-00002-FB,BNA    I29 @TIMECARD_LIB.TIMECARD(SCH_1):PAGE9
  R363    1      1 RESISTOR-G155-133R0-01,33OHM,1%    I67 @TIMECARD_LIB.TIMECARD(SCH_1):PAGE9

R_BNO080_EVN_SDA @TIMECARD_LIB.TIMECARD(SCH_1):R_BNO080_EVN_SDA
   U29   16 ENV_SDA BNO080_LGA_28-A246-00002-FB,BNA    I29 @TIMECARD_LIB.TIMECARD(SCH_1):PAGE9
  R330    1      1 RESISTOR-G155-133R0-01,33OHM,1%    I64 @TIMECARD_LIB.TIMECARD(SCH_1):PAGE9

R_BNO080_I2C_SCL @TIMECARD_LIB.TIMECARD(SCH_1):R_BNO080_I2C_SCL
   R77    2      2 RESISTOR-G155-133R0-01,33OHM,1%    I11 @TIMECARD_LIB.TIMECARD(SCH_1):PAGE9
   U29   19 H_SCL/SCK/RX BNO080_LGA_28-A246-00002-FB,BNA    I29 @TIMECARD_LIB.TIMECARD(SCH_1):PAGE9

R_BNO080_I2C_SDA @TIMECARD_LIB.TIMECARD(SCH_1):R_BNO080_I2C_SDA
   R76    2      2 RESISTOR-G155-133R0-01,33OHM,1%    I12 @TIMECARD_LIB.TIMECARD(SCH_1):PAGE9
   U29   20 H_SDA/H_MISO/TX BNO080_LGA_28-A246-00002-FB,BNA    I29 @TIMECARD_LIB.TIMECARD(SCH_1):PAGE9

R_BNO080_INT_N @TIMECARD_LIB.TIMECARD(SCH_1):R_BNO080_INT_N
   U29   14 H_INTN BNO080_LGA_28-A246-00002-FB,BNA    I29 @TIMECARD_LIB.TIMECARD(SCH_1):PAGE9
   R79    2      2 RESISTOR-G155-133R0-01,33OHM,1%    I31 @TIMECARD_LIB.TIMECARD(SCH_1):PAGE9
  TP17    1      1 TP_PIONT-TP010CT020B030_PTH-TPA  I1632 @TIMECARD_LIB.TIMECARD(SCH_1):PAGE16

R_BNO080_RST_N @TIMECARD_LIB.TIMECARD(SCH_1):R_BNO080_RST_N
   U29   11   RST* BNO080_LGA_28-A246-00002-FB,BNA    I29 @TIMECARD_LIB.TIMECARD(SCH_1):PAGE9
   R78    1      1 RESISTOR-G155-133R0-01,33OHM,1%    I41 @TIMECARD_LIB.TIMECARD(SCH_1):PAGE9
  R301    1      1 RESISTOR-G155-14701-01,4.7KOHMA    I43 @TIMECARD_LIB.TIMECARD(SCH_1):PAGE9
  R291    2      2 RESISTOR-G155-14701-01,4.7KOHMA    I44 @TIMECARD_LIB.TIMECARD(SCH_1):PAGE9
  TP16    1      1 TP_PIONT-TP010CT020B030_PTH-TPA  I1631 @TIMECARD_LIB.TIMECARD(SCH_1):PAGE16

R_FPGA_TDO @TIMECARD_LIB.TIMECARD(SCH_1):R_FPGA_TDO
   U24  U13  TDO_0 XC7A200T_2FBG484C_FBG484-G240-A   I232 @TIMECARD_LIB.TIMECARD(SCH_1):PAGE127
  R195    2      2 RESISTOR-G155-133R0-01,33OHM,1%   I331 @TIMECARD_LIB.TIMECARD(SCH_1):PAGE127

R_FT4232_CHC_RX @TIMECARD_LIB.TIMECARD(SCH_1):R_FT4232_CHC_RX
   U18   39 CDBUS1 FT4232HL_REEL_QFP64-G223-10282A    I64 @TIMECARD_LIB.TIMECARD(SCH_1):PAGE524
  R481    1      1 RESISTOR-G155-11003-01,100KOHMA   I150 @TIMECARD_LIB.TIMECARD(SCH_1):PAGE524
  R352    1      1 RESISTOR-G155-11000-01,100OHM,A   I154 @TIMECARD_LIB.TIMECARD(SCH_1):PAGE524

R_FT4232_CHC_TX @TIMECARD_LIB.TIMECARD(SCH_1):R_FT4232_CHC_TX
   U18   38 CDBUS0 FT4232HL_REEL_QFP64-G223-10282A    I64 @TIMECARD_LIB.TIMECARD(SCH_1):PAGE524
  R353    1      1 RESISTOR-G155-11000-01,100OHM,A   I153 @TIMECARD_LIB.TIMECARD(SCH_1):PAGE524

R_FT4232_CHD_RX @TIMECARD_LIB.TIMECARD(SCH_1):R_FT4232_CHD_RX
   U18   52 DDBUS1 FT4232HL_REEL_QFP64-G223-10282A    I64 @TIMECARD_LIB.TIMECARD(SCH_1):PAGE524
  R349    1      1 RESISTOR-G155-11003-01,100KOHMA   I184 @TIMECARD_LIB.TIMECARD(SCH_1):PAGE524
  R132    1      1 RESISTOR-G155-11000-01,100OHM,A   I188 @TIMECARD_LIB.TIMECARD(SCH_1):PAGE524

R_FT4232_CHD_TX @TIMECARD_LIB.TIMECARD(SCH_1):R_FT4232_CHD_TX
   U18   48 DDBUS0 FT4232HL_REEL_QFP64-G223-10282A    I64 @TIMECARD_LIB.TIMECARD(SCH_1):PAGE524
  R131    1      1 RESISTOR-G155-11000-01,100OHM,A   I187 @TIMECARD_LIB.TIMECARD(SCH_1):PAGE524

R_FT4232_I2C_SCL @TIMECARD_LIB.TIMECARD(SCH_1):R_FT4232_I2C_SCL
   U18   26 BDBUS0 FT4232HL_REEL_QFP64-G223-10282A    I64 @TIMECARD_LIB.TIMECARD(SCH_1):PAGE524
  R471    1      1 RESISTOR-G155-100R0-J0,0OHM,-   I169 @TIMECARD_LIB.TIMECARD(SCH_1):PAGE524

R_FT4232_I2C_SDA_IN @TIMECARD_LIB.TIMECARD(SCH_1):R_FT4232_I2C_SDA_IN
   U18   28 BDBUS2 FT4232HL_REEL_QFP64-G223-10282A    I64 @TIMECARD_LIB.TIMECARD(SCH_1):PAGE524
  R473    1      1 RESISTOR-G155-100R0-J0,0OHM,-   I170 @TIMECARD_LIB.TIMECARD(SCH_1):PAGE524

R_FT4232_I2C_SDA_OUT @TIMECARD_LIB.TIMECARD(SCH_1):R_FT4232_I2C_SDA_OUT
   U18   27 BDBUS1 FT4232HL_REEL_QFP64-G223-10282A    I64 @TIMECARD_LIB.TIMECARD(SCH_1):PAGE524
  R472    1      1 RESISTOR-G155-100R0-J0,0OHM,-   I166 @TIMECARD_LIB.TIMECARD(SCH_1):PAGE524

R_FT4232_TCK @TIMECARD_LIB.TIMECARD(SCH_1):R_FT4232_TCK
   U18   16 ADBUS0 FT4232HL_REEL_QFP64-G223-10282A    I64 @TIMECARD_LIB.TIMECARD(SCH_1):PAGE524
  R467    1      1 RESISTOR-G155-133R0-01,33OHM,1%   I141 @TIMECARD_LIB.TIMECARD(SCH_1):PAGE524

R_FT4232_TDI @TIMECARD_LIB.TIMECARD(SCH_1):R_FT4232_TDI
   U18   17 ADBUS1 FT4232HL_REEL_QFP64-G223-10282A    I64 @TIMECARD_LIB.TIMECARD(SCH_1):PAGE524
  R468    1      1 RESISTOR-G155-133R0-01,33OHM,1%   I140 @TIMECARD_LIB.TIMECARD(SCH_1):PAGE524

R_FT4232_TDO @TIMECARD_LIB.TIMECARD(SCH_1):R_FT4232_TDO
   U18   18 ADBUS2 FT4232HL_REEL_QFP64-G223-10282A    I64 @TIMECARD_LIB.TIMECARD(SCH_1):PAGE524
  R469    1      1 RESISTOR-G155-133R0-01,33OHM,1%   I142 @TIMECARD_LIB.TIMECARD(SCH_1):PAGE524
  R466    1      1 RESISTOR-G155-11003-01,100KOHMA   I198 @TIMECARD_LIB.TIMECARD(SCH_1):PAGE524

R_FT4232_TMS @TIMECARD_LIB.TIMECARD(SCH_1):R_FT4232_TMS
   U18   19 ADBUS3 FT4232HL_REEL_QFP64-G223-10282A    I64 @TIMECARD_LIB.TIMECARD(SCH_1):PAGE524
  R470    1      1 RESISTOR-G155-133R0-01,33OHM,1%   I139 @TIMECARD_LIB.TIMECARD(SCH_1):PAGE524

R_FT_USB_DM @TIMECARD_LIB.TIMECARD(SCH_1):R_FT_USB_DM
  R128    2      2 RESISTOR-G155-100R0-J0,0OHM,-    I28 @TIMECARD_LIB.TIMECARD(SCH_1):PAGE524
   U18    7     DM FT4232HL_REEL_QFP64-G223-10282A    I64 @TIMECARD_LIB.TIMECARD(SCH_1):PAGE524

R_FT_USB_DP @TIMECARD_LIB.TIMECARD(SCH_1):R_FT_USB_DP
  R129    2      2 RESISTOR-G155-100R0-J0,0OHM,-    I26 @TIMECARD_LIB.TIMECARD(SCH_1):PAGE524
   U18    8     DP FT4232HL_REEL_QFP64-G223-10282A    I64 @TIMECARD_LIB.TIMECARD(SCH_1):PAGE524

R_ICP10100_I2C_SCL @TIMECARD_LIB.TIMECARD(SCH_1):R_ICP10100_I2C_SCL
   R73    2      2 RESISTOR-G155-133R0-01,33OHM,1%     I6 @TIMECARD_LIB.TIMECARD(SCH_1):PAGE8
   U28    2    SCL ICP_10100_LGA10-A222-00002-FB,A    I24 @TIMECARD_LIB.TIMECARD(SCH_1):PAGE8

R_ICP10100_I2C_SDA @TIMECARD_LIB.TIMECARD(SCH_1):R_ICP10100_I2C_SDA
   R72    2      2 RESISTOR-G155-133R0-01,33OHM,1%     I7 @TIMECARD_LIB.TIMECARD(SCH_1):PAGE8
   U28    4    SDA ICP_10100_LGA10-A222-00002-FB,A    I24 @TIMECARD_LIB.TIMECARD(SCH_1):PAGE8

R_LM75B_1_I2C_SDA @TIMECARD_LIB.TIMECARD(SCH_1):R_LM75B_1_I2C_SDA
  R332    2      2 RESISTOR-G155-133R0-01,33OHM,1%    I15 @TIMECARD_LIB.TIMECARD(SCH_1):PAGE6
    U8    1    SDA LM75BDP_TSSOP8-G220-10215-01    I34 @TIMECARD_LIB.TIMECARD(SCH_1):PAGE6

R_LM75B_2_I2C_SDA @TIMECARD_LIB.TIMECARD(SCH_1):R_LM75B_2_I2C_SDA
   U35    1    SDA LM75BDP_TSSOP8-G220-10215-01    I59 @TIMECARD_LIB.TIMECARD(SCH_1):PAGE6
  R406    2      2 RESISTOR-G155-133R0-01,33OHM,1%    I76 @TIMECARD_LIB.TIMECARD(SCH_1):PAGE6

R_LM75B_3_I2C_SDA @TIMECARD_LIB.TIMECARD(SCH_1):R_LM75B_3_I2C_SDA
   U36    1    SDA LM75BDP_TSSOP8-G220-10215-01    I81 @TIMECARD_LIB.TIMECARD(SCH_1):PAGE6
  R407    2      2 RESISTOR-G155-133R0-01,33OHM,1%   I100 @TIMECARD_LIB.TIMECARD(SCH_1):PAGE6

R_MAC_10MHZ_RF_OUT @TIMECARD_LIB.TIMECARD(SCH_1):R_MAC_10MHZ_RF_OUT
   R92    1      1 RESISTOR-G155-11000-01,100OHM,A    I55 @TIMECARD_LIB.TIMECARD(SCH_1):PAGE527
MAC_PIN3    1      1 NUT-A200-00029-FB   I226 @TIMECARD_LIB.TIMECARD(SCH_1):PAGE527

R_MAC_BITEOUT @TIMECARD_LIB.TIMECARD(SCH_1):R_MAC_BITE OUT
   R93    1      1 RESISTOR-G155-133R0-01,33OHM,1%    I53 @TIMECARD_LIB.TIMECARD(SCH_1):PAGE527
MAC_PIN6    1      1 NUT-A200-00029-FB   I225 @TIMECARD_LIB.TIMECARD(SCH_1):PAGE527
  TP62    1      1 TP_PIONT-TP010CT020B030_PTH-TPA  I1705 @TIMECARD_LIB.TIMECARD(SCH_1):PAGE16

R_MAC_PPS_IN0N @TIMECARD_LIB.TIMECARD(SCH_1):R_MAC_PPS_IN0N
   R86    2      2 RESISTOR-G155-100R0-J0,0OHM,-    I29 @TIMECARD_LIB.TIMECARD(SCH_1):PAGE527
   R90    1      1 RESISTOR-G155-11000-01,100OHM,A    I33 @TIMECARD_LIB.TIMECARD(SCH_1):PAGE527
    P1    7      7 CONN_HDR_2X10_M_S_SMT-G200-130A   I193 @TIMECARD_LIB.TIMECARD(SCH_1):PAGE527

R_MAC_PPS_IN0P @TIMECARD_LIB.TIMECARD(SCH_1):R_MAC_PPS_IN0P
   R85    2      2 RESISTOR-G155-100R0-J0,0OHM,-    I30 @TIMECARD_LIB.TIMECARD(SCH_1):PAGE527
   R90    2      2 RESISTOR-G155-11000-01,100OHM,A    I33 @TIMECARD_LIB.TIMECARD(SCH_1):PAGE527
    P1    5      5 CONN_HDR_2X10_M_S_SMT-G200-130A   I193 @TIMECARD_LIB.TIMECARD(SCH_1):PAGE527

R_MAC_PPS_IN1N @TIMECARD_LIB.TIMECARD(SCH_1):R_MAC_PPS_IN1N
   R84    2      2 RESISTOR-G155-100R0-J0,0OHM,-    I31 @TIMECARD_LIB.TIMECARD(SCH_1):PAGE527
   R89    2      2 RESISTOR-G155-11000-01,100OHM,A    I34 @TIMECARD_LIB.TIMECARD(SCH_1):PAGE527
    P1    3      3 CONN_HDR_2X10_M_S_SMT-G200-130A   I193 @TIMECARD_LIB.TIMECARD(SCH_1):PAGE527

R_MAC_PPS_IN1P @TIMECARD_LIB.TIMECARD(SCH_1):R_MAC_PPS_IN1P
   R83    2      2 RESISTOR-G155-100R0-J0,0OHM,-    I32 @TIMECARD_LIB.TIMECARD(SCH_1):PAGE527
   R89    1      1 RESISTOR-G155-11000-01,100OHM,A    I34 @TIMECARD_LIB.TIMECARD(SCH_1):PAGE527
    P1    1      1 CONN_HDR_2X10_M_S_SMT-G200-130A   I193 @TIMECARD_LIB.TIMECARD(SCH_1):PAGE527

R_MAC_PPS_OUTN @TIMECARD_LIB.TIMECARD(SCH_1):R_MAC_PPS_OUTN
   R88    2      2 RESISTOR-G155-100R0-J0,0OHM,-    I13 @TIMECARD_LIB.TIMECARD(SCH_1):PAGE527
    P1   19     19 CONN_HDR_2X10_M_S_SMT-G200-130A   I193 @TIMECARD_LIB.TIMECARD(SCH_1):PAGE527

R_MAC_PPS_OUTP @TIMECARD_LIB.TIMECARD(SCH_1):R_MAC_PPS_OUTP
   R87    2      2 RESISTOR-G155-100R0-J0,0OHM,-    I14 @TIMECARD_LIB.TIMECARD(SCH_1):PAGE527
    P1   17     17 CONN_HDR_2X10_M_S_SMT-G200-130A   I193 @TIMECARD_LIB.TIMECARD(SCH_1):PAGE527

R_MAC_UART_RX_FPGA_TX @TIMECARD_LIB.TIMECARD(SCH_1):R_MAC_UART_RX_FPGA_TX
   R95    1      1 RESISTOR-G155-133R0-01,33OHM,1%    I52 @TIMECARD_LIB.TIMECARD(SCH_1):PAGE527
MAC_PIN8    1      1 NUT-A200-00029-FB   I220 @TIMECARD_LIB.TIMECARD(SCH_1):PAGE527
  R264    2      2 RESISTOR-G155-11003-01,100KOHMA   I222 @TIMECARD_LIB.TIMECARD(SCH_1):PAGE527
   R81    1      1 RESISTOR-G155-133R0-01,33OHM,1%   I240 @TIMECARD_LIB.TIMECARD(SCH_1):PAGE527

R_MAC_UART_TX_FPGA_RX @TIMECARD_LIB.TIMECARD(SCH_1):R_MAC_UART_TX_FPGA_RX
   R94    1      1 RESISTOR-G155-133R0-01,33OHM,1%    I54 @TIMECARD_LIB.TIMECARD(SCH_1):PAGE527
MAC_PIN7    1      1 NUT-A200-00029-FB   I224 @TIMECARD_LIB.TIMECARD(SCH_1):PAGE527
   R82    1      1 RESISTOR-G155-133R0-01,33OHM,1%   I241 @TIMECARD_LIB.TIMECARD(SCH_1):PAGE527

R_MAC_USB_DM @TIMECARD_LIB.TIMECARD(SCH_1):R_MAC_USB_DM
   R98    1      1 RESISTOR-G155-100R0-J0,0OHM,-   I175 @TIMECARD_LIB.TIMECARD(SCH_1):PAGE527
    P1    4      4 CONN_HDR_2X10_M_S_SMT-G200-130A   I193 @TIMECARD_LIB.TIMECARD(SCH_1):PAGE527

R_MAC_USB_DP @TIMECARD_LIB.TIMECARD(SCH_1):R_MAC_USB_DP
   R97    1      1 RESISTOR-G155-100R0-J0,0OHM,-   I176 @TIMECARD_LIB.TIMECARD(SCH_1):PAGE527
    P1    2      2 CONN_HDR_2X10_M_S_SMT-G200-130A   I193 @TIMECARD_LIB.TIMECARD(SCH_1):PAGE527

R_PCA9546_I2C_SCL @TIMECARD_LIB.TIMECARD(SCH_1):R_PCA9546_I2C_SCL
   R59    2      2 RESISTOR-G155-133R0-01,33OHM,1%     I4 @TIMECARD_LIB.TIMECARD(SCH_1):PAGE5
    U4   14    SCL PCA9546APW_TSSOP16-G223-10280-A    I33 @TIMECARD_LIB.TIMECARD(SCH_1):PAGE5
  R145    2      2 RESISTOR-G155-133R0-01,33OHM,1%    I67 @TIMECARD_LIB.TIMECARD(SCH_1):PAGE5
   R27    2      2 RESISTOR-G155-133R0-01,33OHM,1%    I72 @TIMECARD_LIB.TIMECARD(SCH_1):PAGE5
  R148    2      2 RESISTOR-G155-11002-01,10KOHM,A    I81 @TIMECARD_LIB.TIMECARD(SCH_1):PAGE5
  R311    2      2 RESISTOR-G155-100R0-J0,0OHM,-   I115 @TIMECARD_LIB.TIMECARD(SCH_1):PAGE5

R_PCA9546_I2C_SDA @TIMECARD_LIB.TIMECARD(SCH_1):R_PCA9546_I2C_SDA
    U4   15    SDA PCA9546APW_TSSOP16-G223-10280-A    I33 @TIMECARD_LIB.TIMECARD(SCH_1):PAGE5
  R144    2      2 RESISTOR-G155-133R0-01,33OHM,1%    I68 @TIMECARD_LIB.TIMECARD(SCH_1):PAGE5
   R26    2      2 RESISTOR-G155-133R0-01,33OHM,1%    I69 @TIMECARD_LIB.TIMECARD(SCH_1):PAGE5
  R147    2      2 RESISTOR-G155-11002-01,10KOHM,A    I80 @TIMECARD_LIB.TIMECARD(SCH_1):PAGE5
   R58    2      2 RESISTOR-G155-133R0-01,33OHM,1%    I88 @TIMECARD_LIB.TIMECARD(SCH_1):PAGE5
  R310    2      2 RESISTOR-G155-100R0-J0,0OHM,-   I116 @TIMECARD_LIB.TIMECARD(SCH_1):PAGE5

R_RGB_LED_I2C_SCL @TIMECARD_LIB.TIMECARD(SCH_1):R_RGB_LED_I2C_SCL
   U33    7    SCL IS32FL3207_QWLA3_TR_QFN29-A223A   I219 @TIMECARD_LIB.TIMECARD(SCH_1):PAGE14
  R322    2      2 RESISTOR-G155-133R0-01,33OHM,1%   I257 @TIMECARD_LIB.TIMECARD(SCH_1):PAGE14
  R318    2      2 RESISTOR-G155-11002-01,10KOHM,A   I261 @TIMECARD_LIB.TIMECARD(SCH_1):PAGE14
  R366    2      2 RESISTOR-G155-133R0-01,33OHM,1%   I299 @TIMECARD_LIB.TIMECARD(SCH_1):PAGE14

R_RGB_LED_I2C_SDA @TIMECARD_LIB.TIMECARD(SCH_1):R_RGB_LED_I2C_SDA
   U33    6    SDA IS32FL3207_QWLA3_TR_QFN29-A223A   I219 @TIMECARD_LIB.TIMECARD(SCH_1):PAGE14
  R321    2      2 RESISTOR-G155-133R0-01,33OHM,1%   I258 @TIMECARD_LIB.TIMECARD(SCH_1):PAGE14
  R317    2      2 RESISTOR-G155-11002-01,10KOHM,A   I259 @TIMECARD_LIB.TIMECARD(SCH_1):PAGE14
  R364    2      2 RESISTOR-G155-133R0-01,33OHM,1%   I298 @TIMECARD_LIB.TIMECARD(SCH_1):PAGE14

R_SHT3X_ALERT_N @TIMECARD_LIB.TIMECARD(SCH_1):R_SHT3X_ALERT_N
  R299    1      1 RESISTOR-G155-133R0-01,33OHM,1%    I40 @TIMECARD_LIB.TIMECARD(SCH_1):PAGE7
   U27    3  ALERT SHT31A_DIS_B10KS_DFN8-A222-000A    I44 @TIMECARD_LIB.TIMECARD(SCH_1):PAGE7
  TP27    1      1 TP_PIONT-TP010CT020B030_PTH-TPA  I1661 @TIMECARD_LIB.TIMECARD(SCH_1):PAGE16

R_SHT3X_I2C_SCL @TIMECARD_LIB.TIMECARD(SCH_1):R_SHT3X_I2C_SCL
   R67    2      2 RESISTOR-G155-133R0-01,33OHM,1%    I13 @TIMECARD_LIB.TIMECARD(SCH_1):PAGE7
   U27    4    SCL SHT31A_DIS_B10KS_DFN8-A222-000A    I44 @TIMECARD_LIB.TIMECARD(SCH_1):PAGE7

R_SHT3X_I2C_SDA @TIMECARD_LIB.TIMECARD(SCH_1):R_SHT3X_I2C_SDA
   R66    2      2 RESISTOR-G155-133R0-01,33OHM,1%    I14 @TIMECARD_LIB.TIMECARD(SCH_1):PAGE7
   U27    1    SDA SHT31A_DIS_B10KS_DFN8-A222-000A    I44 @TIMECARD_LIB.TIMECARD(SCH_1):PAGE7

R_SHT3X_RST_N @TIMECARD_LIB.TIMECARD(SCH_1):R_SHT3X_RST_N
  R298    1      1 RESISTOR-G155-133R0-01,33OHM,1%    I33 @TIMECARD_LIB.TIMECARD(SCH_1):PAGE7
  R296    2      2 RESISTOR-G155-14701-01,4.7KOHMA    I38 @TIMECARD_LIB.TIMECARD(SCH_1):PAGE7
  R297    1      1 RESISTOR-G155-14701-01,4.7KOHMA    I39 @TIMECARD_LIB.TIMECARD(SCH_1):PAGE7
   U27    6 RESET* SHT31A_DIS_B10KS_DFN8-A222-000A    I44 @TIMECARD_LIB.TIMECARD(SCH_1):PAGE7
  TP26    1      1 TP_PIONT-TP010CT020B030_PTH-TPA  I1660 @TIMECARD_LIB.TIMECARD(SCH_1):PAGE16

R_XP3R3V_PG @TIMECARD_LIB.TIMECARD(SCH_1):R_XP3R3V_PG
   C77    2      2 CAPACITOR-G104-0B103-EK,0.01UFA     I2 @TIMECARD_LIB.TIMECARD(SCH_1):PAGE517
   R51    2      2 RESISTOR-G155-11002-01,10KOHM,A     I3 @TIMECARD_LIB.TIMECARD(SCH_1):PAGE517
    U6   18  PGOOD TPS54824RNVR_VQFN18-G220-10657A    I42 @TIMECARD_LIB.TIMECARD(SCH_1):PAGE517
  R263    1      1 RESISTOR-G155-100R0-J0,0OHM,-    I47 @TIMECARD_LIB.TIMECARD(SCH_1):PAGE517

R_XP5R0V_EN @TIMECARD_LIB.TIMECARD(SCH_1):R_XP5R0V_EN
   R48    1      1 RESISTOR-A155-05101-DL,5.1KOHMA     I9 @TIMECARD_LIB.TIMECARD(SCH_1):PAGE516
   C29    1      1 CAPACITOR-G105-0B104-CK,0.1UF,A    I10 @TIMECARD_LIB.TIMECARD(SCH_1):PAGE516
   R49    2      2 RESISTOR-G155-11002-01,10KOHM,A    I16 @TIMECARD_LIB.TIMECARD(SCH_1):PAGE516
    U5   17     EN TPS54824RNVR_VQFN18-G220-10657A    I42 @TIMECARD_LIB.TIMECARD(SCH_1):PAGE516
  R142    2      2 RESISTOR-G155-11000-01,100OHM,A    I44 @TIMECARD_LIB.TIMECARD(SCH_1):PAGE516

SEC_EEPROM_SDA @TIMECARD_LIB.TIMECARD(SCH_1):SEC_EEPROM_SDA
   U19    5    SDA 24LC16BT_I_ST_TSSOP8-G221-1017A   I151 @TIMECARD_LIB.TIMECARD(SCH_1):PAGE5
   R45    2      2 RESISTOR-G155-133R0-01,33OHM,1%   I162 @TIMECARD_LIB.TIMECARD(SCH_1):PAGE5

SEC_EEPROM_WP @TIMECARD_LIB.TIMECARD(SCH_1):SEC_EEPROM_WP
   J17    3      3 CONN_HDR_2X2_M_S_SMT-G200-1068A   I127 @TIMECARD_LIB.TIMECARD(SCH_1):PAGE5
   U19    7     WP 24LC16BT_I_ST_TSSOP8-G221-1017A   I151 @TIMECARD_LIB.TIMECARD(SCH_1):PAGE5
   R24    1      1 RESISTOR-G155-14701-01,4.7KOHMA   I167 @TIMECARD_LIB.TIMECARD(SCH_1):PAGE5
    R3    2      2 RESISTOR-G155-14701-01,4.7KOHMA   I169 @TIMECARD_LIB.TIMECARD(SCH_1):PAGE5
    R2    2      2 RESISTOR-G155-13300-01,330OHM,A   I173 @TIMECARD_LIB.TIMECARD(SCH_1):PAGE5
  TP20    1      1 TP_PIONT-TP010CT020B030_PTH-TPA  I1615 @TIMECARD_LIB.TIMECARD(SCH_1):PAGE16

SG @TIMECARD_LIB.TIMECARD(SCH_1):SG
   C37    2      2 CAPACITOR-G105-0B104-CK,0.1UF,A     I4 @TIMECARD_LIB.TIMECARD(SCH_1):PAGE3
   GF1   B4   GND1 CONN_64P_GF-S_M_EF64_PCIE_P039A    I61 @TIMECARD_LIB.TIMECARD(SCH_1):PAGE3
   GF1   A4   GND2 CONN_64P_GF-S_M_EF64_PCIE_P039A    I61 @TIMECARD_LIB.TIMECARD(SCH_1):PAGE3
   GF1   B7   GND3 CONN_64P_GF-S_M_EF64_PCIE_P039A    I61 @TIMECARD_LIB.TIMECARD(SCH_1):PAGE3
   GF1  A12   GND4 CONN_64P_GF-S_M_EF64_PCIE_P039A    I61 @TIMECARD_LIB.TIMECARD(SCH_1):PAGE3
   GF1  B13   GND5 CONN_64P_GF-S_M_EF64_PCIE_P039A    I61 @TIMECARD_LIB.TIMECARD(SCH_1):PAGE3
   GF1  A15   GND6 CONN_64P_GF-S_M_EF64_PCIE_P039A    I61 @TIMECARD_LIB.TIMECARD(SCH_1):PAGE3
   GF1  B16   GND7 CONN_64P_GF-S_M_EF64_PCIE_P039A    I61 @TIMECARD_LIB.TIMECARD(SCH_1):PAGE3
   GF1  A18   GND8 CONN_64P_GF-S_M_EF64_PCIE_P039A    I61 @TIMECARD_LIB.TIMECARD(SCH_1):PAGE3
   GF1  B18   GND9 CONN_64P_GF-S_M_EF64_PCIE_P039A    I61 @TIMECARD_LIB.TIMECARD(SCH_1):PAGE3
   GF1  A20  GND10 CONN_64P_GF-S_M_EF64_PCIE_P039A    I61 @TIMECARD_LIB.TIMECARD(SCH_1):PAGE3
   GF1  B21  GND11 CONN_64P_GF-S_M_EF64_PCIE_P039A    I61 @TIMECARD_LIB.TIMECARD(SCH_1):PAGE3
   GF1  B22  GND12 CONN_64P_GF-S_M_EF64_PCIE_P039A    I61 @TIMECARD_LIB.TIMECARD(SCH_1):PAGE3
   GF1  A23  GND13 CONN_64P_GF-S_M_EF64_PCIE_P039A    I61 @TIMECARD_LIB.TIMECARD(SCH_1):PAGE3
   GF1  A24  GND14 CONN_64P_GF-S_M_EF64_PCIE_P039A    I61 @TIMECARD_LIB.TIMECARD(SCH_1):PAGE3
   GF1  B25  GND15 CONN_64P_GF-S_M_EF64_PCIE_P039A    I61 @TIMECARD_LIB.TIMECARD(SCH_1):PAGE3
   GF1  B26  GND17 CONN_64P_GF-S_M_EF64_PCIE_P039A    I61 @TIMECARD_LIB.TIMECARD(SCH_1):PAGE3
   GF1  A27  GND18 CONN_64P_GF-S_M_EF64_PCIE_P039A    I61 @TIMECARD_LIB.TIMECARD(SCH_1):PAGE3
   GF1  A28  GND19 CONN_64P_GF-S_M_EF64_PCIE_P039A    I61 @TIMECARD_LIB.TIMECARD(SCH_1):PAGE3
   GF1  B29  GND20 CONN_64P_GF-S_M_EF64_PCIE_P039A    I61 @TIMECARD_LIB.TIMECARD(SCH_1):PAGE3
   GF1  A31  GND21 CONN_64P_GF-S_M_EF64_PCIE_P039A    I61 @TIMECARD_LIB.TIMECARD(SCH_1):PAGE3
   GF1  B32  GND22 CONN_64P_GF-S_M_EF64_PCIE_P039A    I61 @TIMECARD_LIB.TIMECARD(SCH_1):PAGE3
  R334    2      2 RESISTOR-G155-11001-01,1KOHM,1%    I30 @TIMECARD_LIB.TIMECARD(SCH_1):PAGE6
  R336    2      2 RESISTOR-G155-11001-01,1KOHM,1%    I32 @TIMECARD_LIB.TIMECARD(SCH_1):PAGE6
  R338    2      2 RESISTOR-G155-11001-01,1KOHM,1%    I33 @TIMECARD_LIB.TIMECARD(SCH_1):PAGE6
   C39    1      1 CAPACITOR-G105-0B104-EK,0.1UF,A    I37 @TIMECARD_LIB.TIMECARD(SCH_1):PAGE6
    U8    4    GND LM75BDP_TSSOP8-G220-10215-01    I38 @TIMECARD_LIB.TIMECARD(SCH_1):PAGE6
   R69    2      2 RESISTOR-G155-11001-01,1KOHM,1%     I7 @TIMECARD_LIB.TIMECARD(SCH_1):PAGE7
   C51    2      2 CAPACITOR-G104-0A120-FJ,12PF,5%    I17 @TIMECARD_LIB.TIMECARD(SCH_1):PAGE9
   C72    2      2 CAPACITOR-G107-0F106-EM,10UF,2A    I12 @TIMECARD_LIB.TIMECARD(SCH_1):PAGE11
   C73    2      2 CAPACITOR-G105-0B104-EK,0.1UF,A    I13 @TIMECARD_LIB.TIMECARD(SCH_1):PAGE11
   C78    2      2 CAPACITOR-G105-0B104-EK,0.1UF,A    I15 @TIMECARD_LIB.TIMECARD(SCH_1):PAGE11
  R114    2      2 RESISTOR-G155-14701-01,4.7KOHMA    I18 @TIMECARD_LIB.TIMECARD(SCH_1):PAGE11
   C79    2      2 CAPACITOR-G107-0F106-EM,10UF,2A    I24 @TIMECARD_LIB.TIMECARD(SCH_1):PAGE11
   C80    2      2 CAPACITOR-G105-0B104-CK,0.1UF,A    I26 @TIMECARD_LIB.TIMECARD(SCH_1):PAGE11
   CR5    1    GND DIODE_4_V1-G122-10123-01    I42 @TIMECARD_LIB.TIMECARD(SCH_1):PAGE12
   R55    2      2 RESISTOR-G155-14701-01,4.7KOHMA    I62 @TIMECARD_LIB.TIMECARD(SCH_1):PAGE3
   C77    1      1 CAPACITOR-G104-0B103-EK,0.01UFA     I2 @TIMECARD_LIB.TIMECARD(SCH_1):PAGE517
   C76    2      2 CAPACITOR-G105-0B104-EK,0.1UF,A     I6 @TIMECARD_LIB.TIMECARD(SCH_1):PAGE517
   R52    2      2 RESISTOR-G155-05101-01,5.1KOHMA    I11 @TIMECARD_LIB.TIMECARD(SCH_1):PAGE517
   C46    2      2 CAPACITOR-G105-0B104-CK,0.1UF,A    I12 @TIMECARD_LIB.TIMECARD(SCH_1):PAGE517
   C48    2      2 CAPACITOR-G107-0F106-EM,10UF,2A    I14 @TIMECARD_LIB.TIMECARD(SCH_1):PAGE517
   C50    2      2 CAPACITOR-G107-0F106-EM,10UF,2A    I15 @TIMECARD_LIB.TIMECARD(SCH_1):PAGE517
   C52    2      2 CAPACITOR-G105-0B104-EK,0.1UF,A    I16 @TIMECARD_LIB.TIMECARD(SCH_1):PAGE517
   C53    2      2 CAPACITOR-G105-0B104-EK,0.1UF,A    I21 @TIMECARD_LIB.TIMECARD(SCH_1):PAGE517
   SP2    1      1 SOLDER_PREFORM-G380-10015-01    I24 @TIMECARD_LIB.TIMECARD(SCH_1):PAGE517
   R39    2      2 RESISTOR-G157-12R20-01,2.2OHM,A    I32 @TIMECARD_LIB.TIMECARD(SCH_1):PAGE517
   C18    2      2 CAPACITOR-G105-0B104-CK,0.1UF,A    I36 @TIMECARD_LIB.TIMECARD(SCH_1):PAGE517
   C20    2      2 CAPACITOR-G107-0F226-CM,22UF,2A    I37 @TIMECARD_LIB.TIMECARD(SCH_1):PAGE517
   C21    2      2 CAPACITOR-G107-0F226-CM,22UF,2A    I38 @TIMECARD_LIB.TIMECARD(SCH_1):PAGE517
   C22    2      2 CAPACITOR-G107-0F226-CM,22UF,2A    I40 @TIMECARD_LIB.TIMECARD(SCH_1):PAGE517
    U6    3 PGND_1 TPS54824RNVR_VQFN18-G220-10657A    I42 @TIMECARD_LIB.TIMECARD(SCH_1):PAGE517
    U6    4 PGND_2 TPS54824RNVR_VQFN18-G220-10657A    I42 @TIMECARD_LIB.TIMECARD(SCH_1):PAGE517
    U6    5 PGND_3 TPS54824RNVR_VQFN18-G220-10657A    I42 @TIMECARD_LIB.TIMECARD(SCH_1):PAGE517
    U6    8 PGND_4 TPS54824RNVR_VQFN18-G220-10657A    I42 @TIMECARD_LIB.TIMECARD(SCH_1):PAGE517
    U6    9 PGND_5 TPS54824RNVR_VQFN18-G220-10657A    I42 @TIMECARD_LIB.TIMECARD(SCH_1):PAGE517
    U6   10 PGND_6 TPS54824RNVR_VQFN18-G220-10657A    I42 @TIMECARD_LIB.TIMECARD(SCH_1):PAGE517
   C74    2      2 CAPACITOR-G105-0B104-EK,0.1UF,A     I4 @TIMECARD_LIB.TIMECARD(SCH_1):PAGE516
   C75    1      1 CAPACITOR-G104-0B103-EK,0.01UFA     I7 @TIMECARD_LIB.TIMECARD(SCH_1):PAGE516
   R48    2      2 RESISTOR-A155-05101-DL,5.1KOHMA     I9 @TIMECARD_LIB.TIMECARD(SCH_1):PAGE516
   C29    2      2 CAPACITOR-G105-0B104-CK,0.1UF,A    I10 @TIMECARD_LIB.TIMECARD(SCH_1):PAGE516
   C30    2      2 CAPACITOR-G107-0F106-EM,10UF,2A    I18 @TIMECARD_LIB.TIMECARD(SCH_1):PAGE516
   C32    2      2 CAPACITOR-G107-0F106-EM,10UF,2A    I19 @TIMECARD_LIB.TIMECARD(SCH_1):PAGE516
   C33    2      2 CAPACITOR-G105-0B104-EK,0.1UF,A    I20 @TIMECARD_LIB.TIMECARD(SCH_1):PAGE516
   C41    2      2 CAPACITOR-G105-0B104-EK,0.1UF,A    I22 @TIMECARD_LIB.TIMECARD(SCH_1):PAGE516
   SP1    1      1 SOLDER_PREFORM-G380-10015-01    I24 @TIMECARD_LIB.TIMECARD(SCH_1):PAGE516
   C12    2      2 CAPACITOR-G105-0B104-CK,0.1UF,A    I32 @TIMECARD_LIB.TIMECARD(SCH_1):PAGE516
   C13    2      2 CAPACITOR-G107-0F226-CM,22UF,2A    I33 @TIMECARD_LIB.TIMECARD(SCH_1):PAGE516
   C14    2      2 CAPACITOR-G107-0F226-CM,22UF,2A    I35 @TIMECARD_LIB.TIMECARD(SCH_1):PAGE516
   R33    2      2 RESISTOR-G157-12R20-01,2.2OHM,A    I38 @TIMECARD_LIB.TIMECARD(SCH_1):PAGE516
   C15    2      2 CAPACITOR-G107-0F226-CM,22UF,2A    I40 @TIMECARD_LIB.TIMECARD(SCH_1):PAGE516
    U5    3 PGND_1 TPS54824RNVR_VQFN18-G220-10657A    I42 @TIMECARD_LIB.TIMECARD(SCH_1):PAGE516
    U5    4 PGND_2 TPS54824RNVR_VQFN18-G220-10657A    I42 @TIMECARD_LIB.TIMECARD(SCH_1):PAGE516
    U5    5 PGND_3 TPS54824RNVR_VQFN18-G220-10657A    I42 @TIMECARD_LIB.TIMECARD(SCH_1):PAGE516
    U5    8 PGND_4 TPS54824RNVR_VQFN18-G220-10657A    I42 @TIMECARD_LIB.TIMECARD(SCH_1):PAGE516
    U5    9 PGND_5 TPS54824RNVR_VQFN18-G220-10657A    I42 @TIMECARD_LIB.TIMECARD(SCH_1):PAGE516
    U5   10 PGND_6 TPS54824RNVR_VQFN18-G220-10657A    I42 @TIMECARD_LIB.TIMECARD(SCH_1):PAGE516
   C17    2      2 CAPACITOR-G105-0B104-CK,0.1UF,A    I92 @TIMECARD_LIB.TIMECARD(SCH_1):PAGE3
    U2    4    GND G220_10198_01-G223-10197-01   I100 @TIMECARD_LIB.TIMECARD(SCH_1):PAGE3
   C38    2      2 CAPACITOR-G105-0B104-CK,0.1UF,A    I45 @TIMECARD_LIB.TIMECARD(SCH_1):PAGE5
    U4    8    VSS PCA9546APW_TSSOP16-G223-10280-A    I54 @TIMECARD_LIB.TIMECARD(SCH_1):PAGE5
  R155    1      1 RESISTOR-G155-14701-01,4.7KOHMA    I66 @TIMECARD_LIB.TIMECARD(SCH_1):PAGE5
    C3    2      2 CAPACITOR-G105-0B104-EK,0.1UF,A   I156 @TIMECARD_LIB.TIMECARD(SCH_1):PAGE15
  CR10    A      A DIODE_2E-G122-10190-01   I159 @TIMECARD_LIB.TIMECARD(SCH_1):PAGE15
    C2    2      2 CAPACITOR-G105-0B104-EK,0.1UF,A   I160 @TIMECARD_LIB.TIMECARD(SCH_1):PAGE15
    R5    2      2 RESISTOR-G155-11002-01,10KOHM,A   I169 @TIMECARD_LIB.TIMECARD(SCH_1):PAGE15
   R46    1      1 RESISTOR-G155-02672-01,26.7K,1%   I171 @TIMECARD_LIB.TIMECARD(SCH_1):PAGE15
    C4    1      1 CAPACITOR-G104-0F224-BK,0.22UFA   I172 @TIMECARD_LIB.TIMECARD(SCH_1):PAGE15
    R8    1      1 RESISTOR-G155-100R0-J0,0OHM,-   I173 @TIMECARD_LIB.TIMECARD(SCH_1):PAGE15
    R7    1      1 RESISTOR-G155-100R0-J0,0OHM,-   I174 @TIMECARD_LIB.TIMECARD(SCH_1):PAGE15
   R10    2      2 RESISTOR-G155-11002-01,10KOHM,A   I183 @TIMECARD_LIB.TIMECARD(SCH_1):PAGE15
    C7    2      2 CAPACITOR-G105-0B104-EK,0.1UF,A   I185 @TIMECARD_LIB.TIMECARD(SCH_1):PAGE15
   R14    2      2 RESISTOR-G155-03921-01,3.92KOHA   I186 @TIMECARD_LIB.TIMECARD(SCH_1):PAGE15
   R16    2      2 RESISTOR-G155-03921-01,3.92KOHA   I188 @TIMECARD_LIB.TIMECARD(SCH_1):PAGE15
    C6    2      2 CAPACITOR-G107-0F106-EM,10UF,2A   I196 @TIMECARD_LIB.TIMECARD(SCH_1):PAGE15
   R12    2      2 RESISTOR-G155-11002-01,10KOHM,A   I197 @TIMECARD_LIB.TIMECARD(SCH_1):PAGE15
    C8    2      2 CAPACITOR-G104-0B103-EK,0.01UFA   I201 @TIMECARD_LIB.TIMECARD(SCH_1):PAGE15
   CR3    A      A DIODE_2-G122-00005-01   I204 @TIMECARD_LIB.TIMECARD(SCH_1):PAGE15
    C9    2      2 CAPACITOR-G107-0F106-EM,10UF,2A   I206 @TIMECARD_LIB.TIMECARD(SCH_1):PAGE15
   C10    2      2 CAPACITOR-G107-0F106-EM,10UF,2A   I207 @TIMECARD_LIB.TIMECARD(SCH_1):PAGE15
    C5    2      2 CAPACITOR-G105-0B104-EK,0.1UF,A   I211 @TIMECARD_LIB.TIMECARD(SCH_1):PAGE15
    U1    7    GND MP5022CGQV_Z_QFN22-G220-10510-A   I212 @TIMECARD_LIB.TIMECARD(SCH_1):PAGE15
  R165    2      2 RESISTOR-G155-11002-01,10KOHM,A     I2 @TIMECARD_LIB.TIMECARD(SCH_1):PAGE68
  C184    2      2 CAPACITOR-G105-0B104-EK,0.1UF,A     I3 @TIMECARD_LIB.TIMECARD(SCH_1):PAGE68
  C190    2      2 CAPACITOR-G104-0B103-EK,0.01UFA     I5 @TIMECARD_LIB.TIMECARD(SCH_1):PAGE68
   U20    5    GND ISL80101IRAJZ_DFN10-G222-10136A     I6 @TIMECARD_LIB.TIMECARD(SCH_1):PAGE68
   U20   11 THRM_PAD ISL80101IRAJZ_DFN10-G222-10136A     I6 @TIMECARD_LIB.TIMECARD(SCH_1):PAGE68
  C192    2      2 CAPACITOR-G104-0B103-EK,0.01UFA     I9 @TIMECARD_LIB.TIMECARD(SCH_1):PAGE68
  R186    1      1 RESISTOR-G155-03001-01,3KOHM,1%    I14 @TIMECARD_LIB.TIMECARD(SCH_1):PAGE68
  R189    1      1 RESISTOR-G155-03241-01,3.24KOHA    I16 @TIMECARD_LIB.TIMECARD(SCH_1):PAGE68
  C185    2      2 CAPACITOR-G107-0F106-EM,10UF,2A    I27 @TIMECARD_LIB.TIMECARD(SCH_1):PAGE68
  C188    2      2 CAPACITOR-G105-0B104-EK,0.1UF,A    I35 @TIMECARD_LIB.TIMECARD(SCH_1):PAGE68
  R174    2      2 RESISTOR-G155-11002-01,10KOHM,A    I44 @TIMECARD_LIB.TIMECARD(SCH_1):PAGE68
  C187    2      2 CAPACITOR-G105-0B104-EK,0.1UF,A    I46 @TIMECARD_LIB.TIMECARD(SCH_1):PAGE68
  C186    2      2 CAPACITOR-G107-0F106-EM,10UF,2A    I47 @TIMECARD_LIB.TIMECARD(SCH_1):PAGE68
  C191    2      2 CAPACITOR-G104-0B103-EK,0.01UFA    I49 @TIMECARD_LIB.TIMECARD(SCH_1):PAGE68
  C189    2      2 CAPACITOR-G105-0B104-EK,0.1UF,A    I51 @TIMECARD_LIB.TIMECARD(SCH_1):PAGE68
   U21    5    GND ISL80101IRAJZ_DFN10-G222-10136A    I52 @TIMECARD_LIB.TIMECARD(SCH_1):PAGE68
   U21   11 THRM_PAD ISL80101IRAJZ_DFN10-G222-10136A    I52 @TIMECARD_LIB.TIMECARD(SCH_1):PAGE68
  C194    2      2 CAPACITOR-G107-0F106-EM,10UF,2A    I60 @TIMECARD_LIB.TIMECARD(SCH_1):PAGE68
  C196    2      2 CAPACITOR-G105-0B104-EK,0.1UF,A    I61 @TIMECARD_LIB.TIMECARD(SCH_1):PAGE68
  C193    2      2 CAPACITOR-G104-0B103-EK,0.01UFA    I71 @TIMECARD_LIB.TIMECARD(SCH_1):PAGE68
  R188    1      1 RESISTOR-G155-03241-01,3.24KOHA    I79 @TIMECARD_LIB.TIMECARD(SCH_1):PAGE68
  R190    1      1 RESISTOR-G155-03241-01,3.24KOHA    I80 @TIMECARD_LIB.TIMECARD(SCH_1):PAGE68
  C195    2      2 CAPACITOR-G107-0F106-EM,10UF,2A    I81 @TIMECARD_LIB.TIMECARD(SCH_1):PAGE68
  C197    2      2 CAPACITOR-G105-0B104-EK,0.1UF,A    I83 @TIMECARD_LIB.TIMECARD(SCH_1):PAGE68
  C180    2      2 CAPACITOR-G107-0F226-CM,22UF,2A    I93 @TIMECARD_LIB.TIMECARD(SCH_1):PAGE68
  C182    2      2 CAPACITOR-G105-0B104-EK,0.1UF,A    I94 @TIMECARD_LIB.TIMECARD(SCH_1):PAGE68
  C181    2      2 CAPACITOR-G107-0F226-CM,22UF,2A    I97 @TIMECARD_LIB.TIMECARD(SCH_1):PAGE68
  C183    2      2 CAPACITOR-G105-0B104-EK,0.1UF,A    I98 @TIMECARD_LIB.TIMECARD(SCH_1):PAGE68
   U24   N9  DXN_0 XC7A200T_2FBG484C_FBG484-G240-A   I232 @TIMECARD_LIB.TIMECARD(SCH_1):PAGE127
   U24  N10  DXP_0 XC7A200T_2FBG484C_FBG484-G240-A   I232 @TIMECARD_LIB.TIMECARD(SCH_1):PAGE127
   U24   M9   VN_0 XC7A200T_2FBG484C_FBG484-G240-A   I232 @TIMECARD_LIB.TIMECARD(SCH_1):PAGE127
   U24  L10   VP_0 XC7A200T_2FBG484C_FBG484-G240-A   I232 @TIMECARD_LIB.TIMECARD(SCH_1):PAGE127
   U24   L9 VREFN_0 XC7A200T_2FBG484C_FBG484-G240-A   I232 @TIMECARD_LIB.TIMECARD(SCH_1):PAGE127
   U24  M10 VREFP_0 XC7A200T_2FBG484C_FBG484-G240-A   I232 @TIMECARD_LIB.TIMECARD(SCH_1):PAGE127
  R216    2      2 RESISTOR-G155-11001-01,1KOHM,1%   I391 @TIMECARD_LIB.TIMECARD(SCH_1):PAGE127
  R220    2      2 RESISTOR-G155-11001-01,1KOHM,1%   I393 @TIMECARD_LIB.TIMECARD(SCH_1):PAGE127
  R214    2      2 RESISTOR-G155-11001-01,1KOHM,1%   I397 @TIMECARD_LIB.TIMECARD(SCH_1):PAGE127
  R222    2      2 RESISTOR-G155-11000-01,100OHM,A   I405 @TIMECARD_LIB.TIMECARD(SCH_1):PAGE127
  R218    2      2 RESISTOR-G155-11000-01,100OHM,A   I406 @TIMECARD_LIB.TIMECARD(SCH_1):PAGE127
  R212    2      2 RESISTOR-G155-11000-01,100OHM,A   I407 @TIMECARD_LIB.TIMECARD(SCH_1):PAGE127
   U24  A11  GND_1 XC7A200T_2FBG484C_FBG484-G240-A   I138 @TIMECARD_LIB.TIMECARD(SCH_1):PAGE164
   U24  A12  GND_2 XC7A200T_2FBG484C_FBG484-G240-A   I138 @TIMECARD_LIB.TIMECARD(SCH_1):PAGE164
   U24   A2  GND_3 XC7A200T_2FBG484C_FBG484-G240-A   I138 @TIMECARD_LIB.TIMECARD(SCH_1):PAGE164
   U24  A22  GND_4 XC7A200T_2FBG484C_FBG484-G240-A   I138 @TIMECARD_LIB.TIMECARD(SCH_1):PAGE164
   U24   A3  GND_5 XC7A200T_2FBG484C_FBG484-G240-A   I138 @TIMECARD_LIB.TIMECARD(SCH_1):PAGE164
   U24   A5  GND_6 XC7A200T_2FBG484C_FBG484-G240-A   I138 @TIMECARD_LIB.TIMECARD(SCH_1):PAGE164
   U24   A7  GND_7 XC7A200T_2FBG484C_FBG484-G240-A   I138 @TIMECARD_LIB.TIMECARD(SCH_1):PAGE164
   U24   A9  GND_8 XC7A200T_2FBG484C_FBG484-G240-A   I138 @TIMECARD_LIB.TIMECARD(SCH_1):PAGE164
   U24 AA12  GND_9 XC7A200T_2FBG484C_FBG484-G240-A   I138 @TIMECARD_LIB.TIMECARD(SCH_1):PAGE164
   U24  AA2 GND_10 XC7A200T_2FBG484C_FBG484-G240-A   I138 @TIMECARD_LIB.TIMECARD(SCH_1):PAGE164
   U24 AA22 GND_11 XC7A200T_2FBG484C_FBG484-G240-A   I138 @TIMECARD_LIB.TIMECARD(SCH_1):PAGE164
   U24 AB19 GND_12 XC7A200T_2FBG484C_FBG484-G240-A   I138 @TIMECARD_LIB.TIMECARD(SCH_1):PAGE164
   U24  AB9 GND_13 XC7A200T_2FBG484C_FBG484-G240-A   I138 @TIMECARD_LIB.TIMECARD(SCH_1):PAGE164
   U24  B12 GND_14 XC7A200T_2FBG484C_FBG484-G240-A   I138 @TIMECARD_LIB.TIMECARD(SCH_1):PAGE164
   U24  B19 GND_15 XC7A200T_2FBG484C_FBG484-G240-A   I138 @TIMECARD_LIB.TIMECARD(SCH_1):PAGE164
   U24   B3 GND_16 XC7A200T_2FBG484C_FBG484-G240-A   I138 @TIMECARD_LIB.TIMECARD(SCH_1):PAGE164
   U24  C10 GND_17 XC7A200T_2FBG484C_FBG484-G240-A   I138 @TIMECARD_LIB.TIMECARD(SCH_1):PAGE164
   U24  C12 GND_18 XC7A200T_2FBG484C_FBG484-G240-A   I138 @TIMECARD_LIB.TIMECARD(SCH_1):PAGE164
   U24  C16 GND_19 XC7A200T_2FBG484C_FBG484-G240-A   I138 @TIMECARD_LIB.TIMECARD(SCH_1):PAGE164
   U24   C3 GND_20 XC7A200T_2FBG484C_FBG484-G240-A   I138 @TIMECARD_LIB.TIMECARD(SCH_1):PAGE164
   U24   C6 GND_21 XC7A200T_2FBG484C_FBG484-G240-A   I138 @TIMECARD_LIB.TIMECARD(SCH_1):PAGE164
   U24  D12 GND_22 XC7A200T_2FBG484C_FBG484-G240-A   I138 @TIMECARD_LIB.TIMECARD(SCH_1):PAGE164
   U24  D13 GND_23 XC7A200T_2FBG484C_FBG484-G240-A   I138 @TIMECARD_LIB.TIMECARD(SCH_1):PAGE164
   U24   D3 GND_24 XC7A200T_2FBG484C_FBG484-G240-A   I138 @TIMECARD_LIB.TIMECARD(SCH_1):PAGE164
   U24   D4 GND_25 XC7A200T_2FBG484C_FBG484-G240-A   I138 @TIMECARD_LIB.TIMECARD(SCH_1):PAGE164
   U24   D8 GND_26 XC7A200T_2FBG484C_FBG484-G240-A   I138 @TIMECARD_LIB.TIMECARD(SCH_1):PAGE164
   U24  E11 GND_27 XC7A200T_2FBG484C_FBG484-G240-A   I138 @TIMECARD_LIB.TIMECARD(SCH_1):PAGE164
   U24  E20 GND_28 XC7A200T_2FBG484C_FBG484-G240-A   I138 @TIMECARD_LIB.TIMECARD(SCH_1):PAGE164
   U24   E4 GND_29 XC7A200T_2FBG484C_FBG484-G240-A   I138 @TIMECARD_LIB.TIMECARD(SCH_1):PAGE164
   U24   E5 GND_30 XC7A200T_2FBG484C_FBG484-G240-A   I138 @TIMECARD_LIB.TIMECARD(SCH_1):PAGE164
   U24   E7 GND_31 XC7A200T_2FBG484C_FBG484-G240-A   I138 @TIMECARD_LIB.TIMECARD(SCH_1):PAGE164
   U24   E9 GND_32 XC7A200T_2FBG484C_FBG484-G240-A   I138 @TIMECARD_LIB.TIMECARD(SCH_1):PAGE164
   U24  F11 GND_33 XC7A200T_2FBG484C_FBG484-G240-A   I138 @TIMECARD_LIB.TIMECARD(SCH_1):PAGE164
   U24  F17 GND_34 XC7A200T_2FBG484C_FBG484-G240-A   I138 @TIMECARD_LIB.TIMECARD(SCH_1):PAGE164
   U24   F5 GND_35 XC7A200T_2FBG484C_FBG484-G240-A   I138 @TIMECARD_LIB.TIMECARD(SCH_1):PAGE164
   U24  G10 GND_36 XC7A200T_2FBG484C_FBG484-G240-A   I138 @TIMECARD_LIB.TIMECARD(SCH_1):PAGE164
   U24  G12 GND_37 XC7A200T_2FBG484C_FBG484-G240-A   I138 @TIMECARD_LIB.TIMECARD(SCH_1):PAGE164
   U24  G14 GND_38 XC7A200T_2FBG484C_FBG484-G240-A   I138 @TIMECARD_LIB.TIMECARD(SCH_1):PAGE164
   U24   G5 GND_39 XC7A200T_2FBG484C_FBG484-G240-A   I138 @TIMECARD_LIB.TIMECARD(SCH_1):PAGE164
   U24   G6 GND_40 XC7A200T_2FBG484C_FBG484-G240-A   I138 @TIMECARD_LIB.TIMECARD(SCH_1):PAGE164
   U24   G7 GND_41 XC7A200T_2FBG484C_FBG484-G240-A   I138 @TIMECARD_LIB.TIMECARD(SCH_1):PAGE164
   U24   G8 GND_42 XC7A200T_2FBG484C_FBG484-G240-A   I138 @TIMECARD_LIB.TIMECARD(SCH_1):PAGE164
   U24   G9 GND_43 XC7A200T_2FBG484C_FBG484-G240-A   I138 @TIMECARD_LIB.TIMECARD(SCH_1):PAGE164
   U24   H1 GND_44 XC7A200T_2FBG484C_FBG484-G240-A   I138 @TIMECARD_LIB.TIMECARD(SCH_1):PAGE164
   U24  H11 GND_45 XC7A200T_2FBG484C_FBG484-G240-A   I138 @TIMECARD_LIB.TIMECARD(SCH_1):PAGE164
   U24  H21 GND_46 XC7A200T_2FBG484C_FBG484-G240-A   I138 @TIMECARD_LIB.TIMECARD(SCH_1):PAGE164
   U24   H7 GND_47 XC7A200T_2FBG484C_FBG484-G240-A   I138 @TIMECARD_LIB.TIMECARD(SCH_1):PAGE164
   U24   H9 GND_48 XC7A200T_2FBG484C_FBG484-G240-A   I138 @TIMECARD_LIB.TIMECARD(SCH_1):PAGE164
   U24  J10 GND_49 XC7A200T_2FBG484C_FBG484-G240-A   I138 @TIMECARD_LIB.TIMECARD(SCH_1):PAGE164
   U24  J12 GND_50 XC7A200T_2FBG484C_FBG484-G240-A   I138 @TIMECARD_LIB.TIMECARD(SCH_1):PAGE164
   U24  J18 GND_51 XC7A200T_2FBG484C_FBG484-G240-A   I138 @TIMECARD_LIB.TIMECARD(SCH_1):PAGE164
   U24   J8 GND_52 XC7A200T_2FBG484C_FBG484-G240-A   I138 @TIMECARD_LIB.TIMECARD(SCH_1):PAGE164
   U24  K11 GND_53 XC7A200T_2FBG484C_FBG484-G240-A   I138 @TIMECARD_LIB.TIMECARD(SCH_1):PAGE164
   U24  K15 GND_54 XC7A200T_2FBG484C_FBG484-G240-A   I138 @TIMECARD_LIB.TIMECARD(SCH_1):PAGE164
   U24   K5 GND_55 XC7A200T_2FBG484C_FBG484-G240-A   I138 @TIMECARD_LIB.TIMECARD(SCH_1):PAGE164
   U24   K7 GND_56 XC7A200T_2FBG484C_FBG484-G240-A   I138 @TIMECARD_LIB.TIMECARD(SCH_1):PAGE164
   U24   L2 GND_57 XC7A200T_2FBG484C_FBG484-G240-A   I138 @TIMECARD_LIB.TIMECARD(SCH_1):PAGE164
   U24  L22 GND_58 XC7A200T_2FBG484C_FBG484-G240-A   I138 @TIMECARD_LIB.TIMECARD(SCH_1):PAGE164
   U24   L8 GND_59 XC7A200T_2FBG484C_FBG484-G240-A   I138 @TIMECARD_LIB.TIMECARD(SCH_1):PAGE164
   U24  M11 GND_60 XC7A200T_2FBG484C_FBG484-G240-A   I138 @TIMECARD_LIB.TIMECARD(SCH_1):PAGE164
   U24  M19 GND_61 XC7A200T_2FBG484C_FBG484-G240-A   I138 @TIMECARD_LIB.TIMECARD(SCH_1):PAGE164
   U24   M7 GND_62 XC7A200T_2FBG484C_FBG484-G240-A   I138 @TIMECARD_LIB.TIMECARD(SCH_1):PAGE164
   U24  N16 GND_63 XC7A200T_2FBG484C_FBG484-G240-A   I138 @TIMECARD_LIB.TIMECARD(SCH_1):PAGE164
   U24   N6 GND_64 XC7A200T_2FBG484C_FBG484-G240-A   I138 @TIMECARD_LIB.TIMECARD(SCH_1):PAGE164
   U24   N8 GND_65 XC7A200T_2FBG484C_FBG484-G240-A   I138 @TIMECARD_LIB.TIMECARD(SCH_1):PAGE164
   U24  P11 GND_66 XC7A200T_2FBG484C_FBG484-G240-A   I138 @TIMECARD_LIB.TIMECARD(SCH_1):PAGE164
   U24  P13 GND_67 XC7A200T_2FBG484C_FBG484-G240-A   I138 @TIMECARD_LIB.TIMECARD(SCH_1):PAGE164
   U24   P3 GND_68 XC7A200T_2FBG484C_FBG484-G240-A   I138 @TIMECARD_LIB.TIMECARD(SCH_1):PAGE164
   U24   P7 GND_69 XC7A200T_2FBG484C_FBG484-G240-A   I138 @TIMECARD_LIB.TIMECARD(SCH_1):PAGE164
   U24   P9 GND_70 XC7A200T_2FBG484C_FBG484-G240-A   I138 @TIMECARD_LIB.TIMECARD(SCH_1):PAGE164
   U24  R10 GND_71 XC7A200T_2FBG484C_FBG484-G240-A   I138 @TIMECARD_LIB.TIMECARD(SCH_1):PAGE164
   U24  R12 GND_72 XC7A200T_2FBG484C_FBG484-G240-A   I138 @TIMECARD_LIB.TIMECARD(SCH_1):PAGE164
   U24  R20 GND_73 XC7A200T_2FBG484C_FBG484-G240-A   I138 @TIMECARD_LIB.TIMECARD(SCH_1):PAGE164
   U24   R8 GND_74 XC7A200T_2FBG484C_FBG484-G240-A   I138 @TIMECARD_LIB.TIMECARD(SCH_1):PAGE164
   U24  T11 GND_75 XC7A200T_2FBG484C_FBG484-G240-A   I138 @TIMECARD_LIB.TIMECARD(SCH_1):PAGE164
   U24  T17 GND_76 XC7A200T_2FBG484C_FBG484-G240-A   I138 @TIMECARD_LIB.TIMECARD(SCH_1):PAGE164
   U24   T7 GND_77 XC7A200T_2FBG484C_FBG484-G240-A   I138 @TIMECARD_LIB.TIMECARD(SCH_1):PAGE164
   U24   T9 GND_78 XC7A200T_2FBG484C_FBG484-G240-A   I138 @TIMECARD_LIB.TIMECARD(SCH_1):PAGE164
   U24  U14 GND_79 XC7A200T_2FBG484C_FBG484-G240-A   I138 @TIMECARD_LIB.TIMECARD(SCH_1):PAGE164
   U24   U4 GND_80 XC7A200T_2FBG484C_FBG484-G240-A   I138 @TIMECARD_LIB.TIMECARD(SCH_1):PAGE164
   U24   V1 GND_81 XC7A200T_2FBG484C_FBG484-G240-A   I138 @TIMECARD_LIB.TIMECARD(SCH_1):PAGE164
   U24  V11 GND_82 XC7A200T_2FBG484C_FBG484-G240-A   I138 @TIMECARD_LIB.TIMECARD(SCH_1):PAGE164
   U24  V21 GND_83 XC7A200T_2FBG484C_FBG484-G240-A   I138 @TIMECARD_LIB.TIMECARD(SCH_1):PAGE164
   U24  W18 GND_84 XC7A200T_2FBG484C_FBG484-G240-A   I138 @TIMECARD_LIB.TIMECARD(SCH_1):PAGE164
   U24   W8 GND_85 XC7A200T_2FBG484C_FBG484-G240-A   I138 @TIMECARD_LIB.TIMECARD(SCH_1):PAGE164
   U24  Y15 GND_86 XC7A200T_2FBG484C_FBG484-G240-A   I138 @TIMECARD_LIB.TIMECARD(SCH_1):PAGE164
   U24   Y5 GND_87 XC7A200T_2FBG484C_FBG484-G240-A   I138 @TIMECARD_LIB.TIMECARD(SCH_1):PAGE164
   U24   K9 GNDADC_0 XC7A200T_2FBG484C_FBG484-G240-A   I138 @TIMECARD_LIB.TIMECARD(SCH_1):PAGE164
  C176    2      2 CAPACITOR-G109-0G107-BM,100UF,A   I172 @TIMECARD_LIB.TIMECARD(SCH_1):PAGE164
  C175    2      2 CAPACITOR-G109-0G107-BM,100UF,A   I173 @TIMECARD_LIB.TIMECARD(SCH_1):PAGE164
  C172    2      2 CAPACITOR-G109-0G107-BM,100UF,A   I174 @TIMECARD_LIB.TIMECARD(SCH_1):PAGE164
  C158    2      2 CAPACITOR-G107-0F226-CM,22UF,2A   I176 @TIMECARD_LIB.TIMECARD(SCH_1):PAGE164
  C120    2      2 CAPACITOR-G105-0F475-BM,4.7UF,A   I177 @TIMECARD_LIB.TIMECARD(SCH_1):PAGE164
  C174    2      2 CAPACITOR-G109-0G107-BM,100UF,A   I178 @TIMECARD_LIB.TIMECARD(SCH_1):PAGE164
  C201    2      2 CAPACITOR-G105-0B104-CK,0.1UF,A   I182 @TIMECARD_LIB.TIMECARD(SCH_1):PAGE164
  C207    2      2 CAPACITOR-G105-0B104-CK,0.1UF,A   I183 @TIMECARD_LIB.TIMECARD(SCH_1):PAGE164
  C214    2      2 CAPACITOR-G105-0B104-CK,0.1UF,A   I184 @TIMECARD_LIB.TIMECARD(SCH_1):PAGE164
  C222    2      2 CAPACITOR-G105-0B104-CK,0.1UF,A   I185 @TIMECARD_LIB.TIMECARD(SCH_1):PAGE164
  C109    2      2 CAPACITOR-G105-0B104-CK,0.1UF,A   I186 @TIMECARD_LIB.TIMECARD(SCH_1):PAGE164
  C114    2      2 CAPACITOR-G105-0B104-CK,0.1UF,A   I187 @TIMECARD_LIB.TIMECARD(SCH_1):PAGE164
  C121    2      2 CAPACITOR-G105-0B104-CK,0.1UF,A   I188 @TIMECARD_LIB.TIMECARD(SCH_1):PAGE164
  C129    2      2 CAPACITOR-G105-0B104-CK,0.1UF,A   I189 @TIMECARD_LIB.TIMECARD(SCH_1):PAGE164
  C133    2      2 CAPACITOR-G105-0B104-CK,0.1UF,A   I190 @TIMECARD_LIB.TIMECARD(SCH_1):PAGE164
  C141    2      2 CAPACITOR-G105-0B104-CK,0.1UF,A   I191 @TIMECARD_LIB.TIMECARD(SCH_1):PAGE164
  C147    2      2 CAPACITOR-G105-0B104-CK,0.1UF,A   I192 @TIMECARD_LIB.TIMECARD(SCH_1):PAGE164
  C152    2      2 CAPACITOR-G105-0B104-CK,0.1UF,A   I193 @TIMECARD_LIB.TIMECARD(SCH_1):PAGE164
  C156    2      2 CAPACITOR-G105-0B104-CK,0.1UF,A   I194 @TIMECARD_LIB.TIMECARD(SCH_1):PAGE164
  C161    2      2 CAPACITOR-G105-0B104-CK,0.1UF,A   I195 @TIMECARD_LIB.TIMECARD(SCH_1):PAGE164
  C166    2      2 CAPACITOR-G105-0B104-CK,0.1UF,A   I196 @TIMECARD_LIB.TIMECARD(SCH_1):PAGE164
  C169    2      2 CAPACITOR-G105-0B104-CK,0.1UF,A   I197 @TIMECARD_LIB.TIMECARD(SCH_1):PAGE164
  C171    2      2 CAPACITOR-G105-0B104-CK,0.1UF,A   I198 @TIMECARD_LIB.TIMECARD(SCH_1):PAGE164
  C200    2      2 CAPACITOR-G105-0B104-CK,0.1UF,A   I199 @TIMECARD_LIB.TIMECARD(SCH_1):PAGE164
  C206    2      2 CAPACITOR-G105-0B104-CK,0.1UF,A   I200 @TIMECARD_LIB.TIMECARD(SCH_1):PAGE164
  C212    2      2 CAPACITOR-G105-0B104-CK,0.1UF,A   I201 @TIMECARD_LIB.TIMECARD(SCH_1):PAGE164
  C219    2      2 CAPACITOR-G105-0B104-CK,0.1UF,A   I202 @TIMECARD_LIB.TIMECARD(SCH_1):PAGE164
  C106    2      2 CAPACITOR-G105-0B104-CK,0.1UF,A   I203 @TIMECARD_LIB.TIMECARD(SCH_1):PAGE164
  C113    2      2 CAPACITOR-G105-0B104-CK,0.1UF,A   I204 @TIMECARD_LIB.TIMECARD(SCH_1):PAGE164
  C202    2      2 CAPACITOR-G105-0B104-CK,0.1UF,A   I205 @TIMECARD_LIB.TIMECARD(SCH_1):PAGE164
  C210    2      2 CAPACITOR-G105-0B104-CK,0.1UF,A   I206 @TIMECARD_LIB.TIMECARD(SCH_1):PAGE164
  C215    2      2 CAPACITOR-G105-0B104-CK,0.1UF,A   I207 @TIMECARD_LIB.TIMECARD(SCH_1):PAGE164
  C103    2      2 CAPACITOR-G105-0B104-CK,0.1UF,A   I208 @TIMECARD_LIB.TIMECARD(SCH_1):PAGE164
  C112    2      2 CAPACITOR-G105-0B104-CK,0.1UF,A   I209 @TIMECARD_LIB.TIMECARD(SCH_1):PAGE164
  C119    2      2 CAPACITOR-G105-0B104-CK,0.1UF,A   I210 @TIMECARD_LIB.TIMECARD(SCH_1):PAGE164
  C126    2      2 CAPACITOR-G105-0B104-CK,0.1UF,A   I211 @TIMECARD_LIB.TIMECARD(SCH_1):PAGE164
  C132    2      2 CAPACITOR-G105-0B104-CK,0.1UF,A   I212 @TIMECARD_LIB.TIMECARD(SCH_1):PAGE164
  C139    2      2 CAPACITOR-G105-0B104-CK,0.1UF,A   I213 @TIMECARD_LIB.TIMECARD(SCH_1):PAGE164
  C144    2      2 CAPACITOR-G105-0B104-CK,0.1UF,A   I214 @TIMECARD_LIB.TIMECARD(SCH_1):PAGE164
  C149    2      2 CAPACITOR-G105-0B104-CK,0.1UF,A   I215 @TIMECARD_LIB.TIMECARD(SCH_1):PAGE164
  C203    2      2 CAPACITOR-G105-0B104-CK,0.1UF,A   I216 @TIMECARD_LIB.TIMECARD(SCH_1):PAGE164
  C211    2      2 CAPACITOR-G105-0B104-CK,0.1UF,A   I217 @TIMECARD_LIB.TIMECARD(SCH_1):PAGE164
  C216    2      2 CAPACITOR-G105-0B104-CK,0.1UF,A   I218 @TIMECARD_LIB.TIMECARD(SCH_1):PAGE164
  C221    2      2 CAPACITOR-G105-0B104-CK,0.1UF,A   I219 @TIMECARD_LIB.TIMECARD(SCH_1):PAGE164
  C107    2      2 CAPACITOR-G105-0B104-CK,0.1UF,A   I220 @TIMECARD_LIB.TIMECARD(SCH_1):PAGE164
  C115    2      2 CAPACITOR-G105-0B104-CK,0.1UF,A   I221 @TIMECARD_LIB.TIMECARD(SCH_1):PAGE164
  C223    2      2 CAPACITOR-G105-0B104-CK,0.1UF,A   I222 @TIMECARD_LIB.TIMECARD(SCH_1):PAGE164
  C130    2      2 CAPACITOR-G105-0B104-CK,0.1UF,A   I223 @TIMECARD_LIB.TIMECARD(SCH_1):PAGE164
  C134    2      2 CAPACITOR-G105-0B104-CK,0.1UF,A   I224 @TIMECARD_LIB.TIMECARD(SCH_1):PAGE164
  C140    2      2 CAPACITOR-G105-0B104-CK,0.1UF,A   I225 @TIMECARD_LIB.TIMECARD(SCH_1):PAGE164
  C145    2      2 CAPACITOR-G105-0B104-CK,0.1UF,A   I226 @TIMECARD_LIB.TIMECARD(SCH_1):PAGE164
  C153    2      2 CAPACITOR-G105-0B104-CK,0.1UF,A   I227 @TIMECARD_LIB.TIMECARD(SCH_1):PAGE164
  C157    2      2 CAPACITOR-G105-0B104-CK,0.1UF,A   I228 @TIMECARD_LIB.TIMECARD(SCH_1):PAGE164
  C162    2      2 CAPACITOR-G105-0B104-CK,0.1UF,A   I229 @TIMECARD_LIB.TIMECARD(SCH_1):PAGE164
  C165    2      2 CAPACITOR-G105-0B104-CK,0.1UF,A   I230 @TIMECARD_LIB.TIMECARD(SCH_1):PAGE164
  C204    2      2 CAPACITOR-G105-0B104-CK,0.1UF,A   I231 @TIMECARD_LIB.TIMECARD(SCH_1):PAGE164
  C208    2      2 CAPACITOR-G105-0B104-CK,0.1UF,A   I232 @TIMECARD_LIB.TIMECARD(SCH_1):PAGE164
  C213    2      2 CAPACITOR-G105-0B104-CK,0.1UF,A   I233 @TIMECARD_LIB.TIMECARD(SCH_1):PAGE164
  C220    2      2 CAPACITOR-G105-0B104-CK,0.1UF,A   I234 @TIMECARD_LIB.TIMECARD(SCH_1):PAGE164
  C108    2      2 CAPACITOR-G105-0B104-CK,0.1UF,A   I235 @TIMECARD_LIB.TIMECARD(SCH_1):PAGE164
  C116    2      2 CAPACITOR-G105-0B104-CK,0.1UF,A   I236 @TIMECARD_LIB.TIMECARD(SCH_1):PAGE164
  C122    2      2 CAPACITOR-G105-0B104-CK,0.1UF,A   I237 @TIMECARD_LIB.TIMECARD(SCH_1):PAGE164
  C127    2      2 CAPACITOR-G105-0B104-CK,0.1UF,A   I238 @TIMECARD_LIB.TIMECARD(SCH_1):PAGE164
  C135    2      2 CAPACITOR-G105-0B104-CK,0.1UF,A   I239 @TIMECARD_LIB.TIMECARD(SCH_1):PAGE164
  C142    2      2 CAPACITOR-G105-0B104-CK,0.1UF,A   I240 @TIMECARD_LIB.TIMECARD(SCH_1):PAGE164
  C146    2      2 CAPACITOR-G105-0B104-CK,0.1UF,A   I241 @TIMECARD_LIB.TIMECARD(SCH_1):PAGE164
  C151    2      2 CAPACITOR-G105-0B104-CK,0.1UF,A   I242 @TIMECARD_LIB.TIMECARD(SCH_1):PAGE164
  C128    2      2 CAPACITOR-G105-0F475-BM,4.7UF,A   I243 @TIMECARD_LIB.TIMECARD(SCH_1):PAGE164
  C160    2      2 CAPACITOR-G105-0F475-BM,4.7UF,A   I245 @TIMECARD_LIB.TIMECARD(SCH_1):PAGE164
  C117    2      2 CAPACITOR-G105-0F475-BM,4.7UF,A   I246 @TIMECARD_LIB.TIMECARD(SCH_1):PAGE164
  C131    2      2 CAPACITOR-G105-0F475-BM,4.7UF,A   I248 @TIMECARD_LIB.TIMECARD(SCH_1):PAGE164
  C136    2      2 CAPACITOR-G105-0B104-CK,0.1UF,A   I249 @TIMECARD_LIB.TIMECARD(SCH_1):PAGE164
  C148    2      2 CAPACITOR-G105-0B104-CK,0.1UF,A   I250 @TIMECARD_LIB.TIMECARD(SCH_1):PAGE164
  C218    2      2 CAPACITOR-G105-0B104-CK,0.1UF,A   I251 @TIMECARD_LIB.TIMECARD(SCH_1):PAGE164
  C105    2      2 CAPACITOR-G105-0B104-CK,0.1UF,A   I252 @TIMECARD_LIB.TIMECARD(SCH_1):PAGE164
  C111    2      2 CAPACITOR-G105-0B104-CK,0.1UF,A   I253 @TIMECARD_LIB.TIMECARD(SCH_1):PAGE164
  C118    2      2 CAPACITOR-G105-0B104-CK,0.1UF,A   I254 @TIMECARD_LIB.TIMECARD(SCH_1):PAGE164
  C124    2      2 CAPACITOR-G105-0B104-CK,0.1UF,A   I255 @TIMECARD_LIB.TIMECARD(SCH_1):PAGE164
  C110    2      2 CAPACITOR-G105-0B104-CK,0.1UF,A   I256 @TIMECARD_LIB.TIMECARD(SCH_1):PAGE164
  C104    2      2 CAPACITOR-G105-0B104-CK,0.1UF,A   I257 @TIMECARD_LIB.TIMECARD(SCH_1):PAGE164
  C217    2      2 CAPACITOR-G105-0B104-CK,0.1UF,A   I258 @TIMECARD_LIB.TIMECARD(SCH_1):PAGE164
  C209    2      2 CAPACITOR-G105-0B104-CK,0.1UF,A   I259 @TIMECARD_LIB.TIMECARD(SCH_1):PAGE164
  C205    2      2 CAPACITOR-G105-0B104-CK,0.1UF,A   I260 @TIMECARD_LIB.TIMECARD(SCH_1):PAGE164
  C125    2      2 CAPACITOR-G107-0F476-AM,47UF,2A   I264 @TIMECARD_LIB.TIMECARD(SCH_1):PAGE164
  C143    2      2 CAPACITOR-G107-0F476-AM,47UF,2A   I265 @TIMECARD_LIB.TIMECARD(SCH_1):PAGE164
  C155    2      2 CAPACITOR-G107-0F476-AM,47UF,2A   I266 @TIMECARD_LIB.TIMECARD(SCH_1):PAGE164
  C168    2      2 CAPACITOR-G107-0F226-CM,22UF,2A   I267 @TIMECARD_LIB.TIMECARD(SCH_1):PAGE164
  C164    2      2 CAPACITOR-G107-0F226-CM,22UF,2A   I268 @TIMECARD_LIB.TIMECARD(SCH_1):PAGE164
  C154    2      2 CAPACITOR-G105-0F475-BM,4.7UF,A   I270 @TIMECARD_LIB.TIMECARD(SCH_1):PAGE164
  C159    2      2 CAPACITOR-G105-0F475-BM,4.7UF,A   I271 @TIMECARD_LIB.TIMECARD(SCH_1):PAGE164
  C163    2      2 CAPACITOR-G105-0F475-BM,4.7UF,A   I272 @TIMECARD_LIB.TIMECARD(SCH_1):PAGE164
  C167    2      2 CAPACITOR-G105-0F475-BM,4.7UF,A   I273 @TIMECARD_LIB.TIMECARD(SCH_1):PAGE164
  C179    2      2 CAPACITOR-G107-0F476-AM,47UF,2A   I274 @TIMECARD_LIB.TIMECARD(SCH_1):PAGE164
  C138    2      2 CAPACITOR-G105-0F475-BM,4.7UF,A   I275 @TIMECARD_LIB.TIMECARD(SCH_1):PAGE164
  C150    2      2 CAPACITOR-G105-0B104-CK,0.1UF,A   I276 @TIMECARD_LIB.TIMECARD(SCH_1):PAGE164
  C177    2      2 CAPACITOR-G109-0G107-BM,100UF,A   I277 @TIMECARD_LIB.TIMECARD(SCH_1):PAGE164
  C173    2      2 CAPACITOR-G107-0F476-AM,47UF,2A   I280 @TIMECARD_LIB.TIMECARD(SCH_1):PAGE164
  C137    2      2 CAPACITOR-G107-0F476-AM,47UF,2A   I281 @TIMECARD_LIB.TIMECARD(SCH_1):PAGE164
  C170    2      2 CAPACITOR-G105-0F475-BM,4.7UF,A   I282 @TIMECARD_LIB.TIMECARD(SCH_1):PAGE164
  C178    2      2 CAPACITOR-G105-0B104-CK,0.1UF,A   I283 @TIMECARD_LIB.TIMECARD(SCH_1):PAGE164
  R237    2      2 RESISTOR-G155-11002-01,10KOHM,A    I56 @TIMECARD_LIB.TIMECARD(SCH_1):PAGE515
  C232    2      2 CAPACITOR-G107-0F226-CM,22UF,2A    I61 @TIMECARD_LIB.TIMECARD(SCH_1):PAGE515
  C233    2      2 CAPACITOR-G105-0B104-CK,0.1UF,A    I63 @TIMECARD_LIB.TIMECARD(SCH_1):PAGE515
  C237    2      2 CAPACITOR-G105-0B104-CK,0.1UF,A    I64 @TIMECARD_LIB.TIMECARD(SCH_1):PAGE515
  C236    2      2 CAPACITOR-G105-0B104-EK,0.1UF,A    I66 @TIMECARD_LIB.TIMECARD(SCH_1):PAGE515
  C240    2      2 CAPACITOR-G107-0F226-CM,22UF,2A    I71 @TIMECARD_LIB.TIMECARD(SCH_1):PAGE515
  C241    2      2 CAPACITOR-G107-0F226-CM,22UF,2A    I72 @TIMECARD_LIB.TIMECARD(SCH_1):PAGE515
  C243    2      2 CAPACITOR-G107-0F226-CM,22UF,2A    I74 @TIMECARD_LIB.TIMECARD(SCH_1):PAGE515
   U22    4    GND NCP45560IMNTWG_H_DFN12-G222-10A    I76 @TIMECARD_LIB.TIMECARD(SCH_1):PAGE515
  C235    2      2 CAPACITOR-G105-0B104-CK,0.1UF,A    I80 @TIMECARD_LIB.TIMECARD(SCH_1):PAGE515
  C238    2      2 CAPACITOR-G107-0F226-CM,22UF,2A    I81 @TIMECARD_LIB.TIMECARD(SCH_1):PAGE515
  C229    2      2 CAPACITOR-G105-0B104-CK,0.1UF,A    I87 @TIMECARD_LIB.TIMECARD(SCH_1):PAGE515
  R227    2      2 RESISTOR-G155-11002-01,10KOHM,A   I127 @TIMECARD_LIB.TIMECARD(SCH_1):PAGE515
  C227    2      2 CAPACITOR-G105-0B104-EK,0.1UF,A   I128 @TIMECARD_LIB.TIMECARD(SCH_1):PAGE515
  C228    2      2 CAPACITOR-G107-0F106-EM,10UF,2A   I130 @TIMECARD_LIB.TIMECARD(SCH_1):PAGE515
  C231    2      2 CAPACITOR-G104-0B103-EK,0.01UFA   I132 @TIMECARD_LIB.TIMECARD(SCH_1):PAGE515
  C230    2      2 CAPACITOR-G105-0B104-EK,0.1UF,A   I134 @TIMECARD_LIB.TIMECARD(SCH_1):PAGE515
  C234    2      2 CAPACITOR-G104-0B103-EK,0.01UFA   I138 @TIMECARD_LIB.TIMECARD(SCH_1):PAGE515
  R232    1      1 RESISTOR-G155-02101-01,2.1KOHMA   I143 @TIMECARD_LIB.TIMECARD(SCH_1):PAGE515
  R233    1      1 RESISTOR-G155-02101-01,2.1KOHMA   I145 @TIMECARD_LIB.TIMECARD(SCH_1):PAGE515
  C239    2      2 CAPACITOR-G107-0F106-EM,10UF,2A   I147 @TIMECARD_LIB.TIMECARD(SCH_1):PAGE515
  C242    2      2 CAPACITOR-G105-0B104-EK,0.1UF,A   I149 @TIMECARD_LIB.TIMECARD(SCH_1):PAGE515
   U25    5    GND ISL80101IRAJZ_DFN10-G222-10136A   I151 @TIMECARD_LIB.TIMECARD(SCH_1):PAGE515
   U25   11 THRM_PAD ISL80101IRAJZ_DFN10-G222-10136A   I151 @TIMECARD_LIB.TIMECARD(SCH_1):PAGE515
  C224    2      2 CAPACITOR-G107-0F226-CM,22UF,2A   I154 @TIMECARD_LIB.TIMECARD(SCH_1):PAGE515
  C226    2      2 CAPACITOR-G105-0B104-EK,0.1UF,A   I155 @TIMECARD_LIB.TIMECARD(SCH_1):PAGE515
    Y3    3    GND OSC6P_V2-A130-00003-AW   I144 @TIMECARD_LIB.TIMECARD(SCH_1):PAGE522
    Y4    3    GND OSC6P_V2-A130-00004-AW   I145 @TIMECARD_LIB.TIMECARD(SCH_1):PAGE522
  C248    2      2 CAPACITOR-G105-0B104-EK,0.1UF,A   I147 @TIMECARD_LIB.TIMECARD(SCH_1):PAGE522
  C246    2      2 CAPACITOR-G105-0C106-BM,10UF,2A   I151 @TIMECARD_LIB.TIMECARD(SCH_1):PAGE522
  C244    2      2 CAPACITOR-G105-0B104-EK,0.1UF,A   I152 @TIMECARD_LIB.TIMECARD(SCH_1):PAGE522
  C245    2      2 CAPACITOR-G105-0B104-EK,0.1UF,A   I153 @TIMECARD_LIB.TIMECARD(SCH_1):PAGE522
  C247    2      2 CAPACITOR-G105-0C106-BM,10UF,2A   I154 @TIMECARD_LIB.TIMECARD(SCH_1):PAGE522
  C249    2      2 CAPACITOR-G105-0B104-EK,0.1UF,A   I158 @TIMECARD_LIB.TIMECARD(SCH_1):PAGE522
  R239    2      2 RESISTOR-G155-11500-01,150OHM,A   I169 @TIMECARD_LIB.TIMECARD(SCH_1):PAGE522
  R241    2      2 RESISTOR-G155-11500-01,150OHM,A   I170 @TIMECARD_LIB.TIMECARD(SCH_1):PAGE522
  R240    2      2 RESISTOR-G155-11500-01,150OHM,A   I172 @TIMECARD_LIB.TIMECARD(SCH_1):PAGE522
  R242    2      2 RESISTOR-G155-11500-01,150OHM,A   I174 @TIMECARD_LIB.TIMECARD(SCH_1):PAGE522
  C256    2      2 CAPACITOR-G105-0B104-CK,0.1UF,A     I7 @TIMECARD_LIB.TIMECARD(SCH_1):PAGE523
   U26    3 PGND_1 TPS54824RNVR_VQFN18-G220-10657A    I11 @TIMECARD_LIB.TIMECARD(SCH_1):PAGE523
   U26    4 PGND_2 TPS54824RNVR_VQFN18-G220-10657A    I11 @TIMECARD_LIB.TIMECARD(SCH_1):PAGE523
   U26    5 PGND_3 TPS54824RNVR_VQFN18-G220-10657A    I11 @TIMECARD_LIB.TIMECARD(SCH_1):PAGE523
   U26    8 PGND_4 TPS54824RNVR_VQFN18-G220-10657A    I11 @TIMECARD_LIB.TIMECARD(SCH_1):PAGE523
   U26    9 PGND_5 TPS54824RNVR_VQFN18-G220-10657A    I11 @TIMECARD_LIB.TIMECARD(SCH_1):PAGE523
   U26   10 PGND_6 TPS54824RNVR_VQFN18-G220-10657A    I11 @TIMECARD_LIB.TIMECARD(SCH_1):PAGE523
  C257    2      2 CAPACITOR-G107-0F106-EM,10UF,2A    I13 @TIMECARD_LIB.TIMECARD(SCH_1):PAGE523
  C260    2      2 CAPACITOR-G107-0F106-EM,10UF,2A    I14 @TIMECARD_LIB.TIMECARD(SCH_1):PAGE523
  C261    2      2 CAPACITOR-G105-0B104-EK,0.1UF,A    I17 @TIMECARD_LIB.TIMECARD(SCH_1):PAGE523
  C262    2      2 CAPACITOR-G105-0B104-EK,0.1UF,A    I19 @TIMECARD_LIB.TIMECARD(SCH_1):PAGE523
  R253    2      2 RESISTOR-G157-12R20-01,2.2OHM,A    I26 @TIMECARD_LIB.TIMECARD(SCH_1):PAGE523
  C268    2      2 CAPACITOR-G105-0B104-CK,0.1UF,A    I33 @TIMECARD_LIB.TIMECARD(SCH_1):PAGE523
  C269    2      2 CAPACITOR-G107-0F476-AM,47UF,2A    I34 @TIMECARD_LIB.TIMECARD(SCH_1):PAGE523
  C270    2      2 CAPACITOR-G107-0F476-AM,47UF,2A    I35 @TIMECARD_LIB.TIMECARD(SCH_1):PAGE523
  C271    2      2 CAPACITOR-G107-0F476-AM,47UF,2A    I37 @TIMECARD_LIB.TIMECARD(SCH_1):PAGE523
   SP3    1      1 SOLDER_PREFORM-G380-10015-01    I39 @TIMECARD_LIB.TIMECARD(SCH_1):PAGE523
  C255    2      2 CAPACITOR-G105-0B104-EK,0.1UF,A    I46 @TIMECARD_LIB.TIMECARD(SCH_1):PAGE523
  C258    1      1 CAPACITOR-G104-0B103-EK,0.01UFA    I50 @TIMECARD_LIB.TIMECARD(SCH_1):PAGE523
  R246    2      2 RESISTOR-A155-05101-DL,5.1KOHMA    I51 @TIMECARD_LIB.TIMECARD(SCH_1):PAGE523
    P2    8      8 CONN_HDR_2X4_F_S_SMT-G200-1307A    I36 @TIMECARD_LIB.TIMECARD(SCH_1):PAGE11
   C81    2      2 CAPACITOR-G105-0B104-CK,0.1UF,A    I43 @TIMECARD_LIB.TIMECARD(SCH_1):PAGE11
  R270    1      1 RESISTOR-G155-14701-01,4.7KOHMA   I140 @TIMECARD_LIB.TIMECARD(SCH_1):PAGE161
  C272    2      2 CAPACITOR-G105-0B104-EK,0.1UF,A    I44 @TIMECARD_LIB.TIMECARD(SCH_1):PAGE11
  C273    2      2 CAPACITOR-G105-0B104-CK,0.1UF,A    I45 @TIMECARD_LIB.TIMECARD(SCH_1):PAGE11
  C280    2      2 CAPACITOR-G105-0C106-BM,10UF,2A    I23 @TIMECARD_LIB.TIMECARD(SCH_1):PAGE9
   C40    2      2 CAPACITOR-G105-0B104-EK,0.1UF,A    I18 @TIMECARD_LIB.TIMECARD(SCH_1):PAGE7
  C276    2      2 CAPACITOR-G105-0B104-EK,0.1UF,A    I16 @TIMECARD_LIB.TIMECARD(SCH_1):PAGE8
  C278    2      2 CAPACITOR-G105-0B104-EK,0.1UF,A    I19 @TIMECARD_LIB.TIMECARD(SCH_1):PAGE8
  C277    2      2 CAPACITOR-G105-0C106-BM,10UF,2A    I21 @TIMECARD_LIB.TIMECARD(SCH_1):PAGE8
  C279    2      2 CAPACITOR-G105-0B104-EK,0.1UF,A    I21 @TIMECARD_LIB.TIMECARD(SCH_1):PAGE9
  C281    2      2 CAPACITOR-G105-0B104-EK,0.1UF,A    I24 @TIMECARD_LIB.TIMECARD(SCH_1):PAGE9
  C275    2      2 CAPACITOR-G105-0B104-EK,0.1UF,A    I19 @TIMECARD_LIB.TIMECARD(SCH_1):PAGE7
  C274    2      2 CAPACITOR-G105-0C106-BM,10UF,2A    I23 @TIMECARD_LIB.TIMECARD(SCH_1):PAGE7
  R297    2      2 RESISTOR-G155-14701-01,4.7KOHMA    I39 @TIMECARD_LIB.TIMECARD(SCH_1):PAGE7
   U27    7      R SHT31A_DIS_B10KS_DFN8-A222-000A    I44 @TIMECARD_LIB.TIMECARD(SCH_1):PAGE7
   U27    9 THRM_PAD SHT31A_DIS_B10KS_DFN8-A222-000A    I44 @TIMECARD_LIB.TIMECARD(SCH_1):PAGE7
   U27    8    VSS SHT31A_DIS_B10KS_DFN8-A222-000A    I44 @TIMECARD_LIB.TIMECARD(SCH_1):PAGE7
   U28    8  GND_1 ICP_10100_LGA10-A222-00002-FB,A    I24 @TIMECARD_LIB.TIMECARD(SCH_1):PAGE8
   U28    9  GND_2 ICP_10100_LGA10-A222-00002-FB,A    I24 @TIMECARD_LIB.TIMECARD(SCH_1):PAGE8
   U29    2  GND_1 BNO080_LGA_28-A246-00002-FB,BNA    I29 @TIMECARD_LIB.TIMECARD(SCH_1):PAGE9
   U29   25  GND_2 BNO080_LGA_28-A246-00002-FB,BNA    I29 @TIMECARD_LIB.TIMECARD(SCH_1):PAGE9
  R301    2      2 RESISTOR-G155-14701-01,4.7KOHMA    I43 @TIMECARD_LIB.TIMECARD(SCH_1):PAGE9
  R307    2      2 RESISTOR-G155-11001-01,1KOHM,1%    I47 @TIMECARD_LIB.TIMECARD(SCH_1):PAGE9
  R305    2      2 RESISTOR-G155-11001-01,1KOHM,1%    I49 @TIMECARD_LIB.TIMECARD(SCH_1):PAGE9
  R303    2      2 RESISTOR-G155-11001-01,1KOHM,1%    I50 @TIMECARD_LIB.TIMECARD(SCH_1):PAGE9
  R302    2      2 RESISTOR-G155-11001-01,1KOHM,1%    I52 @TIMECARD_LIB.TIMECARD(SCH_1):PAGE9
  C285    2      2 CAPACITOR-G105-0B104-CK,0.1UF,A    I53 @TIMECARD_LIB.TIMECARD(SCH_1):PAGE9
   C47    2      2 CAPACITOR-G104-0A120-FJ,12PF,5%    I54 @TIMECARD_LIB.TIMECARD(SCH_1):PAGE9
  R351    2      2 RESISTOR-G155-100R0-J0,0OHM,-    I30 @TIMECARD_LIB.TIMECARD(SCH_1):PAGE8
  C286    2      2 CAPACITOR-G105-0B224-DK,0.22UFA    I51 @TIMECARD_LIB.TIMECARD(SCH_1):PAGE517
   CR4    1    GND DIODE_4_V1-G122-10123-01   I179 @TIMECARD_LIB.TIMECARD(SCH_1):PAGE12
   DS6    C      C OPTICAL-G170-10143-01   I140 @TIMECARD_LIB.TIMECARD(SCH_1):PAGE14
   DS7    C      C OPTICAL-G170-10143-01   I141 @TIMECARD_LIB.TIMECARD(SCH_1):PAGE14
   DS8    C      C OPTICAL-G170-10143-01   I142 @TIMECARD_LIB.TIMECARD(SCH_1):PAGE14
   DS5    C      C OPTICAL-G170-10143-01   I143 @TIMECARD_LIB.TIMECARD(SCH_1):PAGE14
  R271    1      1 RESISTOR-G155-14701-01,4.7KOHMA   I200 @TIMECARD_LIB.TIMECARD(SCH_1):PAGE161
  R288    1      1 RESISTOR-G155-14701-01,4.7KOHMA   I201 @TIMECARD_LIB.TIMECARD(SCH_1):PAGE161
  R359    2      2 RESISTOR-G155-11002-01,10KOHM,A   I127 @TIMECARD_LIB.TIMECARD(SCH_1):PAGE163
  R360    2      2 RESISTOR-G155-11002-01,10KOHM,A   I128 @TIMECARD_LIB.TIMECARD(SCH_1):PAGE163
  R152    1      1 RESISTOR-G155-14701-01,4.7KOHMA    I85 @TIMECARD_LIB.TIMECARD(SCH_1):PAGE5
  R153    1      1 RESISTOR-G155-14701-01,4.7KOHMA    I86 @TIMECARD_LIB.TIMECARD(SCH_1):PAGE5
  R154    1      1 RESISTOR-G155-14701-01,4.7KOHMA    I87 @TIMECARD_LIB.TIMECARD(SCH_1):PAGE5
  R346    2      2 RESISTOR-G155-100R0-J0,0OHM,-    I33 @TIMECARD_LIB.TIMECARD(SCH_1):PAGE8
  R343    2      2 RESISTOR-G155-100R0-J0,0OHM,-    I34 @TIMECARD_LIB.TIMECARD(SCH_1):PAGE8
  C291    2      2 CAPACITOR-G107-0F226-CM,22UF,2A   I290 @TIMECARD_LIB.TIMECARD(SCH_1):PAGE164
  C292    2      2 CAPACITOR-G107-0F226-CM,22UF,2A   I291 @TIMECARD_LIB.TIMECARD(SCH_1):PAGE164
   C93    2      2 CAPACITOR-G105-0F475-BM,4.7UF,A   I292 @TIMECARD_LIB.TIMECARD(SCH_1):PAGE164
  C293    2      2 CAPACITOR-G105-0B224-DK,0.22UFA   I168 @TIMECARD_LIB.TIMECARD(SCH_1):PAGE515
  C294    2      2 CAPACITOR-G105-0B224-DK,0.22UFA   I169 @TIMECARD_LIB.TIMECARD(SCH_1):PAGE515
  C297    2      2 CAPACITOR-G107-0F106-EM,10UF,2A   I229 @TIMECARD_LIB.TIMECARD(SCH_1):PAGE15
  C299    2      2 CAPACITOR-G107-0F106-EM,10UF,2A   I230 @TIMECARD_LIB.TIMECARD(SCH_1):PAGE15
  C303    2      2 CAPACITOR-G107-0F106-EM,10UF,2A   I231 @TIMECARD_LIB.TIMECARD(SCH_1):PAGE15
  C301    2      2 CAPACITOR-G107-0F106-EM,10UF,2A   I232 @TIMECARD_LIB.TIMECARD(SCH_1):PAGE15
    U7    2    GND AT24MAC402_SOT23_5-A221-00002-A    I89 @TIMECARD_LIB.TIMECARD(SCH_1):PAGE5
  C225    2      2 CAPACITOR-G105-0B104-EK,0.1UF,A    I92 @TIMECARD_LIB.TIMECARD(SCH_1):PAGE5
  R344    2      2 RESISTOR-G155-14701-01,4.7KOHMA    I97 @TIMECARD_LIB.TIMECARD(SCH_1):PAGE5
  R413    2      2 RESISTOR-G155-11001-01,1KOHM,1%    I60 @TIMECARD_LIB.TIMECARD(SCH_1):PAGE6
   U36    4    GND LM75BDP_TSSOP8-G220-10215-01    I66 @TIMECARD_LIB.TIMECARD(SCH_1):PAGE6
  C305    1      1 CAPACITOR-G105-0B104-EK,0.1UF,A    I67 @TIMECARD_LIB.TIMECARD(SCH_1):PAGE6
  R416    2      2 RESISTOR-G155-11001-01,1KOHM,1%    I72 @TIMECARD_LIB.TIMECARD(SCH_1):PAGE6
  R409    2      2 RESISTOR-G155-11001-01,1KOHM,1%    I73 @TIMECARD_LIB.TIMECARD(SCH_1):PAGE6
   U35    4    GND LM75BDP_TSSOP8-G220-10215-01    I90 @TIMECARD_LIB.TIMECARD(SCH_1):PAGE6
  C306    1      1 CAPACITOR-G105-0B104-EK,0.1UF,A    I91 @TIMECARD_LIB.TIMECARD(SCH_1):PAGE6
  R417    2      2 RESISTOR-G155-11001-01,1KOHM,1%    I93 @TIMECARD_LIB.TIMECARD(SCH_1):PAGE6
  R415    2      2 RESISTOR-G155-11001-01,1KOHM,1%    I94 @TIMECARD_LIB.TIMECARD(SCH_1):PAGE6
  R411    2      2 RESISTOR-G155-11001-01,1KOHM,1%    I95 @TIMECARD_LIB.TIMECARD(SCH_1):PAGE6
   J14    2      2 G200_10283_01-G200-10283-01   I427 @TIMECARD_LIB.TIMECARD(SCH_1):PAGE127
   J14   10     10 G200_10283_01-G200-10283-01   I427 @TIMECARD_LIB.TIMECARD(SCH_1):PAGE127
  R402    2      2 RESISTOR-G155-12201-01,2.2KOHMA   I440 @TIMECARD_LIB.TIMECARD(SCH_1):PAGE127
   CR7    1    GND DIODE_4_V1-G122-10123-01   I442 @TIMECARD_LIB.TIMECARD(SCH_1):PAGE127
   CR6    1    GND DIODE_4_V1-G122-10123-01   I443 @TIMECARD_LIB.TIMECARD(SCH_1):PAGE127
   U13    4    GND 74HCT2G125DP_TSSOP8-G220-00055A   I204 @TIMECARD_LIB.TIMECARD(SCH_1):PAGE12
   C83    2      2 CAPACITOR-G105-0B104-CK,0.1UF,A   I207 @TIMECARD_LIB.TIMECARD(SCH_1):PAGE12
   U14    4    GND 74HCT2G125DP_TSSOP8-G220-00055A   I226 @TIMECARD_LIB.TIMECARD(SCH_1):PAGE12
   C82    2      2 CAPACITOR-G105-0B104-CK,0.1UF,A   I231 @TIMECARD_LIB.TIMECARD(SCH_1):PAGE12
   U15    4    GND 74HCT2G125DP_TSSOP8-G220-00055A   I255 @TIMECARD_LIB.TIMECARD(SCH_1):PAGE12
   C85    2      2 CAPACITOR-G105-0B104-CK,0.1UF,A   I272 @TIMECARD_LIB.TIMECARD(SCH_1):PAGE12
   U16    4    GND 74HCT2G125DP_TSSOP8-G220-00055A   I273 @TIMECARD_LIB.TIMECARD(SCH_1):PAGE12
   C84    2      2 CAPACITOR-G105-0B104-CK,0.1UF,A   I289 @TIMECARD_LIB.TIMECARD(SCH_1):PAGE12
  C289    2      2 CAPACITOR-G105-0C106-BM,10UF,2A   I124 @TIMECARD_LIB.TIMECARD(SCH_1):PAGE3
  C290    2      2 CAPACITOR-G105-0B104-EK,0.1UF,A   I126 @TIMECARD_LIB.TIMECARD(SCH_1):PAGE3
  C288    2      2 CAPACITOR-G105-0B104-EK,0.1UF,A   I127 @TIMECARD_LIB.TIMECARD(SCH_1):PAGE3
  C287    2      2 CAPACITOR-G105-0C106-BM,10UF,2A   I129 @TIMECARD_LIB.TIMECARD(SCH_1):PAGE3
  DS19    C      C OPTICAL-G170-10143-01   I191 @TIMECARD_LIB.TIMECARD(SCH_1):PAGE14
  DS20    C      C OPTICAL-G170-10143-01   I194 @TIMECARD_LIB.TIMECARD(SCH_1):PAGE14
   U33    4  GND_1 IS32FL3207_QWLA3_TR_QFN29-A223A   I219 @TIMECARD_LIB.TIMECARD(SCH_1):PAGE14
   U33   11  GND_2 IS32FL3207_QWLA3_TR_QFN29-A223A   I219 @TIMECARD_LIB.TIMECARD(SCH_1):PAGE14
   U33   18  GND_3 IS32FL3207_QWLA3_TR_QFN29-A223A   I219 @TIMECARD_LIB.TIMECARD(SCH_1):PAGE14
   U33   25  GND_4 IS32FL3207_QWLA3_TR_QFN29-A223A   I219 @TIMECARD_LIB.TIMECARD(SCH_1):PAGE14
   U33   29 THRM_PAD IS32FL3207_QWLA3_TR_QFN29-A223A   I219 @TIMECARD_LIB.TIMECARD(SCH_1):PAGE14
  C315    2      2 CAPACITOR-G105-0B104-EK,0.1UF,A   I237 @TIMECARD_LIB.TIMECARD(SCH_1):PAGE14
  C314    2      2 CAPACITOR-G105-0C106-BM,10UF,2A   I238 @TIMECARD_LIB.TIMECARD(SCH_1):PAGE14
  R323    2      2 RESISTOR-G155-14701-01,4.7KOHMA   I246 @TIMECARD_LIB.TIMECARD(SCH_1):PAGE14
  R324    1      1 RESISTOR-G155-100R0-J0,0OHM,-   I247 @TIMECARD_LIB.TIMECARD(SCH_1):PAGE14
  C316    2      2 CAPACITOR-G105-0B104-EK,0.1UF,A   I250 @TIMECARD_LIB.TIMECARD(SCH_1):PAGE14
  C312    2      2 CAPACITOR-G105-0B104-CK,0.1UF,A    I39 @TIMECARD_LIB.TIMECARD(SCH_1):PAGE8
  C313    2      2 CAPACITOR-G105-0B104-CK,0.1UF,A    I41 @TIMECARD_LIB.TIMECARD(SCH_1):PAGE8
   U32    4    GND PCA9508DP_TSSOP8-G223-10278-01    I52 @TIMECARD_LIB.TIMECARD(SCH_1):PAGE8
    J1  GH1    GH1 CONN_JACK_1P_GH4_S_TH-G200-130A   I290 @TIMECARD_LIB.TIMECARD(SCH_1):PAGE12
    J1  GH2    GH2 CONN_JACK_1P_GH4_S_TH-G200-130A   I290 @TIMECARD_LIB.TIMECARD(SCH_1):PAGE12
    J1  GH3    GH3 CONN_JACK_1P_GH4_S_TH-G200-130A   I290 @TIMECARD_LIB.TIMECARD(SCH_1):PAGE12
    J1  GH4    GH4 CONN_JACK_1P_GH4_S_TH-G200-130A   I290 @TIMECARD_LIB.TIMECARD(SCH_1):PAGE12
    J2  GH1    GH1 CONN_JACK_1P_GH4_S_TH-G200-130A   I294 @TIMECARD_LIB.TIMECARD(SCH_1):PAGE12
    J2  GH2    GH2 CONN_JACK_1P_GH4_S_TH-G200-130A   I294 @TIMECARD_LIB.TIMECARD(SCH_1):PAGE12
    J2  GH3    GH3 CONN_JACK_1P_GH4_S_TH-G200-130A   I294 @TIMECARD_LIB.TIMECARD(SCH_1):PAGE12
    J2  GH4    GH4 CONN_JACK_1P_GH4_S_TH-G200-130A   I294 @TIMECARD_LIB.TIMECARD(SCH_1):PAGE12
    J3  GH1    GH1 CONN_JACK_1P_GH4_S_TH-G200-130A   I297 @TIMECARD_LIB.TIMECARD(SCH_1):PAGE12
    J3  GH2    GH2 CONN_JACK_1P_GH4_S_TH-G200-130A   I297 @TIMECARD_LIB.TIMECARD(SCH_1):PAGE12
    J3  GH3    GH3 CONN_JACK_1P_GH4_S_TH-G200-130A   I297 @TIMECARD_LIB.TIMECARD(SCH_1):PAGE12
    J3  GH4    GH4 CONN_JACK_1P_GH4_S_TH-G200-130A   I297 @TIMECARD_LIB.TIMECARD(SCH_1):PAGE12
    J4  GH1    GH1 CONN_JACK_1P_GH4_S_TH-G200-130A   I300 @TIMECARD_LIB.TIMECARD(SCH_1):PAGE12
    J4  GH2    GH2 CONN_JACK_1P_GH4_S_TH-G200-130A   I300 @TIMECARD_LIB.TIMECARD(SCH_1):PAGE12
    J4  GH3    GH3 CONN_JACK_1P_GH4_S_TH-G200-130A   I300 @TIMECARD_LIB.TIMECARD(SCH_1):PAGE12
    J4  GH4    GH4 CONN_JACK_1P_GH4_S_TH-G200-130A   I300 @TIMECARD_LIB.TIMECARD(SCH_1):PAGE12
    U3    3    GND 74LVC1G07_SC70_5-G220-10017-01   I135 @TIMECARD_LIB.TIMECARD(SCH_1):PAGE3
    P3    4      4 CONN_HDR_2X3_M_RA_TH-G200-1251A   I238 @TIMECARD_LIB.TIMECARD(SCH_1):PAGE15
    P3    5      5 CONN_HDR_2X3_M_RA_TH-G200-1251A   I238 @TIMECARD_LIB.TIMECARD(SCH_1):PAGE15
    P3    6      6 CONN_HDR_2X3_M_RA_TH-G200-1251A   I238 @TIMECARD_LIB.TIMECARD(SCH_1):PAGE15
   U17    2      2 CL1001485A-G122-00019-01     I3 @TIMECARD_LIB.TIMECARD(SCH_1):PAGE524
   C86    1      1 CAPACITOR-G104-0A180-FJ,18PF,5%     I7 @TIMECARD_LIB.TIMECARD(SCH_1):PAGE524
    Y2    2      2 XTAL_4-G131-10038-02     I8 @TIMECARD_LIB.TIMECARD(SCH_1):PAGE524
    Y2    4      4 XTAL_4-G131-10038-02     I8 @TIMECARD_LIB.TIMECARD(SCH_1):PAGE524
   C87    1      1 CAPACITOR-G104-0A180-FJ,18PF,5%    I10 @TIMECARD_LIB.TIMECARD(SCH_1):PAGE524
  R130    2      2 RESISTOR-G155-11002-01,10KOHM,A    I23 @TIMECARD_LIB.TIMECARD(SCH_1):PAGE524
   U18   10   AGND FT4232HL_REEL_QFP64-G223-10282A    I64 @TIMECARD_LIB.TIMECARD(SCH_1):PAGE524
   U18   51  GND_1 FT4232HL_REEL_QFP64-G223-10282A    I64 @TIMECARD_LIB.TIMECARD(SCH_1):PAGE524
   U18   47  GND_2 FT4232HL_REEL_QFP64-G223-10282A    I64 @TIMECARD_LIB.TIMECARD(SCH_1):PAGE524
   U18   35  GND_3 FT4232HL_REEL_QFP64-G223-10282A    I64 @TIMECARD_LIB.TIMECARD(SCH_1):PAGE524
   U18   25  GND_4 FT4232HL_REEL_QFP64-G223-10282A    I64 @TIMECARD_LIB.TIMECARD(SCH_1):PAGE524
   U18   15  GND_5 FT4232HL_REEL_QFP64-G223-10282A    I64 @TIMECARD_LIB.TIMECARD(SCH_1):PAGE524
   U18   11  GND_6 FT4232HL_REEL_QFP64-G223-10282A    I64 @TIMECARD_LIB.TIMECARD(SCH_1):PAGE524
   U18    5  GND_7 FT4232HL_REEL_QFP64-G223-10282A    I64 @TIMECARD_LIB.TIMECARD(SCH_1):PAGE524
   U18    1  GND_8 FT4232HL_REEL_QFP64-G223-10282A    I64 @TIMECARD_LIB.TIMECARD(SCH_1):PAGE524
   U18   13   TEST FT4232HL_REEL_QFP64-G223-10282A    I64 @TIMECARD_LIB.TIMECARD(SCH_1):PAGE524
  R463    2      2 RESISTOR-G155-01202-01,12KOHM,A   I106 @TIMECARD_LIB.TIMECARD(SCH_1):PAGE524
   C90    2      2 CAPACITOR-G105-0F475-BM,4.7UF,A   I123 @TIMECARD_LIB.TIMECARD(SCH_1):PAGE524
   C91    2      2 CAPACITOR-G105-0F475-BM,4.7UF,A   I128 @TIMECARD_LIB.TIMECARD(SCH_1):PAGE524
   J10    9      9 G200_10283_01-G200-10283-01   I173 @TIMECARD_LIB.TIMECARD(SCH_1):PAGE524
   U31    5    GND CAT93C46VI_GT3_SOIC8-G221-1007A   I201 @TIMECARD_LIB.TIMECARD(SCH_1):PAGE524
  R171    1      1 RESISTOR-G155-14701-01,4.7KOHMA  I1542 @TIMECARD_LIB.TIMECARD(SCH_1):PAGE16
  R173    1      1 RESISTOR-G155-14701-01,4.7KOHMA  I1544 @TIMECARD_LIB.TIMECARD(SCH_1):PAGE16
  R284    1      1 RESISTOR-G155-14701-01,4.7KOHMA  I1547 @TIMECARD_LIB.TIMECARD(SCH_1):PAGE16
  R286    1      1 RESISTOR-G155-14701-01,4.7KOHMA  I1549 @TIMECARD_LIB.TIMECARD(SCH_1):PAGE16
  R328    1      1 RESISTOR-G155-14701-01,4.7KOHMA  I1550 @TIMECARD_LIB.TIMECARD(SCH_1):PAGE16
  R326    1      1 RESISTOR-G155-14701-01,4.7KOHMA  I1552 @TIMECARD_LIB.TIMECARD(SCH_1):PAGE16
  R293    1      1 RESISTOR-G155-14701-01,4.7KOHMA  I1555 @TIMECARD_LIB.TIMECARD(SCH_1):PAGE16
  R309    1      1 RESISTOR-G155-14701-01,4.7KOHMA  I1557 @TIMECARD_LIB.TIMECARD(SCH_1):PAGE16
  C284    2      2 CAPACITOR-G107-0F226-CM,22UF,2A     I7 @TIMECARD_LIB.TIMECARD(SCH_1):PAGE525
  C298    2      2 CAPACITOR-G105-0B104-EK,0.1UF,A     I8 @TIMECARD_LIB.TIMECARD(SCH_1):PAGE525
  R488    2      2 RESISTOR-G155-11002-01,10KOHM,A    I13 @TIMECARD_LIB.TIMECARD(SCH_1):PAGE525
  C302    2      2 CAPACITOR-G105-0B104-EK,0.1UF,A    I14 @TIMECARD_LIB.TIMECARD(SCH_1):PAGE525
  C300    2      2 CAPACITOR-G107-0F106-EM,10UF,2A    I16 @TIMECARD_LIB.TIMECARD(SCH_1):PAGE525
  C307    2      2 CAPACITOR-G104-0B103-EK,0.01UFA    I18 @TIMECARD_LIB.TIMECARD(SCH_1):PAGE525
  C304    2      2 CAPACITOR-G105-0B104-EK,0.1UF,A    I20 @TIMECARD_LIB.TIMECARD(SCH_1):PAGE525
   U41    5    GND ISL80101IRAJZ_DFN10-G222-10136A    I29 @TIMECARD_LIB.TIMECARD(SCH_1):PAGE525
   U41   11 THRM_PAD ISL80101IRAJZ_DFN10-G222-10136A    I29 @TIMECARD_LIB.TIMECARD(SCH_1):PAGE525
  C309    2      2 CAPACITOR-G105-0B104-EK,0.1UF,A    I56 @TIMECARD_LIB.TIMECARD(SCH_1):PAGE525
  C308    2      2 CAPACITOR-G107-0F106-EM,10UF,2A    I64 @TIMECARD_LIB.TIMECARD(SCH_1):PAGE525
  R491    2      2 RESISTOR-G155-03241-01,3.24KOHA    I67 @TIMECARD_LIB.TIMECARD(SCH_1):PAGE525
  R489    2      2 RESISTOR-G155-03921-01,3.92KOHA    I68 @TIMECARD_LIB.TIMECARD(SCH_1):PAGE525
  DS12    C      C OPTICAL-G170-10143-01   I289 @TIMECARD_LIB.TIMECARD(SCH_1):PAGE14
  C101    2      2 CAPACITOR-G105-0B104-EK,0.1UF,A   I373 @TIMECARD_LIB.TIMECARD(SCH_1):PAGE524
  C100    2      2 CAPACITOR-G105-0B104-EK,0.1UF,A   I374 @TIMECARD_LIB.TIMECARD(SCH_1):PAGE524
   C95    2      2 CAPACITOR-G105-0B104-EK,0.1UF,A   I375 @TIMECARD_LIB.TIMECARD(SCH_1):PAGE524
   C96    2      2 CAPACITOR-G105-0B104-EK,0.1UF,A   I376 @TIMECARD_LIB.TIMECARD(SCH_1):PAGE524
   C94    2      2 CAPACITOR-G105-0B104-EK,0.1UF,A   I377 @TIMECARD_LIB.TIMECARD(SCH_1):PAGE524
   C88    2      2 CAPACITOR-G105-0B104-EK,0.1UF,A   I378 @TIMECARD_LIB.TIMECARD(SCH_1):PAGE524
   C98    2      2 CAPACITOR-G105-0F475-BM,4.7UF,A   I379 @TIMECARD_LIB.TIMECARD(SCH_1):PAGE524
   C99    2      2 CAPACITOR-G105-0F475-BM,4.7UF,A   I380 @TIMECARD_LIB.TIMECARD(SCH_1):PAGE524
  R445    2      2 RESISTOR-G155-05101-01,5.1KOHMA   I395 @TIMECARD_LIB.TIMECARD(SCH_1):PAGE524
   J17    2      2 CONN_HDR_2X2_M_S_SMT-G200-1068A   I127 @TIMECARD_LIB.TIMECARD(SCH_1):PAGE5
   J17    4      4 CONN_HDR_2X2_M_S_SMT-G200-1068A   I127 @TIMECARD_LIB.TIMECARD(SCH_1):PAGE5
   U19    4    VSS 24LC16BT_I_ST_TSSOP8-G221-1017A   I148 @TIMECARD_LIB.TIMECARD(SCH_1):PAGE5
  R159    2      2 RESISTOR-G155-14701-01,4.7KOHMA   I156 @TIMECARD_LIB.TIMECARD(SCH_1):PAGE5
  R161    2      2 RESISTOR-G155-14701-01,4.7KOHMA   I165 @TIMECARD_LIB.TIMECARD(SCH_1):PAGE5
  R163    2      2 RESISTOR-G155-14701-01,4.7KOHMA   I166 @TIMECARD_LIB.TIMECARD(SCH_1):PAGE5
   R24    2      2 RESISTOR-G155-14701-01,4.7KOHMA   I167 @TIMECARD_LIB.TIMECARD(SCH_1):PAGE5
    C1    2      2 CAPACITOR-G105-0B104-EK,0.1UF,A   I171 @TIMECARD_LIB.TIMECARD(SCH_1):PAGE5
  R437    1      1 RESISTOR-G155-11502-01,15KOHM,A   I239 @TIMECARD_LIB.TIMECARD(SCH_1):PAGE161
  R436    1      1 RESISTOR-G155-11502-01,15KOHM,A   I240 @TIMECARD_LIB.TIMECARD(SCH_1):PAGE161
   J11    5      5 CONN_USB_1X5_G2_GH4_F_RA_SMT-GA     I2 @TIMECARD_LIB.TIMECARD(SCH_1):PAGE527
   J11   G1     G1 CONN_USB_1X5_G2_GH4_F_RA_SMT-GA     I2 @TIMECARD_LIB.TIMECARD(SCH_1):PAGE527
   J11   G2     G2 CONN_USB_1X5_G2_GH4_F_RA_SMT-GA     I2 @TIMECARD_LIB.TIMECARD(SCH_1):PAGE527
   J11  GH1    GH1 CONN_USB_1X5_G2_GH4_F_RA_SMT-GA     I2 @TIMECARD_LIB.TIMECARD(SCH_1):PAGE527
   J11  GH2    GH2 CONN_USB_1X5_G2_GH4_F_RA_SMT-GA     I2 @TIMECARD_LIB.TIMECARD(SCH_1):PAGE527
   J11  GH3    GH3 CONN_USB_1X5_G2_GH4_F_RA_SMT-GA     I2 @TIMECARD_LIB.TIMECARD(SCH_1):PAGE527
   J11  GH4    GH4 CONN_USB_1X5_G2_GH4_F_RA_SMT-GA     I2 @TIMECARD_LIB.TIMECARD(SCH_1):PAGE527
    U9    2      2 CL1001485A-G122-00019-01     I4 @TIMECARD_LIB.TIMECARD(SCH_1):PAGE527
   C63    2      2 CAPACITOR-G105-0B104-EK,0.1UF,A    I15 @TIMECARD_LIB.TIMECARD(SCH_1):PAGE527
   C61    2      2 CAPACITOR-G107-0F106-EM,10UF,2A    I16 @TIMECARD_LIB.TIMECARD(SCH_1):PAGE527
   C58    2      2 CAPACITOR-G107-0F106-EM,10UF,2A    I47 @TIMECARD_LIB.TIMECARD(SCH_1):PAGE527
   C59    2      2 CAPACITOR-G105-0B104-EK,0.1UF,A    I48 @TIMECARD_LIB.TIMECARD(SCH_1):PAGE527
   C64    2      2 CAPACITOR-G107-0F106-EM,10UF,2A    I51 @TIMECARD_LIB.TIMECARD(SCH_1):PAGE527
   C65    2      2 CAPACITOR-G105-0B104-EK,0.1UF,A    I56 @TIMECARD_LIB.TIMECARD(SCH_1):PAGE527
   C66    2      2 CAPACITOR-G105-0B104-EK,0.1UF,A    I57 @TIMECARD_LIB.TIMECARD(SCH_1):PAGE527
   C60    2      2 CAPACITOR-G105-0B104-EK,0.1UF,A    I66 @TIMECARD_LIB.TIMECARD(SCH_1):PAGE527
   C69    2      2 CAPACITOR-G105-0B104-EK,0.1UF,A    I74 @TIMECARD_LIB.TIMECARD(SCH_1):PAGE527
   C70    2      2 CAPACITOR-G105-0B104-EK,0.1UF,A    I77 @TIMECARD_LIB.TIMECARD(SCH_1):PAGE527
   U12    2    GND TPS2051BDBVT_SOT23_5-G220-1033A    I78 @TIMECARD_LIB.TIMECARD(SCH_1):PAGE527
   C71    2      2 CAPACITOR-G105-0B104-EK,0.1UF,A    I85 @TIMECARD_LIB.TIMECARD(SCH_1):PAGE527
   C62    2      2 CAPACITOR-G105-0B104-EK,0.1UF,A    I93 @TIMECARD_LIB.TIMECARD(SCH_1):PAGE527
   C67    2      2 CAPACITOR-G105-0B104-CK,0.1UF,A   I103 @TIMECARD_LIB.TIMECARD(SCH_1):PAGE527
   U11    9    GND TS3USB3031RMGR_WQFN12-G220-103A   I108 @TIMECARD_LIB.TIMECARD(SCH_1):PAGE527
  R104    2      2 RESISTOR-G155-14701-01,4.7KOHMA   I126 @TIMECARD_LIB.TIMECARD(SCH_1):PAGE527
   C68    2      2 CAPACITOR-G105-0B104-EK,0.1UF,A   I144 @TIMECARD_LIB.TIMECARD(SCH_1):PAGE527
   U10    3    GND CL5003148A-G220-10019-01   I146 @TIMECARD_LIB.TIMECARD(SCH_1):PAGE527
   R99    2      2 RESISTOR-G155-14701-01,4.7KOHMA   I149 @TIMECARD_LIB.TIMECARD(SCH_1):PAGE527
    P1    8      8 CONN_HDR_2X10_M_S_SMT-G200-130A   I193 @TIMECARD_LIB.TIMECARD(SCH_1):PAGE527
    P1    9      9 CONN_HDR_2X10_M_S_SMT-G200-130A   I193 @TIMECARD_LIB.TIMECARD(SCH_1):PAGE527
    P1   15     15 CONN_HDR_2X10_M_S_SMT-G200-130A   I193 @TIMECARD_LIB.TIMECARD(SCH_1):PAGE527
   J18    1      1 CONN_HDR_1X3_M_S_SMT-G205-1002A   I198 @TIMECARD_LIB.TIMECARD(SCH_1):PAGE527
   J18    3      3 CONN_HDR_1X3_M_S_SMT-G205-1002A   I198 @TIMECARD_LIB.TIMECARD(SCH_1):PAGE527
  R103    2      2 RESISTOR-G155-11001-01,1KOHM,1%   I202 @TIMECARD_LIB.TIMECARD(SCH_1):PAGE527
  C282    2      2 CAPACITOR-G107-0F106-EM,10UF,2A   I208 @TIMECARD_LIB.TIMECARD(SCH_1):PAGE527
  C283    2      2 CAPACITOR-G107-0F106-EM,10UF,2A   I209 @TIMECARD_LIB.TIMECARD(SCH_1):PAGE527
MAC_PIN4    1      1 NUT-A200-00029-FB   I228 @TIMECARD_LIB.TIMECARD(SCH_1):PAGE527
MAC_PIN2    1      1 NUT-A200-00029-FB   I229 @TIMECARD_LIB.TIMECARD(SCH_1):PAGE527
    Q2    2      S POWERMOS_3P_NCH_V1-G121-10200-A   I232 @TIMECARD_LIB.TIMECARD(SCH_1):PAGE527
  R441    2      2 RESISTOR-G155-11002-01,10KOHM,A   I134 @TIMECARD_LIB.TIMECARD(SCH_1):PAGE163
  R440    2      2 RESISTOR-G155-11002-01,10KOHM,A   I135 @TIMECARD_LIB.TIMECARD(SCH_1):PAGE163
  R458    1      1 RESISTOR-G155-11001-01,1KOHM,1%   I430 @TIMECARD_LIB.TIMECARD(SCH_1):PAGE524
  R459    1      1 RESISTOR-G155-11001-01,1KOHM,1%   I432 @TIMECARD_LIB.TIMECARD(SCH_1):PAGE524
  R451    2      2 RESISTOR-G155-11001-01,1KOHM,1%   I441 @TIMECARD_LIB.TIMECARD(SCH_1):PAGE524
  R453    2      2 RESISTOR-G155-11001-01,1KOHM,1%   I442 @TIMECARD_LIB.TIMECARD(SCH_1):PAGE524
    Q1    2      S POWERMOS_3P_NCH_V1-G121-10200-A   I445 @TIMECARD_LIB.TIMECARD(SCH_1):PAGE524
  R483    1      1 RESISTOR-G155-11001-01,1KOHM,1%   I462 @TIMECARD_LIB.TIMECARD(SCH_1):PAGE524
  R484    1      1 RESISTOR-G155-11001-01,1KOHM,1%   I463 @TIMECARD_LIB.TIMECARD(SCH_1):PAGE524
   U30    8    GND TS3A5018PWR_TSSOP16-G220-10324A   I473 @TIMECARD_LIB.TIMECARD(SCH_1):PAGE524
   C89    2      2 CAPACITOR-G105-0B104-EK,0.1UF,A   I474 @TIMECARD_LIB.TIMECARD(SCH_1):PAGE524
   C92    2      2 CAPACITOR-G105-0B104-EK,0.1UF,A   I476 @TIMECARD_LIB.TIMECARD(SCH_1):PAGE524
   U37    8    GND TS3A5018PWR_TSSOP16-G220-10324A   I478 @TIMECARD_LIB.TIMECARD(SCH_1):PAGE524
   U38    8    GND TS3A5018PWR_TSSOP16-G220-10324A   I481 @TIMECARD_LIB.TIMECARD(SCH_1):PAGE524
   C97    2      2 CAPACITOR-G105-0B104-EK,0.1UF,A   I482 @TIMECARD_LIB.TIMECARD(SCH_1):PAGE524
   U39    2    GND NLASB3157DFT2G_SC88-G223-10187A   I485 @TIMECARD_LIB.TIMECARD(SCH_1):PAGE524
  C123    2      2 CAPACITOR-G105-0B104-EK,0.1UF,A   I486 @TIMECARD_LIB.TIMECARD(SCH_1):PAGE524
  C102    2      2 CAPACITOR-G105-0B104-EK,0.1UF,A   I490 @TIMECARD_LIB.TIMECARD(SCH_1):PAGE524
   U40    2    GND NLASB3157DFT2G_SC88-G223-10187A   I491 @TIMECARD_LIB.TIMECARD(SCH_1):PAGE524
   U23    4    VSS MT25QL128ABA1ESE_SOP8-G221-102A   I456 @TIMECARD_LIB.TIMECARD(SCH_1):PAGE127
  R192    2      2 RESISTOR-G155-14701-01,4.7KOHMA   I470 @TIMECARD_LIB.TIMECARD(SCH_1):PAGE127
  C199    2      2 CAPACITOR-G105-0B104-CK,0.1UF,A   I472 @TIMECARD_LIB.TIMECARD(SCH_1):PAGE127
  C198    2      2 CAPACITOR-G105-0F475-BM,4.7UF,A   I473 @TIMECARD_LIB.TIMECARD(SCH_1):PAGE127
    J5    9      9 CONN_HDR_2X6_F_S_SMT-G200-1313A  I1614 @TIMECARD_LIB.TIMECARD(SCH_1):PAGE16
    J5   10     10 CONN_HDR_2X6_F_S_SMT-G200-1313A  I1614 @TIMECARD_LIB.TIMECARD(SCH_1):PAGE16
  ME11    1      1 MEC_MTH8-MTH125C236N_V8-MTH125A     I1 @TIMECARD_LIB.TIMECARD(SCH_1):PAGE33
  ME11    2      2 MEC_MTH8-MTH125C236N_V8-MTH125A     I1 @TIMECARD_LIB.TIMECARD(SCH_1):PAGE33
  ME11    3      3 MEC_MTH8-MTH125C236N_V8-MTH125A     I1 @TIMECARD_LIB.TIMECARD(SCH_1):PAGE33
  ME11    4      4 MEC_MTH8-MTH125C236N_V8-MTH125A     I1 @TIMECARD_LIB.TIMECARD(SCH_1):PAGE33
  ME11    5      5 MEC_MTH8-MTH125C236N_V8-MTH125A     I1 @TIMECARD_LIB.TIMECARD(SCH_1):PAGE33
  ME11    6      6 MEC_MTH8-MTH125C236N_V8-MTH125A     I1 @TIMECARD_LIB.TIMECARD(SCH_1):PAGE33
  ME11    7      7 MEC_MTH8-MTH125C236N_V8-MTH125A     I1 @TIMECARD_LIB.TIMECARD(SCH_1):PAGE33
  ME11    8      8 MEC_MTH8-MTH125C236N_V8-MTH125A     I1 @TIMECARD_LIB.TIMECARD(SCH_1):PAGE33
  ME12    1      1 MEC_MTH8-MTH125C236N_V8-MTH125A     I2 @TIMECARD_LIB.TIMECARD(SCH_1):PAGE33
  ME12    2      2 MEC_MTH8-MTH125C236N_V8-MTH125A     I2 @TIMECARD_LIB.TIMECARD(SCH_1):PAGE33
  ME12    3      3 MEC_MTH8-MTH125C236N_V8-MTH125A     I2 @TIMECARD_LIB.TIMECARD(SCH_1):PAGE33
  ME12    4      4 MEC_MTH8-MTH125C236N_V8-MTH125A     I2 @TIMECARD_LIB.TIMECARD(SCH_1):PAGE33
  ME12    5      5 MEC_MTH8-MTH125C236N_V8-MTH125A     I2 @TIMECARD_LIB.TIMECARD(SCH_1):PAGE33
  ME12    6      6 MEC_MTH8-MTH125C236N_V8-MTH125A     I2 @TIMECARD_LIB.TIMECARD(SCH_1):PAGE33
  ME12    7      7 MEC_MTH8-MTH125C236N_V8-MTH125A     I2 @TIMECARD_LIB.TIMECARD(SCH_1):PAGE33
  ME12    8      8 MEC_MTH8-MTH125C236N_V8-MTH125A     I2 @TIMECARD_LIB.TIMECARD(SCH_1):PAGE33
  ME10    1      1 MEC_MTH8-MTH125C236N_V8-MTH125A     I5 @TIMECARD_LIB.TIMECARD(SCH_1):PAGE33
  ME10    2      2 MEC_MTH8-MTH125C236N_V8-MTH125A     I5 @TIMECARD_LIB.TIMECARD(SCH_1):PAGE33
  ME10    3      3 MEC_MTH8-MTH125C236N_V8-MTH125A     I5 @TIMECARD_LIB.TIMECARD(SCH_1):PAGE33
  ME10    4      4 MEC_MTH8-MTH125C236N_V8-MTH125A     I5 @TIMECARD_LIB.TIMECARD(SCH_1):PAGE33
  ME10    5      5 MEC_MTH8-MTH125C236N_V8-MTH125A     I5 @TIMECARD_LIB.TIMECARD(SCH_1):PAGE33
  ME10    6      6 MEC_MTH8-MTH125C236N_V8-MTH125A     I5 @TIMECARD_LIB.TIMECARD(SCH_1):PAGE33
  ME10    7      7 MEC_MTH8-MTH125C236N_V8-MTH125A     I5 @TIMECARD_LIB.TIMECARD(SCH_1):PAGE33
  ME10    8      8 MEC_MTH8-MTH125C236N_V8-MTH125A     I5 @TIMECARD_LIB.TIMECARD(SCH_1):PAGE33
   ME9    1      1 MEC_MTH8-MTH125C236N_V8-MTH125A     I7 @TIMECARD_LIB.TIMECARD(SCH_1):PAGE33
   ME9    2      2 MEC_MTH8-MTH125C236N_V8-MTH125A     I7 @TIMECARD_LIB.TIMECARD(SCH_1):PAGE33
   ME9    3      3 MEC_MTH8-MTH125C236N_V8-MTH125A     I7 @TIMECARD_LIB.TIMECARD(SCH_1):PAGE33
   ME9    4      4 MEC_MTH8-MTH125C236N_V8-MTH125A     I7 @TIMECARD_LIB.TIMECARD(SCH_1):PAGE33
   ME9    5      5 MEC_MTH8-MTH125C236N_V8-MTH125A     I7 @TIMECARD_LIB.TIMECARD(SCH_1):PAGE33
   ME9    6      6 MEC_MTH8-MTH125C236N_V8-MTH125A     I7 @TIMECARD_LIB.TIMECARD(SCH_1):PAGE33
   ME9    7      7 MEC_MTH8-MTH125C236N_V8-MTH125A     I7 @TIMECARD_LIB.TIMECARD(SCH_1):PAGE33
   ME9    8      8 MEC_MTH8-MTH125C236N_V8-MTH125A     I7 @TIMECARD_LIB.TIMECARD(SCH_1):PAGE33
   ME3    1      1 NUT-G340-10437-01   I125 @TIMECARD_LIB.TIMECARD(SCH_1):PAGE33
   ME4    1      1 NUT-G340-10437-01   I126 @TIMECARD_LIB.TIMECARD(SCH_1):PAGE33
   ME1    1      1 NUT-G340-10437-01   I127 @TIMECARD_LIB.TIMECARD(SCH_1):PAGE33
   ME2    1      1 NUT-G340-10437-01   I129 @TIMECARD_LIB.TIMECARD(SCH_1):PAGE33
  C310    1      1 CAPACITOR-G104-0A180-FJ,18PF,5%   I318 @TIMECARD_LIB.TIMECARD(SCH_1):PAGE12
  R496    1      1 RESISTOR-G155-11004-01,1MOHM,1%   I320 @TIMECARD_LIB.TIMECARD(SCH_1):PAGE12
  R497    1      1 RESISTOR-G155-11004-01,1MOHM,1%   I322 @TIMECARD_LIB.TIMECARD(SCH_1):PAGE12
  R498    1      1 RESISTOR-G155-11004-01,1MOHM,1%   I327 @TIMECARD_LIB.TIMECARD(SCH_1):PAGE12
  C317    1      1 CAPACITOR-G104-0A180-FJ,18PF,5%   I328 @TIMECARD_LIB.TIMECARD(SCH_1):PAGE12
  C311    1      1 CAPACITOR-G104-0A180-FJ,18PF,5%   I321 @TIMECARD_LIB.TIMECARD(SCH_1):PAGE12
  R499    1      1 RESISTOR-G155-11004-01,1MOHM,1%   I331 @TIMECARD_LIB.TIMECARD(SCH_1):PAGE12
  C318    1      1 CAPACITOR-G104-0A180-FJ,18PF,5%   I332 @TIMECARD_LIB.TIMECARD(SCH_1):PAGE12
  R501    1      1 RESISTOR-G155-14701-01,4.7KOHMA   I241 @TIMECARD_LIB.TIMECARD(SCH_1):PAGE161
  R500    1      1 RESISTOR-G155-14701-01,4.7KOHMA   I242 @TIMECARD_LIB.TIMECARD(SCH_1):PAGE161
  R504    2      2 RESISTOR-G155-14701-01,4.7KOHMA   I244 @TIMECARD_LIB.TIMECARD(SCH_1):PAGE161
  R503    2      2 RESISTOR-G155-14701-01,4.7KOHMA   I246 @TIMECARD_LIB.TIMECARD(SCH_1):PAGE161
   J13  GH1    GH1 CONN_USB_14P_GH4_F_RA_TH-G200-A   I495 @TIMECARD_LIB.TIMECARD(SCH_1):PAGE524
   J13  GH2    GH2 CONN_USB_14P_GH4_F_RA_TH-G200-A   I495 @TIMECARD_LIB.TIMECARD(SCH_1):PAGE524
   J13  GH3    GH3 CONN_USB_14P_GH4_F_RA_TH-G200-A   I495 @TIMECARD_LIB.TIMECARD(SCH_1):PAGE524
   J13  GH4    GH4 CONN_USB_14P_GH4_F_RA_TH-G200-A   I495 @TIMECARD_LIB.TIMECARD(SCH_1):PAGE524
   J13   A1  GND_1 CONN_USB_14P_GH4_F_RA_TH-G200-A   I495 @TIMECARD_LIB.TIMECARD(SCH_1):PAGE524
   J13  A12  GND_2 CONN_USB_14P_GH4_F_RA_TH-G200-A   I495 @TIMECARD_LIB.TIMECARD(SCH_1):PAGE524
   J13   B1  GND_3 CONN_USB_14P_GH4_F_RA_TH-G200-A   I495 @TIMECARD_LIB.TIMECARD(SCH_1):PAGE524
   J13  B12  GND_4 CONN_USB_14P_GH4_F_RA_TH-G200-A   I495 @TIMECARD_LIB.TIMECARD(SCH_1):PAGE524
  R442    2      2 RESISTOR-G155-05101-01,5.1KOHMA   I497 @TIMECARD_LIB.TIMECARD(SCH_1):PAGE524
   U34    2    GND TPS3808G18DBVR_SOT23_6-G222-00A   I139 @TIMECARD_LIB.TIMECARD(SCH_1):PAGE3
   DS9    C      C OPTICAL-G170-10143-01   I292 @TIMECARD_LIB.TIMECARD(SCH_1):PAGE14
  C250    2      2 CAPACITOR-G105-0B104-EK,0.1UF,A   I152 @TIMECARD_LIB.TIMECARD(SCH_1):PAGE3
  R224    1      1 RESISTOR-G155-11001-01,1KOHM,1%   I253 @TIMECARD_LIB.TIMECARD(SCH_1):PAGE161

SHT3X_ADDR @TIMECARD_LIB.TIMECARD(SCH_1):SHT3X_ADDR
   R69    1      1 RESISTOR-G155-11001-01,1KOHM,1%     I7 @TIMECARD_LIB.TIMECARD(SCH_1):PAGE7
   R68    2      2 RESISTOR-G155-14701-01,4.7KOHMA     I8 @TIMECARD_LIB.TIMECARD(SCH_1):PAGE7
   U27    2   ADDR SHT31A_DIS_B10KS_DFN8-A222-000A    I44 @TIMECARD_LIB.TIMECARD(SCH_1):PAGE7

SHT3X_I2C_SCL @TIMECARD_LIB.TIMECARD(SCH_1):SHT3X_I2C_SCL
    U4    7    SC1 PCA9546APW_TSSOP16-G223-10280-A    I33 @TIMECARD_LIB.TIMECARD(SCH_1):PAGE5
   R65    2      2 RESISTOR-G155-14701-01,4.7KOHMA     I4 @TIMECARD_LIB.TIMECARD(SCH_1):PAGE7
   R67    1      1 RESISTOR-G155-133R0-01,33OHM,1%    I13 @TIMECARD_LIB.TIMECARD(SCH_1):PAGE7

SHT3X_I2C_SDA @TIMECARD_LIB.TIMECARD(SCH_1):SHT3X_I2C_SDA
    U4    6    SD1 PCA9546APW_TSSOP16-G223-10280-A    I33 @TIMECARD_LIB.TIMECARD(SCH_1):PAGE5
   R64    2      2 RESISTOR-G155-14701-01,4.7KOHMA     I3 @TIMECARD_LIB.TIMECARD(SCH_1):PAGE7
   R66    1      1 RESISTOR-G155-133R0-01,33OHM,1%    I14 @TIMECARD_LIB.TIMECARD(SCH_1):PAGE7

SMA1_LED_BLUE_N @TIMECARD_LIB.TIMECARD(SCH_1):SMA1_LED_BLUE_N
  R385    1      1 RESISTOR-G155-133R0-01,33OHM,1%   I107 @TIMECARD_LIB.TIMECARD(SCH_1):PAGE14
   U33   10   OUT3 IS32FL3207_QWLA3_TR_QFN29-A223A   I219 @TIMECARD_LIB.TIMECARD(SCH_1):PAGE14

SMA1_LED_GREEN_N @TIMECARD_LIB.TIMECARD(SCH_1):SMA1_LED_GREEN_N
  R386    1      1 RESISTOR-G155-133R0-01,33OHM,1%   I108 @TIMECARD_LIB.TIMECARD(SCH_1):PAGE14
   U33    8   OUT1 IS32FL3207_QWLA3_TR_QFN29-A223A   I219 @TIMECARD_LIB.TIMECARD(SCH_1):PAGE14

SMA1_LED_RED_N @TIMECARD_LIB.TIMECARD(SCH_1):SMA1_LED_RED_N
  R387    1      1 RESISTOR-G155-133R0-01,33OHM,1%   I110 @TIMECARD_LIB.TIMECARD(SCH_1):PAGE14
   U33    9   OUT2 IS32FL3207_QWLA3_TR_QFN29-A223A   I219 @TIMECARD_LIB.TIMECARD(SCH_1):PAGE14

SMA1_SIG_IN_BF_EN_N @TIMECARD_LIB.TIMECARD(SCH_1):SMA1_SIG_IN_BF_EN_N
   U24  K14 IO_L19N_T3_A21_VREF_15 XC7A200T_2FBG484C_FBG484-G240-A   I228 @TIMECARD_LIB.TIMECARD(SCH_1):PAGE162
   U15    7   2OE* 74HCT2G125DP_TSSOP8-G220-00055A   I255 @TIMECARD_LIB.TIMECARD(SCH_1):PAGE12
  R381    2      2 RESISTOR-G155-14701-01,4.7KOHMA   I262 @TIMECARD_LIB.TIMECARD(SCH_1):PAGE12
  TP28    1      1 TP_PIONT-TP010CT020B030_PTH-TPA  I1667 @TIMECARD_LIB.TIMECARD(SCH_1):PAGE16

SMA1_SIG_IO_CONN @TIMECARD_LIB.TIMECARD(SCH_1):SMA1_SIG_IO_CONN
   CR4    3    IO2 DIODE_4_V1-G122-10123-01   I179 @TIMECARD_LIB.TIMECARD(SCH_1):PAGE12
  R127    2      2 RESISTOR-G155-149R9-01,49.9OHMA   I257 @TIMECARD_LIB.TIMECARD(SCH_1):PAGE12
    J3    1      1 CONN_JACK_1P_GH4_S_TH-G200-130A   I297 @TIMECARD_LIB.TIMECARD(SCH_1):PAGE12

SMA1_SIG_OUT_BF_EN_N @TIMECARD_LIB.TIMECARD(SCH_1):SMA1_SIG_OUT_BF_EN_N
   U24  K13 IO_L19P_T3_A22_15 XC7A200T_2FBG484C_FBG484-G240-A   I228 @TIMECARD_LIB.TIMECARD(SCH_1):PAGE162
   U15    1   1OE* 74HCT2G125DP_TSSOP8-G220-00055A   I255 @TIMECARD_LIB.TIMECARD(SCH_1):PAGE12
  R361    2      2 RESISTOR-G155-14701-01,4.7KOHMA   I261 @TIMECARD_LIB.TIMECARD(SCH_1):PAGE12
  TP32    1      1 TP_PIONT-TP010CT020B030_PTH-TPA  I1662 @TIMECARD_LIB.TIMECARD(SCH_1):PAGE16

SMA2_LED_BLUE_N @TIMECARD_LIB.TIMECARD(SCH_1):SMA2_LED_BLUE_N
  R388    1      1 RESISTOR-G155-133R0-01,33OHM,1%   I147 @TIMECARD_LIB.TIMECARD(SCH_1):PAGE14
   U33   14   OUT6 IS32FL3207_QWLA3_TR_QFN29-A223A   I219 @TIMECARD_LIB.TIMECARD(SCH_1):PAGE14

SMA2_LED_GREEN_N @TIMECARD_LIB.TIMECARD(SCH_1):SMA2_LED_GREEN_N
  R389    1      1 RESISTOR-G155-133R0-01,33OHM,1%   I148 @TIMECARD_LIB.TIMECARD(SCH_1):PAGE14
   U33   12   OUT4 IS32FL3207_QWLA3_TR_QFN29-A223A   I219 @TIMECARD_LIB.TIMECARD(SCH_1):PAGE14

SMA2_LED_RED_N @TIMECARD_LIB.TIMECARD(SCH_1):SMA2_LED_RED_N
  R390    1      1 RESISTOR-G155-133R0-01,33OHM,1%   I146 @TIMECARD_LIB.TIMECARD(SCH_1):PAGE14
   U33   13   OUT5 IS32FL3207_QWLA3_TR_QFN29-A223A   I219 @TIMECARD_LIB.TIMECARD(SCH_1):PAGE14

SMA2_SIG_IN_BF_EN_N @TIMECARD_LIB.TIMECARD(SCH_1):SMA2_SIG_IN_BF_EN_N
   U24  L13 IO_L20N_T3_A19_15 XC7A200T_2FBG484C_FBG484-G240-A   I228 @TIMECARD_LIB.TIMECARD(SCH_1):PAGE162
   U16    7   2OE* 74HCT2G125DP_TSSOP8-G220-00055A   I273 @TIMECARD_LIB.TIMECARD(SCH_1):PAGE12
  R383    2      2 RESISTOR-G155-14701-01,4.7KOHMA   I281 @TIMECARD_LIB.TIMECARD(SCH_1):PAGE12
  TP29    1      1 TP_PIONT-TP010CT020B030_PTH-TPA  I1672 @TIMECARD_LIB.TIMECARD(SCH_1):PAGE16

SMA2_SIG_IO_CONN @TIMECARD_LIB.TIMECARD(SCH_1):SMA2_SIG_IO_CONN
   CR4    2    IO1 DIODE_4_V1-G122-10123-01   I179 @TIMECARD_LIB.TIMECARD(SCH_1):PAGE12
  R126    2      2 RESISTOR-G155-149R9-01,49.9OHMA   I276 @TIMECARD_LIB.TIMECARD(SCH_1):PAGE12
    J4    1      1 CONN_JACK_1P_GH4_S_TH-G200-130A   I300 @TIMECARD_LIB.TIMECARD(SCH_1):PAGE12

SMA2_SIG_OUT_BF_EN_N @TIMECARD_LIB.TIMECARD(SCH_1):SMA2_SIG_OUT_BF_EN_N
   U24  M13 IO_L20P_T3_A20_15 XC7A200T_2FBG484C_FBG484-G240-A   I228 @TIMECARD_LIB.TIMECARD(SCH_1):PAGE162
   U16    1   1OE* 74HCT2G125DP_TSSOP8-G220-00055A   I273 @TIMECARD_LIB.TIMECARD(SCH_1):PAGE12
  R331    2      2 RESISTOR-G155-14701-01,4.7KOHMA   I280 @TIMECARD_LIB.TIMECARD(SCH_1):PAGE12
  TP33    1      1 TP_PIONT-TP010CT020B030_PTH-TPA  I1669 @TIMECARD_LIB.TIMECARD(SCH_1):PAGE16

SMA3_LED_BLUE_N @TIMECARD_LIB.TIMECARD(SCH_1):SMA3_LED_BLUE_N
  R391    1      1 RESISTOR-G155-133R0-01,33OHM,1%   I150 @TIMECARD_LIB.TIMECARD(SCH_1):PAGE14
   U33   17   OUT9 IS32FL3207_QWLA3_TR_QFN29-A223A   I219 @TIMECARD_LIB.TIMECARD(SCH_1):PAGE14

SMA3_LED_GREEN_N @TIMECARD_LIB.TIMECARD(SCH_1):SMA3_LED_GREEN_N
  R392    1      1 RESISTOR-G155-133R0-01,33OHM,1%   I149 @TIMECARD_LIB.TIMECARD(SCH_1):PAGE14
   U33   15   OUT7 IS32FL3207_QWLA3_TR_QFN29-A223A   I219 @TIMECARD_LIB.TIMECARD(SCH_1):PAGE14

SMA3_LED_RED_N @TIMECARD_LIB.TIMECARD(SCH_1):SMA3_LED_RED_N
  R393    1      1 RESISTOR-G155-133R0-01,33OHM,1%   I151 @TIMECARD_LIB.TIMECARD(SCH_1):PAGE14
   U33   16   OUT8 IS32FL3207_QWLA3_TR_QFN29-A223A   I219 @TIMECARD_LIB.TIMECARD(SCH_1):PAGE14

SMA3_SIG_IN_BF_EN_N @TIMECARD_LIB.TIMECARD(SCH_1):SMA3_SIG_IN_BF_EN_N
   U24  H15 IO_L5N_T0_AD9N_15 XC7A200T_2FBG484C_FBG484-G240-A   I228 @TIMECARD_LIB.TIMECARD(SCH_1):PAGE162
   U13    7   2OE* 74HCT2G125DP_TSSOP8-G220-00055A   I204 @TIMECARD_LIB.TIMECARD(SCH_1):PAGE12
  R377    2      2 RESISTOR-G155-14701-01,4.7KOHMA   I206 @TIMECARD_LIB.TIMECARD(SCH_1):PAGE12
  TP30    1      1 TP_PIONT-TP010CT020B030_PTH-TPA  I1678 @TIMECARD_LIB.TIMECARD(SCH_1):PAGE16

SMA3_SIG_IO_CONN @TIMECARD_LIB.TIMECARD(SCH_1):SMA3_SIG_IO_CONN
   CR5    3    IO2 DIODE_4_V1-G122-10123-01    I42 @TIMECARD_LIB.TIMECARD(SCH_1):PAGE12
  R122    2      2 RESISTOR-G155-149R9-01,49.9OHMA   I197 @TIMECARD_LIB.TIMECARD(SCH_1):PAGE12
    J1    1      1 CONN_JACK_1P_GH4_S_TH-G200-130A   I290 @TIMECARD_LIB.TIMECARD(SCH_1):PAGE12

SMA3_SIG_OUT_BF_EN_N @TIMECARD_LIB.TIMECARD(SCH_1):SMA3_SIG_OUT_BF_EN_N
   U24  J15 IO_L5P_T0_AD9P_15 XC7A200T_2FBG484C_FBG484-G240-A   I228 @TIMECARD_LIB.TIMECARD(SCH_1):PAGE162
  R365    2      2 RESISTOR-G155-14701-01,4.7KOHMA    I88 @TIMECARD_LIB.TIMECARD(SCH_1):PAGE12
   U13    1   1OE* 74HCT2G125DP_TSSOP8-G220-00055A   I204 @TIMECARD_LIB.TIMECARD(SCH_1):PAGE12
  TP34    1      1 TP_PIONT-TP010CT020B030_PTH-TPA  I1673 @TIMECARD_LIB.TIMECARD(SCH_1):PAGE16

SMA4_LED_BLUE_N @TIMECARD_LIB.TIMECARD(SCH_1):SMA4_LED_BLUE_N
  R394    1      1 RESISTOR-G155-133R0-01,33OHM,1%   I153 @TIMECARD_LIB.TIMECARD(SCH_1):PAGE14
   U33   21  OUT12 IS32FL3207_QWLA3_TR_QFN29-A223A   I219 @TIMECARD_LIB.TIMECARD(SCH_1):PAGE14

SMA4_LED_GREEN_N @TIMECARD_LIB.TIMECARD(SCH_1):SMA4_LED_GREEN_N
  R395    1      1 RESISTOR-G155-133R0-01,33OHM,1%   I152 @TIMECARD_LIB.TIMECARD(SCH_1):PAGE14
   U33   19  OUT10 IS32FL3207_QWLA3_TR_QFN29-A223A   I219 @TIMECARD_LIB.TIMECARD(SCH_1):PAGE14

SMA4_LED_RED_N @TIMECARD_LIB.TIMECARD(SCH_1):SMA4_LED_RED_N
  R396    1      1 RESISTOR-G155-133R0-01,33OHM,1%   I154 @TIMECARD_LIB.TIMECARD(SCH_1):PAGE14
   U33   20  OUT11 IS32FL3207_QWLA3_TR_QFN29-A223A   I219 @TIMECARD_LIB.TIMECARD(SCH_1):PAGE14

SMA4_SIG_IN_BF_EN_N @TIMECARD_LIB.TIMECARD(SCH_1):SMA4_SIG_IN_BF_EN_N
   U24  J14 IO_L3P_T0_DQS_AD1P_15 XC7A200T_2FBG484C_FBG484-G240-A   I228 @TIMECARD_LIB.TIMECARD(SCH_1):PAGE162
   U14    7   2OE* 74HCT2G125DP_TSSOP8-G220-00055A   I226 @TIMECARD_LIB.TIMECARD(SCH_1):PAGE12
  R379    2      2 RESISTOR-G155-14701-01,4.7KOHMA   I234 @TIMECARD_LIB.TIMECARD(SCH_1):PAGE12
  TP31    1      1 TP_PIONT-TP010CT020B030_PTH-TPA  I1679 @TIMECARD_LIB.TIMECARD(SCH_1):PAGE16

SMA4_SIG_IO_CONN @TIMECARD_LIB.TIMECARD(SCH_1):SMA4_SIG_IO_CONN
   CR5    2    IO1 DIODE_4_V1-G122-10123-01    I42 @TIMECARD_LIB.TIMECARD(SCH_1):PAGE12
  R123    2      2 RESISTOR-G155-149R9-01,49.9OHMA   I228 @TIMECARD_LIB.TIMECARD(SCH_1):PAGE12
    J2    1      1 CONN_JACK_1P_GH4_S_TH-G200-130A   I294 @TIMECARD_LIB.TIMECARD(SCH_1):PAGE12

SMA4_SIG_OUT_BF_EN_N @TIMECARD_LIB.TIMECARD(SCH_1):SMA4_SIG_OUT_BF_EN_N
   U24  H14 IO_L3N_T0_DQS_AD1N_15 XC7A200T_2FBG484C_FBG484-G240-A   I228 @TIMECARD_LIB.TIMECARD(SCH_1):PAGE162
   U14    1   1OE* 74HCT2G125DP_TSSOP8-G220-00055A   I226 @TIMECARD_LIB.TIMECARD(SCH_1):PAGE12
  R368    2      2 RESISTOR-G155-14701-01,4.7KOHMA   I233 @TIMECARD_LIB.TIMECARD(SCH_1):PAGE12
  TP35    1      1 TP_PIONT-TP010CT020B030_PTH-TPA  I1675 @TIMECARD_LIB.TIMECARD(SCH_1):PAGE16

SMA_ANALOG_TUNING_IN @TIMECARD_LIB.TIMECARD(SCH_1):SMA_ANALOG_TUNING_IN
   R91    2      2 RESISTOR-G155-133R0-01,33OHM,1%   I187 @TIMECARD_LIB.TIMECARD(SCH_1):PAGE527
   J18    2      2 CONN_HDR_1X3_M_S_SMT-G205-1002A   I198 @TIMECARD_LIB.TIMECARD(SCH_1):PAGE527

SN_EEPROM_WP @TIMECARD_LIB.TIMECARD(SCH_1):SN_EEPROM_WP
    U7    5     WP AT24MAC402_SOT23_5-A221-00002-A    I89 @TIMECARD_LIB.TIMECARD(SCH_1):PAGE5
 R1992    2      2 RESISTOR-G155-14701-01,4.7KOHMA    I94 @TIMECARD_LIB.TIMECARD(SCH_1):PAGE5
  R344    1      1 RESISTOR-G155-14701-01,4.7KOHMA    I97 @TIMECARD_LIB.TIMECARD(SCH_1):PAGE5
   J17    1      1 CONN_HDR_2X2_M_S_SMT-G200-1068A   I127 @TIMECARD_LIB.TIMECARD(SCH_1):PAGE5
    R1    2      2 RESISTOR-G155-13300-01,330OHM,A   I130 @TIMECARD_LIB.TIMECARD(SCH_1):PAGE5
  TP19    1      1 TP_PIONT-TP010CT020B030_PTH-TPA  I1634 @TIMECARD_LIB.TIMECARD(SCH_1):PAGE16

UART_FT4232_RX_FPGA_TX @TIMECARD_LIB.TIMECARD(SCH_1):UART_FT4232_RX_FPGA_TX
   U24  P15 IO_L22P_T3_A05_D21_14 XC7A200T_2FBG484C_FBG484-G240-A     I2 @TIMECARD_LIB.TIMECARD(SCH_1):PAGE161
  R352    2      2 RESISTOR-G155-11000-01,100OHM,A   I154 @TIMECARD_LIB.TIMECARD(SCH_1):PAGE524

UART_FT4232_TX_FPGA_RX @TIMECARD_LIB.TIMECARD(SCH_1):UART_FT4232_TX_FPGA_RX
   U24  P16 IO_L24P_T3_A01_D17_14 XC7A200T_2FBG484C_FBG484-G240-A     I2 @TIMECARD_LIB.TIMECARD(SCH_1):PAGE161
  R480    1      1 RESISTOR-G155-11003-01,100KOHMA   I149 @TIMECARD_LIB.TIMECARD(SCH_1):PAGE524
  R353    2      2 RESISTOR-G155-11000-01,100OHM,A   I153 @TIMECARD_LIB.TIMECARD(SCH_1):PAGE524

UART_GPS_RX_FPGA_TX @TIMECARD_LIB.TIMECARD(SCH_1):UART_GPS_RX_FPGA_TX
  R110    1      1 RESISTOR-G155-133R0-01,33OHM,1%    I29 @TIMECARD_LIB.TIMECARD(SCH_1):PAGE11
   U24  P20 IO_0_14 XC7A200T_2FBG484C_FBG484-G240-A     I2 @TIMECARD_LIB.TIMECARD(SCH_1):PAGE161

UART_GPS_TX_FPGA_RX @TIMECARD_LIB.TIMECARD(SCH_1):UART_GPS_TX_FPGA_RX
  R109    1      1 RESISTOR-G155-133R0-01,33OHM,1%    I11 @TIMECARD_LIB.TIMECARD(SCH_1):PAGE11
   U24  N15 IO_25_14 XC7A200T_2FBG484C_FBG484-G240-A     I2 @TIMECARD_LIB.TIMECARD(SCH_1):PAGE161
  R269    2      2 RESISTOR-G155-11003-01,100KOHMA    I40 @TIMECARD_LIB.TIMECARD(SCH_1):PAGE11

UART_MAC_RX_FPGA_TX @TIMECARD_LIB.TIMECARD(SCH_1):UART_MAC_RX_FPGA_TX
   U24 AA18 IO_L17P_T2_A14_D30_14 XC7A200T_2FBG484C_FBG484-G240-A     I2 @TIMECARD_LIB.TIMECARD(SCH_1):PAGE161
   R95    2      2 RESISTOR-G155-133R0-01,33OHM,1%    I52 @TIMECARD_LIB.TIMECARD(SCH_1):PAGE527

UART_MAC_TX_FPGA_RX @TIMECARD_LIB.TIMECARD(SCH_1):UART_MAC_TX_FPGA_RX
   U24 AB18 IO_L17N_T2_A13_D29_14 XC7A200T_2FBG484C_FBG484-G240-A     I2 @TIMECARD_LIB.TIMECARD(SCH_1):PAGE161
   R94    2      2 RESISTOR-G155-133R0-01,33OHM,1%    I54 @TIMECARD_LIB.TIMECARD(SCH_1):PAGE527
  R265    2      2 RESISTOR-G155-11003-01,100KOHMA   I221 @TIMECARD_LIB.TIMECARD(SCH_1):PAGE527

UNNAMED_127_G2001028301_I427_4 @TIMECARD_LIB.TIMECARD(SCH_1):UNNAMED_127_G2001028301_I427_4
   J14    4      4 G200_10283_01-G200-10283-01   I427 @TIMECARD_LIB.TIMECARD(SCH_1):PAGE127
  R133    2      2 RESISTOR-G155-133R0-01,33OHM,1%   I446 @TIMECARD_LIB.TIMECARD(SCH_1):PAGE127

UNNAMED_127_MT25QL128ABA1ESESOP @TIMECARD_LIB.TIMECARD(SCH_1):UNNAMED_127_MT25QL128ABA1ESESOP8_I456_DQ0
   U23    5    DQ0 MT25QL128ABA1ESE_SOP8-G221-102A   I456 @TIMECARD_LIB.TIMECARD(SCH_1):PAGE127
  R199    1      1 RESISTOR-G155-14701-01,4.7KOHMA   I462 @TIMECARD_LIB.TIMECARD(SCH_1):PAGE127
  R203    1      1 RESISTOR-G155-133R0-01,33OHM,1%   I467 @TIMECARD_LIB.TIMECARD(SCH_1):PAGE127

UNNAMED_127_MT25QL128ABA1ESES_1 @TIMECARD_LIB.TIMECARD(SCH_1):UNNAMED_127_MT25QL128ABA1ESESOP8_I456_DQ1
   U23    2    DQ1 MT25QL128ABA1ESE_SOP8-G221-102A   I456 @TIMECARD_LIB.TIMECARD(SCH_1):PAGE127
  R200    1      1 RESISTOR-G155-14701-01,4.7KOHMA   I465 @TIMECARD_LIB.TIMECARD(SCH_1):PAGE127
  R204    1      1 RESISTOR-G155-133R0-01,33OHM,1%   I466 @TIMECARD_LIB.TIMECARD(SCH_1):PAGE127

UNNAMED_127_MT25QL128ABA1ESES_2 @TIMECARD_LIB.TIMECARD(SCH_1):UNNAMED_127_MT25QL128ABA1ESESOP8_I456_HOLD
   U23    7 HOLD/DQ3* MT25QL128ABA1ESE_SOP8-G221-102A   I456 @TIMECARD_LIB.TIMECARD(SCH_1):PAGE127
  R202    1      1 RESISTOR-G155-14701-01,4.7KOHMA   I464 @TIMECARD_LIB.TIMECARD(SCH_1):PAGE127
  R206    1      1 RESISTOR-G155-133R0-01,33OHM,1%   I469 @TIMECARD_LIB.TIMECARD(SCH_1):PAGE127

UNNAMED_127_MT25QL128ABA1ESES_3 @TIMECARD_LIB.TIMECARD(SCH_1):UNNAMED_127_MT25QL128ABA1ESESOP8_I456_W
   U23    3 W/DQ2* MT25QL128ABA1ESE_SOP8-G221-102A   I456 @TIMECARD_LIB.TIMECARD(SCH_1):PAGE127
  R201    1      1 RESISTOR-G155-14701-01,4.7KOHMA   I463 @TIMECARD_LIB.TIMECARD(SCH_1):PAGE127
  R205    1      1 RESISTOR-G155-133R0-01,33OHM,1%   I468 @TIMECARD_LIB.TIMECARD(SCH_1):PAGE127

UNNAMED_12_74HCT2G125DPTSSOP8_3 @TIMECARD_LIB.TIMECARD(SCH_1):UNNAMED_12_74HCT2G125DPTSSOP8_I226_1A
   U14    2     1A 74HCT2G125DP_TSSOP8-G220-00055A   I226 @TIMECARD_LIB.TIMECARD(SCH_1):PAGE12
  R157    2      2 RESISTOR-G155-11000-01,100OHM,A   I237 @TIMECARD_LIB.TIMECARD(SCH_1):PAGE12
  R493    2      2 RESISTOR-G155-100R0-J0,0OHM,-   I323 @TIMECARD_LIB.TIMECARD(SCH_1):PAGE12

UNNAMED_12_74HCT2G125DPTSSOP8_6 @TIMECARD_LIB.TIMECARD(SCH_1):UNNAMED_12_74HCT2G125DPTSSOP8_I255_1A
   U15    2     1A 74HCT2G125DP_TSSOP8-G220-00055A   I255 @TIMECARD_LIB.TIMECARD(SCH_1):PAGE12
  R120    2      2 RESISTOR-G155-11000-01,100OHM,A   I265 @TIMECARD_LIB.TIMECARD(SCH_1):PAGE12
  R494    2      2 RESISTOR-G155-100R0-J0,0OHM,-   I326 @TIMECARD_LIB.TIMECARD(SCH_1):PAGE12

UNNAMED_12_74HCT2G125DPTSSOP8_9 @TIMECARD_LIB.TIMECARD(SCH_1):UNNAMED_12_74HCT2G125DPTSSOP8_I273_1A
   U16    2     1A 74HCT2G125DP_TSSOP8-G220-00055A   I273 @TIMECARD_LIB.TIMECARD(SCH_1):PAGE12
  R121    2      2 RESISTOR-G155-11000-01,100OHM,A   I284 @TIMECARD_LIB.TIMECARD(SCH_1):PAGE12
  R495    2      2 RESISTOR-G155-100R0-J0,0OHM,-   I330 @TIMECARD_LIB.TIMECARD(SCH_1):PAGE12

UNNAMED_12_74HCT2G125DPTSSOP8_I @TIMECARD_LIB.TIMECARD(SCH_1):UNNAMED_12_74HCT2G125DPTSSOP8_I204_1A
  R156    2      2 RESISTOR-G155-11000-01,100OHM,A    I63 @TIMECARD_LIB.TIMECARD(SCH_1):PAGE12
   U13    2     1A 74HCT2G125DP_TSSOP8-G220-00055A   I204 @TIMECARD_LIB.TIMECARD(SCH_1):PAGE12
  R492    2      2 RESISTOR-G155-100R0-J0,0OHM,-   I319 @TIMECARD_LIB.TIMECARD(SCH_1):PAGE12

UNNAMED_12_CAPACITOR_I318_2 @TIMECARD_LIB.TIMECARD(SCH_1):UNNAMED_12_CAPACITOR_I318_2
  C310    2      2 CAPACITOR-G104-0A180-FJ,18PF,5%   I318 @TIMECARD_LIB.TIMECARD(SCH_1):PAGE12
  R492    1      1 RESISTOR-G155-100R0-J0,0OHM,-   I319 @TIMECARD_LIB.TIMECARD(SCH_1):PAGE12

UNNAMED_12_CAPACITOR_I321_2 @TIMECARD_LIB.TIMECARD(SCH_1):UNNAMED_12_CAPACITOR_I321_2
  R493    1      1 RESISTOR-G155-100R0-J0,0OHM,-   I323 @TIMECARD_LIB.TIMECARD(SCH_1):PAGE12
  C311    2      2 CAPACITOR-G104-0A180-FJ,18PF,5%   I321 @TIMECARD_LIB.TIMECARD(SCH_1):PAGE12

UNNAMED_12_CAPACITOR_I328_2 @TIMECARD_LIB.TIMECARD(SCH_1):UNNAMED_12_CAPACITOR_I328_2
  R494    1      1 RESISTOR-G155-100R0-J0,0OHM,-   I326 @TIMECARD_LIB.TIMECARD(SCH_1):PAGE12
  C317    2      2 CAPACITOR-G104-0A180-FJ,18PF,5%   I328 @TIMECARD_LIB.TIMECARD(SCH_1):PAGE12

UNNAMED_12_CAPACITOR_I332_2 @TIMECARD_LIB.TIMECARD(SCH_1):UNNAMED_12_CAPACITOR_I332_2
  R495    1      1 RESISTOR-G155-100R0-J0,0OHM,-   I330 @TIMECARD_LIB.TIMECARD(SCH_1):PAGE12
  C318    2      2 CAPACITOR-G104-0A180-FJ,18PF,5%   I332 @TIMECARD_LIB.TIMECARD(SCH_1):PAGE12

UNNAMED_14_IS32FL3207QWLA3TRQFN @TIMECARD_LIB.TIMECARD(SCH_1):UNNAMED_14_IS32FL3207QWLA3TRQFN29_I219_AD
   U33    2     AD IS32FL3207_QWLA3_TR_QFN29-A223A   I219 @TIMECARD_LIB.TIMECARD(SCH_1):PAGE14
  R324    2      2 RESISTOR-G155-100R0-J0,0OHM,-   I247 @TIMECARD_LIB.TIMECARD(SCH_1):PAGE14

UNNAMED_14_IS32FL3207QWLA3TRQ_1 @TIMECARD_LIB.TIMECARD(SCH_1):UNNAMED_14_IS32FL3207QWLA3TRQFN29_I219_ISET
   U33    5   ISET IS32FL3207_QWLA3_TR_QFN29-A223A   I219 @TIMECARD_LIB.TIMECARD(SCH_1):PAGE14
  R323    1      1 RESISTOR-G155-14701-01,4.7KOHMA   I246 @TIMECARD_LIB.TIMECARD(SCH_1):PAGE14

UNNAMED_14_LED4PV14_I265_1 @TIMECARD_LIB.TIMECARD(SCH_1):UNNAMED_14_LED4PV14_I265_1
  R385    2      2 RESISTOR-G155-133R0-01,33OHM,1%   I107 @TIMECARD_LIB.TIMECARD(SCH_1):PAGE14
  R124    2      2 RESISTOR-G155-11000-01,100OHM,A   I160 @TIMECARD_LIB.TIMECARD(SCH_1):PAGE14
  DS14    1      1 LED_4P_V14-G170-10189-01   I265 @TIMECARD_LIB.TIMECARD(SCH_1):PAGE14

UNNAMED_14_LED4PV14_I265_3 @TIMECARD_LIB.TIMECARD(SCH_1):UNNAMED_14_LED4PV14_I265_3
  R387    2      2 RESISTOR-G155-133R0-01,33OHM,1%   I110 @TIMECARD_LIB.TIMECARD(SCH_1):PAGE14
  R272    2      2 RESISTOR-G155-11000-01,100OHM,A   I163 @TIMECARD_LIB.TIMECARD(SCH_1):PAGE14
  DS14    3      3 LED_4P_V14-G170-10189-01   I265 @TIMECARD_LIB.TIMECARD(SCH_1):PAGE14

UNNAMED_14_LED4PV14_I265_4 @TIMECARD_LIB.TIMECARD(SCH_1):UNNAMED_14_LED4PV14_I265_4
  R386    2      2 RESISTOR-G155-133R0-01,33OHM,1%   I108 @TIMECARD_LIB.TIMECARD(SCH_1):PAGE14
  R125    2      2 RESISTOR-G155-11000-01,100OHM,A   I161 @TIMECARD_LIB.TIMECARD(SCH_1):PAGE14
  DS14    4      4 LED_4P_V14-G170-10189-01   I265 @TIMECARD_LIB.TIMECARD(SCH_1):PAGE14

UNNAMED_14_LED4PV14_I266_1 @TIMECARD_LIB.TIMECARD(SCH_1):UNNAMED_14_LED4PV14_I266_1
  R388    2      2 RESISTOR-G155-133R0-01,33OHM,1%   I147 @TIMECARD_LIB.TIMECARD(SCH_1):PAGE14
  R273    2      2 RESISTOR-G155-11000-01,100OHM,A   I165 @TIMECARD_LIB.TIMECARD(SCH_1):PAGE14
  DS15    1      1 LED_4P_V14-G170-10189-01   I266 @TIMECARD_LIB.TIMECARD(SCH_1):PAGE14

UNNAMED_14_LED4PV14_I266_3 @TIMECARD_LIB.TIMECARD(SCH_1):UNNAMED_14_LED4PV14_I266_3
  R390    2      2 RESISTOR-G155-133R0-01,33OHM,1%   I146 @TIMECARD_LIB.TIMECARD(SCH_1):PAGE14
  R373    2      2 RESISTOR-G155-11000-01,100OHM,A   I181 @TIMECARD_LIB.TIMECARD(SCH_1):PAGE14
  DS15    3      3 LED_4P_V14-G170-10189-01   I266 @TIMECARD_LIB.TIMECARD(SCH_1):PAGE14

UNNAMED_14_LED4PV14_I266_4 @TIMECARD_LIB.TIMECARD(SCH_1):UNNAMED_14_LED4PV14_I266_4
  R389    2      2 RESISTOR-G155-133R0-01,33OHM,1%   I148 @TIMECARD_LIB.TIMECARD(SCH_1):PAGE14
  R274    2      2 RESISTOR-G155-11000-01,100OHM,A   I171 @TIMECARD_LIB.TIMECARD(SCH_1):PAGE14
  DS15    4      4 LED_4P_V14-G170-10189-01   I266 @TIMECARD_LIB.TIMECARD(SCH_1):PAGE14

UNNAMED_14_LED4PV14_I267_1 @TIMECARD_LIB.TIMECARD(SCH_1):UNNAMED_14_LED4PV14_I267_1
  R391    2      2 RESISTOR-G155-133R0-01,33OHM,1%   I150 @TIMECARD_LIB.TIMECARD(SCH_1):PAGE14
  R374    2      2 RESISTOR-G155-11000-01,100OHM,A   I168 @TIMECARD_LIB.TIMECARD(SCH_1):PAGE14
  DS16    1      1 LED_4P_V14-G170-10189-01   I267 @TIMECARD_LIB.TIMECARD(SCH_1):PAGE14

UNNAMED_14_LED4PV14_I267_3 @TIMECARD_LIB.TIMECARD(SCH_1):UNNAMED_14_LED4PV14_I267_3
  R393    2      2 RESISTOR-G155-133R0-01,33OHM,1%   I151 @TIMECARD_LIB.TIMECARD(SCH_1):PAGE14
  R376    2      2 RESISTOR-G155-11000-01,100OHM,A   I184 @TIMECARD_LIB.TIMECARD(SCH_1):PAGE14
  DS16    3      3 LED_4P_V14-G170-10189-01   I267 @TIMECARD_LIB.TIMECARD(SCH_1):PAGE14

UNNAMED_14_LED4PV14_I267_4 @TIMECARD_LIB.TIMECARD(SCH_1):UNNAMED_14_LED4PV14_I267_4
  R392    2      2 RESISTOR-G155-133R0-01,33OHM,1%   I149 @TIMECARD_LIB.TIMECARD(SCH_1):PAGE14
  R375    2      2 RESISTOR-G155-11000-01,100OHM,A   I174 @TIMECARD_LIB.TIMECARD(SCH_1):PAGE14
  DS16    4      4 LED_4P_V14-G170-10189-01   I267 @TIMECARD_LIB.TIMECARD(SCH_1):PAGE14

UNNAMED_14_LED4PV14_I268_1 @TIMECARD_LIB.TIMECARD(SCH_1):UNNAMED_14_LED4PV14_I268_1
  R394    2      2 RESISTOR-G155-133R0-01,33OHM,1%   I153 @TIMECARD_LIB.TIMECARD(SCH_1):PAGE14
  R400    2      2 RESISTOR-G155-11000-01,100OHM,A   I177 @TIMECARD_LIB.TIMECARD(SCH_1):PAGE14
  DS17    1      1 LED_4P_V14-G170-10189-01   I268 @TIMECARD_LIB.TIMECARD(SCH_1):PAGE14

UNNAMED_14_LED4PV14_I268_3 @TIMECARD_LIB.TIMECARD(SCH_1):UNNAMED_14_LED4PV14_I268_3
  R396    2      2 RESISTOR-G155-133R0-01,33OHM,1%   I154 @TIMECARD_LIB.TIMECARD(SCH_1):PAGE14
  R424    2      2 RESISTOR-G155-11000-01,100OHM,A   I186 @TIMECARD_LIB.TIMECARD(SCH_1):PAGE14
  DS17    3      3 LED_4P_V14-G170-10189-01   I268 @TIMECARD_LIB.TIMECARD(SCH_1):PAGE14

UNNAMED_14_LED4PV14_I268_4 @TIMECARD_LIB.TIMECARD(SCH_1):UNNAMED_14_LED4PV14_I268_4
  R395    2      2 RESISTOR-G155-133R0-01,33OHM,1%   I152 @TIMECARD_LIB.TIMECARD(SCH_1):PAGE14
  R401    2      2 RESISTOR-G155-11000-01,100OHM,A   I176 @TIMECARD_LIB.TIMECARD(SCH_1):PAGE14
  DS17    4      4 LED_4P_V14-G170-10189-01   I268 @TIMECARD_LIB.TIMECARD(SCH_1):PAGE14

UNNAMED_14_LED4PV14_I269_1 @TIMECARD_LIB.TIMECARD(SCH_1):UNNAMED_14_LED4PV14_I269_1
  R397    2      2 RESISTOR-G155-133R0-01,33OHM,1%   I156 @TIMECARD_LIB.TIMECARD(SCH_1):PAGE14
  R425    2      2 RESISTOR-G155-11000-01,100OHM,A   I170 @TIMECARD_LIB.TIMECARD(SCH_1):PAGE14
  DS18    1      1 LED_4P_V14-G170-10189-01   I269 @TIMECARD_LIB.TIMECARD(SCH_1):PAGE14

UNNAMED_14_LED4PV14_I269_3 @TIMECARD_LIB.TIMECARD(SCH_1):UNNAMED_14_LED4PV14_I269_3
  R399    2      2 RESISTOR-G155-133R0-01,33OHM,1%   I157 @TIMECARD_LIB.TIMECARD(SCH_1):PAGE14
  R427    2      2 RESISTOR-G155-11000-01,100OHM,A   I188 @TIMECARD_LIB.TIMECARD(SCH_1):PAGE14
  DS18    3      3 LED_4P_V14-G170-10189-01   I269 @TIMECARD_LIB.TIMECARD(SCH_1):PAGE14

UNNAMED_14_LED4PV14_I269_4 @TIMECARD_LIB.TIMECARD(SCH_1):UNNAMED_14_LED4PV14_I269_4
  R398    2      2 RESISTOR-G155-133R0-01,33OHM,1%   I155 @TIMECARD_LIB.TIMECARD(SCH_1):PAGE14
  R426    2      2 RESISTOR-G155-11000-01,100OHM,A   I179 @TIMECARD_LIB.TIMECARD(SCH_1):PAGE14
  DS18    4      4 LED_4P_V14-G170-10189-01   I269 @TIMECARD_LIB.TIMECARD(SCH_1):PAGE14

UNNAMED_14_OPTICAL_I11_A @TIMECARD_LIB.TIMECARD(SCH_1):UNNAMED_14_OPTICAL_I11_A
   DS2    A      A OPTICAL-G170-10143-01    I11 @TIMECARD_LIB.TIMECARD(SCH_1):PAGE14
  R258    1      1 RESISTOR-G155-13300-01,330OHM,A    I68 @TIMECARD_LIB.TIMECARD(SCH_1):PAGE14

UNNAMED_14_OPTICAL_I12_A @TIMECARD_LIB.TIMECARD(SCH_1):UNNAMED_14_OPTICAL_I12_A
   DS1    A      A OPTICAL-G170-10143-01    I12 @TIMECARD_LIB.TIMECARD(SCH_1):PAGE14
  R257    1      1 RESISTOR-G155-13300-01,330OHM,A    I67 @TIMECARD_LIB.TIMECARD(SCH_1):PAGE14

UNNAMED_14_OPTICAL_I136_A @TIMECARD_LIB.TIMECARD(SCH_1):UNNAMED_14_OPTICAL_I136_A
  R259    1      1 RESISTOR-G155-13300-01,330OHM,A    I69 @TIMECARD_LIB.TIMECARD(SCH_1):PAGE14
   DS3    A      A OPTICAL-G170-10143-01   I136 @TIMECARD_LIB.TIMECARD(SCH_1):PAGE14

UNNAMED_14_OPTICAL_I137_A @TIMECARD_LIB.TIMECARD(SCH_1):UNNAMED_14_OPTICAL_I137_A
  R261    1      1 RESISTOR-G155-13300-01,330OHM,A    I70 @TIMECARD_LIB.TIMECARD(SCH_1):PAGE14
   DS4    A      A OPTICAL-G170-10143-01   I137 @TIMECARD_LIB.TIMECARD(SCH_1):PAGE14

UNNAMED_14_OPTICAL_I138_A @TIMECARD_LIB.TIMECARD(SCH_1):UNNAMED_14_OPTICAL_I138_A
  R279    1      1 RESISTOR-G155-13300-01,330OHM,A    I72 @TIMECARD_LIB.TIMECARD(SCH_1):PAGE14
  DS10    A      A OPTICAL-G170-10143-01   I138 @TIMECARD_LIB.TIMECARD(SCH_1):PAGE14

UNNAMED_14_OPTICAL_I139_A @TIMECARD_LIB.TIMECARD(SCH_1):UNNAMED_14_OPTICAL_I139_A
  R280    1      1 RESISTOR-G155-13300-01,330OHM,A    I74 @TIMECARD_LIB.TIMECARD(SCH_1):PAGE14
  DS11    A      A OPTICAL-G170-10143-01   I139 @TIMECARD_LIB.TIMECARD(SCH_1):PAGE14

UNNAMED_14_OPTICAL_I140_A @TIMECARD_LIB.TIMECARD(SCH_1):UNNAMED_14_OPTICAL_I140_A
  R138    1      1 RESISTOR-G155-13300-01,330OHM,A    I63 @TIMECARD_LIB.TIMECARD(SCH_1):PAGE14
   DS6    A      A OPTICAL-G170-10143-01   I140 @TIMECARD_LIB.TIMECARD(SCH_1):PAGE14

UNNAMED_14_OPTICAL_I141_A @TIMECARD_LIB.TIMECARD(SCH_1):UNNAMED_14_OPTICAL_I141_A
  R108    1      1 RESISTOR-G155-11000-01,100OHM,A    I58 @TIMECARD_LIB.TIMECARD(SCH_1):PAGE14
   DS7    A      A OPTICAL-G170-10143-01   I141 @TIMECARD_LIB.TIMECARD(SCH_1):PAGE14

UNNAMED_14_OPTICAL_I142_A @TIMECARD_LIB.TIMECARD(SCH_1):UNNAMED_14_OPTICAL_I142_A
  R180    1      1 RESISTOR-G155-11001-01,1KOHM,1%    I44 @TIMECARD_LIB.TIMECARD(SCH_1):PAGE14
   DS8    A      A OPTICAL-G170-10143-01   I142 @TIMECARD_LIB.TIMECARD(SCH_1):PAGE14

UNNAMED_14_OPTICAL_I143_A @TIMECARD_LIB.TIMECARD(SCH_1):UNNAMED_14_OPTICAL_I143_A
  R256    1      1 RESISTOR-G155-11001-01,1KOHM,1%    I65 @TIMECARD_LIB.TIMECARD(SCH_1):PAGE14
   DS5    A      A OPTICAL-G170-10143-01   I143 @TIMECARD_LIB.TIMECARD(SCH_1):PAGE14

UNNAMED_14_OPTICAL_I191_A @TIMECARD_LIB.TIMECARD(SCH_1):UNNAMED_14_OPTICAL_I191_A
  R118    1      1 RESISTOR-G155-13300-01,330OHM,A   I190 @TIMECARD_LIB.TIMECARD(SCH_1):PAGE14
  DS19    A      A OPTICAL-G170-10143-01   I191 @TIMECARD_LIB.TIMECARD(SCH_1):PAGE14

UNNAMED_14_OPTICAL_I194_A @TIMECARD_LIB.TIMECARD(SCH_1):UNNAMED_14_OPTICAL_I194_A
  R119    1      1 RESISTOR-G155-13300-01,330OHM,A   I192 @TIMECARD_LIB.TIMECARD(SCH_1):PAGE14
  DS20    A      A OPTICAL-G170-10143-01   I194 @TIMECARD_LIB.TIMECARD(SCH_1):PAGE14

UNNAMED_14_OPTICAL_I289_A @TIMECARD_LIB.TIMECARD(SCH_1):UNNAMED_14_OPTICAL_I289_A
  R169    1      1 RESISTOR-G155-13300-01,330OHM,A   I288 @TIMECARD_LIB.TIMECARD(SCH_1):PAGE14
  DS12    A      A OPTICAL-G170-10143-01   I289 @TIMECARD_LIB.TIMECARD(SCH_1):PAGE14

UNNAMED_14_OPTICAL_I292_A @TIMECARD_LIB.TIMECARD(SCH_1):UNNAMED_14_OPTICAL_I292_A
   DS9    A      A OPTICAL-G170-10143-01   I292 @TIMECARD_LIB.TIMECARD(SCH_1):PAGE14
  R208    1      1 RESISTOR-G155-13300-01,330OHM,A   I293 @TIMECARD_LIB.TIMECARD(SCH_1):PAGE14

UNNAMED_14_RESISTOR_I58_2 @TIMECARD_LIB.TIMECARD(SCH_1):UNNAMED_14_RESISTOR_I58_2
  R108    2      2 RESISTOR-G155-11000-01,100OHM,A    I58 @TIMECARD_LIB.TIMECARD(SCH_1):PAGE14
  R139    1      1 RESISTOR-G155-133R0-01,33OHM,1%    I60 @TIMECARD_LIB.TIMECARD(SCH_1):PAGE14

UNNAMED_14_RESISTOR_I65_2 @TIMECARD_LIB.TIMECARD(SCH_1):UNNAMED_14_RESISTOR_I65_2
  R256    2      2 RESISTOR-G155-11001-01,1KOHM,1%    I65 @TIMECARD_LIB.TIMECARD(SCH_1):PAGE14
  R262    1      1 RESISTOR-G155-11001-01,1KOHM,1%    I66 @TIMECARD_LIB.TIMECARD(SCH_1):PAGE14

UNNAMED_15_MP5022CGQVZQFN22_I21 @TIMECARD_LIB.TIMECARD(SCH_1):UNNAMED_15_MP5022CGQVZQFN22_I212_ENTM
    R8    2      2 RESISTOR-G155-100R0-J0,0OHM,-   I173 @TIMECARD_LIB.TIMECARD(SCH_1):PAGE15
    U1    3   ENTM MP5022CGQV_Z_QFN22-G220-10510-A   I212 @TIMECARD_LIB.TIMECARD(SCH_1):PAGE15

UNNAMED_15_MP5022CGQVZQFN22_I_2 @TIMECARD_LIB.TIMECARD(SCH_1):UNNAMED_15_MP5022CGQVZQFN22_I212_LOADEN
    R7    2      2 RESISTOR-G155-100R0-J0,0OHM,-   I174 @TIMECARD_LIB.TIMECARD(SCH_1):PAGE15
    U1    2 LOADEN MP5022CGQV_Z_QFN22-G220-10510-A   I212 @TIMECARD_LIB.TIMECARD(SCH_1):PAGE15

UNNAMED_16_CONNHDR2X6FSSMT_I161 @TIMECARD_LIB.TIMECARD(SCH_1):UNNAMED_16_CONNHDR2X6FSSMT_I1614_1
    J5    1      1 CONN_HDR_2X6_F_S_SMT-G200-1313A  I1614 @TIMECARD_LIB.TIMECARD(SCH_1):PAGE16
  R430    2      2 RESISTOR-G155-133R0-01,33OHM,1%  I1706 @TIMECARD_LIB.TIMECARD(SCH_1):PAGE16

UNNAMED_16_CONNHDR2X6FSSMT_I1_1 @TIMECARD_LIB.TIMECARD(SCH_1):UNNAMED_16_CONNHDR2X6FSSMT_I1614_2
    J5    2      2 CONN_HDR_2X6_F_S_SMT-G200-1313A  I1614 @TIMECARD_LIB.TIMECARD(SCH_1):PAGE16
  R434    1      1 RESISTOR-G155-133R0-01,33OHM,1%  I1721 @TIMECARD_LIB.TIMECARD(SCH_1):PAGE16

UNNAMED_16_CONNHDR2X6FSSMT_I1_2 @TIMECARD_LIB.TIMECARD(SCH_1):UNNAMED_16_CONNHDR2X6FSSMT_I1614_3
    J5    3      3 CONN_HDR_2X6_F_S_SMT-G200-1313A  I1614 @TIMECARD_LIB.TIMECARD(SCH_1):PAGE16
  R429    2      2 RESISTOR-G155-133R0-01,33OHM,1%  I1709 @TIMECARD_LIB.TIMECARD(SCH_1):PAGE16

UNNAMED_16_CONNHDR2X6FSSMT_I1_3 @TIMECARD_LIB.TIMECARD(SCH_1):UNNAMED_16_CONNHDR2X6FSSMT_I1614_4
    J5    4      4 CONN_HDR_2X6_F_S_SMT-G200-1313A  I1614 @TIMECARD_LIB.TIMECARD(SCH_1):PAGE16
  R433    1      1 RESISTOR-G155-133R0-01,33OHM,1%  I1720 @TIMECARD_LIB.TIMECARD(SCH_1):PAGE16

UNNAMED_16_CONNHDR2X6FSSMT_I1_4 @TIMECARD_LIB.TIMECARD(SCH_1):UNNAMED_16_CONNHDR2X6FSSMT_I1614_7
    J5    7      7 CONN_HDR_2X6_F_S_SMT-G200-1313A  I1614 @TIMECARD_LIB.TIMECARD(SCH_1):PAGE16
  R329    2      2 RESISTOR-G155-133R0-01,33OHM,1%  I1707 @TIMECARD_LIB.TIMECARD(SCH_1):PAGE16

UNNAMED_16_CONNHDR2X6FSSMT_I1_5 @TIMECARD_LIB.TIMECARD(SCH_1):UNNAMED_16_CONNHDR2X6FSSMT_I1614_8
    J5    8      8 CONN_HDR_2X6_F_S_SMT-G200-1313A  I1614 @TIMECARD_LIB.TIMECARD(SCH_1):PAGE16
  R431    1      1 RESISTOR-G155-133R0-01,33OHM,1%  I1718 @TIMECARD_LIB.TIMECARD(SCH_1):PAGE16

UNNAMED_16_CONNHDR2X6FSSMT_I1_6 @TIMECARD_LIB.TIMECARD(SCH_1):UNNAMED_16_CONNHDR2X6FSSMT_I1614_5
    J5    5      5 CONN_HDR_2X6_F_S_SMT-G200-1313A  I1614 @TIMECARD_LIB.TIMECARD(SCH_1):PAGE16
  R428    2      2 RESISTOR-G155-133R0-01,33OHM,1%  I1708 @TIMECARD_LIB.TIMECARD(SCH_1):PAGE16

UNNAMED_16_CONNHDR2X6FSSMT_I1_7 @TIMECARD_LIB.TIMECARD(SCH_1):UNNAMED_16_CONNHDR2X6FSSMT_I1614_6
    J5    6      6 CONN_HDR_2X6_F_S_SMT-G200-1313A  I1614 @TIMECARD_LIB.TIMECARD(SCH_1):PAGE16
  R432    1      1 RESISTOR-G155-133R0-01,33OHM,1%  I1719 @TIMECARD_LIB.TIMECARD(SCH_1):PAGE16

UNNAMED_3_CONN64PGF_I61_PRSNT21 @TIMECARD_LIB.TIMECARD(SCH_1):UNNAMED_3_CONN64PGF_I61_PRSNT21
   R22    2      2 RESISTOR-G155-100R0-J0,0OHM,-    I16 @TIMECARD_LIB.TIMECARD(SCH_1):PAGE3
   GF1  B17 PRSNT2_1* CONN_64P_GF-S_M_EF64_PCIE_P039A    I61 @TIMECARD_LIB.TIMECARD(SCH_1):PAGE3

UNNAMED_3_CONN64PGF_I61_PRSNT22 @TIMECARD_LIB.TIMECARD(SCH_1):UNNAMED_3_CONN64PGF_I61_PRSNT22
   R23    2      2 RESISTOR-G155-100R0-J0,0OHM,-    I15 @TIMECARD_LIB.TIMECARD(SCH_1):PAGE3
   GF1  B31 PRSNT2_2* CONN_64P_GF-S_M_EF64_PCIE_P039A    I61 @TIMECARD_LIB.TIMECARD(SCH_1):PAGE3

UNNAMED_3_G2201019801_I100_EN @TIMECARD_LIB.TIMECARD(SCH_1):UNNAMED_3_G2201019801_I100_EN
    U2    1     EN G220_10198_01-G223-10197-01   I100 @TIMECARD_LIB.TIMECARD(SCH_1):PAGE3
   R25    2      2 RESISTOR-G155-14701-01,4.7KOHMA   I103 @TIMECARD_LIB.TIMECARD(SCH_1):PAGE3
  R354    2      2 RESISTOR-G155-133R0-01,33OHM,1%   I114 @TIMECARD_LIB.TIMECARD(SCH_1):PAGE3

UNNAMED_3_RESISTOR_I151_2 @TIMECARD_LIB.TIMECARD(SCH_1):UNNAMED_3_RESISTOR_I151_2
   U34    4     CT TPS3808G18DBVR_SOT23_6-G222-00A   I139 @TIMECARD_LIB.TIMECARD(SCH_1):PAGE3
  R164    2      2 RESISTOR-G155-11003-01,100KOHMA   I151 @TIMECARD_LIB.TIMECARD(SCH_1):PAGE3
  C250    1      1 CAPACITOR-G105-0B104-EK,0.1UF,A   I152 @TIMECARD_LIB.TIMECARD(SCH_1):PAGE3

UNNAMED_515_CAPACITOR_I128_1 @TIMECARD_LIB.TIMECARD(SCH_1):UNNAMED_515_CAPACITOR_I128_1
  R227    1      1 RESISTOR-G155-11002-01,10KOHM,A   I127 @TIMECARD_LIB.TIMECARD(SCH_1):PAGE515
  C227    1      1 CAPACITOR-G105-0B104-EK,0.1UF,A   I128 @TIMECARD_LIB.TIMECARD(SCH_1):PAGE515
  R228    2      2 RESISTOR-G152-00055-01,1.13KOHA   I129 @TIMECARD_LIB.TIMECARD(SCH_1):PAGE515
   U25    7 ENABLE ISL80101IRAJZ_DFN10-G222-10136A   I151 @TIMECARD_LIB.TIMECARD(SCH_1):PAGE515
  R225    2      2 RESISTOR-G155-13300-01,330OHM,A   I152 @TIMECARD_LIB.TIMECARD(SCH_1):PAGE515
  C293    1      1 CAPACITOR-G105-0B224-DK,0.22UFA   I168 @TIMECARD_LIB.TIMECARD(SCH_1):PAGE515

UNNAMED_515_CAPACITOR_I130_1 @TIMECARD_LIB.TIMECARD(SCH_1):UNNAMED_515_CAPACITOR_I130_1
  R228    1      1 RESISTOR-G152-00055-01,1.13KOHA   I129 @TIMECARD_LIB.TIMECARD(SCH_1):PAGE515
  C228    1      1 CAPACITOR-G107-0F106-EM,10UF,2A   I130 @TIMECARD_LIB.TIMECARD(SCH_1):PAGE515
  C230    1      1 CAPACITOR-G105-0B104-EK,0.1UF,A   I134 @TIMECARD_LIB.TIMECARD(SCH_1):PAGE515
   L13    2      2 FERRITEBEAD-G191-10101-01,26OHA   I135 @TIMECARD_LIB.TIMECARD(SCH_1):PAGE515
   U25    9  VIN_1 ISL80101IRAJZ_DFN10-G222-10136A   I151 @TIMECARD_LIB.TIMECARD(SCH_1):PAGE515
   U25   10  VIN_2 ISL80101IRAJZ_DFN10-G222-10136A   I151 @TIMECARD_LIB.TIMECARD(SCH_1):PAGE515

UNNAMED_515_CAPACITOR_I132_1 @TIMECARD_LIB.TIMECARD(SCH_1):UNNAMED_515_CAPACITOR_I132_1
  C231    1      1 CAPACITOR-G104-0B103-EK,0.01UFA   I132 @TIMECARD_LIB.TIMECARD(SCH_1):PAGE515
   U25    6     SS ISL80101IRAJZ_DFN10-G222-10136A   I151 @TIMECARD_LIB.TIMECARD(SCH_1):PAGE515

UNNAMED_515_CAPACITOR_I138_1 @TIMECARD_LIB.TIMECARD(SCH_1):UNNAMED_515_CAPACITOR_I138_1
  C234    1      1 CAPACITOR-G104-0B103-EK,0.01UFA   I138 @TIMECARD_LIB.TIMECARD(SCH_1):PAGE515
  R229    2      2 RESISTOR-G155-14701-01,4.7KOHMA   I139 @TIMECARD_LIB.TIMECARD(SCH_1):PAGE515
  R230    1      1 RESISTOR-G155-100R0-J0,0OHM,-   I140 @TIMECARD_LIB.TIMECARD(SCH_1):PAGE515
   U25    4     PG ISL80101IRAJZ_DFN10-G222-10136A   I151 @TIMECARD_LIB.TIMECARD(SCH_1):PAGE515

UNNAMED_515_ISL80101IRAJZDFN10_ @TIMECARD_LIB.TIMECARD(SCH_1):UNNAMED_515_ISL80101IRAJZDFN10_I151_SENSE
  R232    2      2 RESISTOR-G155-02101-01,2.1KOHMA   I143 @TIMECARD_LIB.TIMECARD(SCH_1):PAGE515
  R233    2      2 RESISTOR-G155-02101-01,2.1KOHMA   I145 @TIMECARD_LIB.TIMECARD(SCH_1):PAGE515
  R231    2      2 RESISTOR-G155-04221-01,4.22KOHA   I146 @TIMECARD_LIB.TIMECARD(SCH_1):PAGE515
   U25    3 SENSE/ADJ ISL80101IRAJZ_DFN10-G222-10136A   I151 @TIMECARD_LIB.TIMECARD(SCH_1):PAGE515

UNNAMED_515_NCP45560IMNTWGHDFN1 @TIMECARD_LIB.TIMECARD(SCH_1):UNNAMED_515_NCP45560IMNTWGHDFN12_I82_PG
  R295    2      2 RESISTOR-G155-11002-01,10KOHM,A    I69 @TIMECARD_LIB.TIMECARD(SCH_1):PAGE515
   U22    6     PG NCP45560IMNTWG_H_DFN12-G222-10A    I82 @TIMECARD_LIB.TIMECARD(SCH_1):PAGE515
  R143    2      2 RESISTOR-G155-133R0-01,33OHM,1%   I167 @TIMECARD_LIB.TIMECARD(SCH_1):PAGE515

UNNAMED_516_CAPACITOR_I13_1 @TIMECARD_LIB.TIMECARD(SCH_1):UNNAMED_516_CAPACITOR_I13_1
   C42    1      1 CAPACITOR-G105-0B222-FK,2200PFA    I13 @TIMECARD_LIB.TIMECARD(SCH_1):PAGE516
   R30    2      2 RESISTOR-G155-12201-01,2.2KOHMA    I14 @TIMECARD_LIB.TIMECARD(SCH_1):PAGE516

UNNAMED_516_CAPACITOR_I27_1 @TIMECARD_LIB.TIMECARD(SCH_1):UNNAMED_516_CAPACITOR_I27_1
   R31    2      2 RESISTOR-G155-100R0-J0,0OHM,-    I26 @TIMECARD_LIB.TIMECARD(SCH_1):PAGE516
   C44    1      1 CAPACITOR-G105-0B104-EK,0.1UF,A    I27 @TIMECARD_LIB.TIMECARD(SCH_1):PAGE516

UNNAMED_516_CAPACITOR_I29_1 @TIMECARD_LIB.TIMECARD(SCH_1):UNNAMED_516_CAPACITOR_I29_1
   C11    1      1 CAPACITOR-G104-0B101-FK,100PF,A    I29 @TIMECARD_LIB.TIMECARD(SCH_1):PAGE516
   R34    1      1 RESISTOR-G155-02402-01,24KOHM,A    I30 @TIMECARD_LIB.TIMECARD(SCH_1):PAGE516
    R6    2      2 RESISTOR-G155-120R0-01,20OHM,1%    I31 @TIMECARD_LIB.TIMECARD(SCH_1):PAGE516

UNNAMED_516_CAPACITOR_I37_2 @TIMECARD_LIB.TIMECARD(SCH_1):UNNAMED_516_CAPACITOR_I37_2
   C45    2      2 CAPACITOR-G105-0A102-FJ,1000PFA    I37 @TIMECARD_LIB.TIMECARD(SCH_1):PAGE516
   R33    1      1 RESISTOR-G157-12R20-01,2.2OHM,A    I38 @TIMECARD_LIB.TIMECARD(SCH_1):PAGE516

UNNAMED_517_CAPACITOR_I17_1 @TIMECARD_LIB.TIMECARD(SCH_1):UNNAMED_517_CAPACITOR_I17_1
   C54    1      1 CAPACITOR-G105-0B222-FK,2200PFA    I17 @TIMECARD_LIB.TIMECARD(SCH_1):PAGE517
   R36    2      2 RESISTOR-G155-11002-01,10KOHM,A    I18 @TIMECARD_LIB.TIMECARD(SCH_1):PAGE517

UNNAMED_517_CAPACITOR_I27_1 @TIMECARD_LIB.TIMECARD(SCH_1):UNNAMED_517_CAPACITOR_I27_1
   R37    2      2 RESISTOR-G155-100R0-J0,0OHM,-    I25 @TIMECARD_LIB.TIMECARD(SCH_1):PAGE517
   C56    1      1 CAPACITOR-G105-0B104-EK,0.1UF,A    I27 @TIMECARD_LIB.TIMECARD(SCH_1):PAGE517

UNNAMED_517_CAPACITOR_I29_2 @TIMECARD_LIB.TIMECARD(SCH_1):UNNAMED_517_CAPACITOR_I29_2
   C57    2      2 CAPACITOR-G105-0A102-FJ,1000PFA    I29 @TIMECARD_LIB.TIMECARD(SCH_1):PAGE517
   R39    1      1 RESISTOR-G157-12R20-01,2.2OHM,A    I32 @TIMECARD_LIB.TIMECARD(SCH_1):PAGE517

UNNAMED_517_CAPACITOR_I30_1 @TIMECARD_LIB.TIMECARD(SCH_1):UNNAMED_517_CAPACITOR_I30_1
   C16    1      1 CAPACITOR-G104-0B101-FK,100PF,A    I30 @TIMECARD_LIB.TIMECARD(SCH_1):PAGE517
   R40    1      1 RESISTOR-G155-12002-01,20KOHM,A    I31 @TIMECARD_LIB.TIMECARD(SCH_1):PAGE517
   R17    2      2 RESISTOR-G155-120R0-01,20OHM,1%    I33 @TIMECARD_LIB.TIMECARD(SCH_1):PAGE517

UNNAMED_523_CAPACITOR_I24_1 @TIMECARD_LIB.TIMECARD(SCH_1):UNNAMED_523_CAPACITOR_I24_1
  R250    2      2 RESISTOR-G155-100R0-J0,0OHM,-    I23 @TIMECARD_LIB.TIMECARD(SCH_1):PAGE523
  C265    1      1 CAPACITOR-G105-0B104-EK,0.1UF,A    I24 @TIMECARD_LIB.TIMECARD(SCH_1):PAGE523

UNNAMED_523_CAPACITOR_I28_1 @TIMECARD_LIB.TIMECARD(SCH_1):UNNAMED_523_CAPACITOR_I28_1
  C267    1      1 CAPACITOR-G104-0B101-FK,100PF,A    I28 @TIMECARD_LIB.TIMECARD(SCH_1):PAGE523
  R255    1      1 RESISTOR-G155-02262-01,22.6K,1%    I29 @TIMECARD_LIB.TIMECARD(SCH_1):PAGE523
  R254    2      2 RESISTOR-G155-120R0-01,20OHM,1%    I30 @TIMECARD_LIB.TIMECARD(SCH_1):PAGE523

UNNAMED_523_CAPACITOR_I31_2 @TIMECARD_LIB.TIMECARD(SCH_1):UNNAMED_523_CAPACITOR_I31_2
  R253    1      1 RESISTOR-G157-12R20-01,2.2OHM,A    I26 @TIMECARD_LIB.TIMECARD(SCH_1):PAGE523
  C266    2      2 CAPACITOR-G105-0A102-FJ,1000PFA    I31 @TIMECARD_LIB.TIMECARD(SCH_1):PAGE523

UNNAMED_523_CAPACITOR_I7_1 @TIMECARD_LIB.TIMECARD(SCH_1):UNNAMED_523_CAPACITOR_I7_1
  C256    1      1 CAPACITOR-G105-0B104-CK,0.1UF,A     I7 @TIMECARD_LIB.TIMECARD(SCH_1):PAGE523
   U26   17     EN TPS54824RNVR_VQFN18-G220-10657A    I11 @TIMECARD_LIB.TIMECARD(SCH_1):PAGE523
  R246    1      1 RESISTOR-A155-05101-DL,5.1KOHMA    I51 @TIMECARD_LIB.TIMECARD(SCH_1):PAGE523
  R247    2      2 RESISTOR-G155-11002-01,10KOHM,A    I54 @TIMECARD_LIB.TIMECARD(SCH_1):PAGE523
  R244    2      2 RESISTOR-G155-100R0-J0,0OHM,-   I109 @TIMECARD_LIB.TIMECARD(SCH_1):PAGE523

UNNAMED_523_CAPACITOR_I9_1 @TIMECARD_LIB.TIMECARD(SCH_1):UNNAMED_523_CAPACITOR_I9_1
  C263    1      1 CAPACITOR-G104-0B472-EK,4700PFA     I9 @TIMECARD_LIB.TIMECARD(SCH_1):PAGE523
  R249    2      2 RESISTOR-G155-14701-01,4.7KOHMA    I16 @TIMECARD_LIB.TIMECARD(SCH_1):PAGE523

UNNAMED_524_CAPACITOR_I10_2 @TIMECARD_LIB.TIMECARD(SCH_1):UNNAMED_524_CAPACITOR_I10_2
    Y2    3      3 XTAL_4-G131-10038-02     I8 @TIMECARD_LIB.TIMECARD(SCH_1):PAGE524
   C87    2      2 CAPACITOR-G104-0A180-FJ,18PF,5%    I10 @TIMECARD_LIB.TIMECARD(SCH_1):PAGE524
   U18    3   OSCO FT4232HL_REEL_QFP64-G223-10282A    I64 @TIMECARD_LIB.TIMECARD(SCH_1):PAGE524
  R455    2      2 RESISTOR-G155-11004-01,1MOHM,1%   I287 @TIMECARD_LIB.TIMECARD(SCH_1):PAGE524

UNNAMED_524_CAPACITOR_I7_2 @TIMECARD_LIB.TIMECARD(SCH_1):UNNAMED_524_CAPACITOR_I7_2
   C86    2      2 CAPACITOR-G104-0A180-FJ,18PF,5%     I7 @TIMECARD_LIB.TIMECARD(SCH_1):PAGE524
    Y2    1      1 XTAL_4-G131-10038-02     I8 @TIMECARD_LIB.TIMECARD(SCH_1):PAGE524
   U18    2   OSCI FT4232HL_REEL_QFP64-G223-10282A    I64 @TIMECARD_LIB.TIMECARD(SCH_1):PAGE524
  R455    1      1 RESISTOR-G155-11004-01,1MOHM,1%   I287 @TIMECARD_LIB.TIMECARD(SCH_1):PAGE524

UNNAMED_524_CONNUSB14PGH4FRATH_ @TIMECARD_LIB.TIMECARD(SCH_1):UNNAMED_524_CONNUSB14PGH4FRATH_I495_CC1
   J13   A5    CC1 CONN_USB_14P_GH4_F_RA_TH-G200-A   I495 @TIMECARD_LIB.TIMECARD(SCH_1):PAGE524
  R442    1      1 RESISTOR-G155-05101-01,5.1KOHMA   I497 @TIMECARD_LIB.TIMECARD(SCH_1):PAGE524

UNNAMED_524_CONNUSB14PGH4FRAT_1 @TIMECARD_LIB.TIMECARD(SCH_1):UNNAMED_524_CONNUSB14PGH4FRATH_I495_CC2
  R445    1      1 RESISTOR-G155-05101-01,5.1KOHMA   I395 @TIMECARD_LIB.TIMECARD(SCH_1):PAGE524
   J13   B5    CC2 CONN_USB_14P_GH4_F_RA_TH-G200-A   I495 @TIMECARD_LIB.TIMECARD(SCH_1):PAGE524

UNNAMED_524_FT4232HLREELQFP64_1 @TIMECARD_LIB.TIMECARD(SCH_1):UNNAMED_524_FT4232HLREELQFP64_I64_BDBUS3
   U18   29 BDBUS3 FT4232HL_REEL_QFP64-G223-10282A    I64 @TIMECARD_LIB.TIMECARD(SCH_1):PAGE524
   TP6    1      1 TP_PIONT-TP010CT020B030_PTH-TPA   I312 @TIMECARD_LIB.TIMECARD(SCH_1):PAGE524

UNNAMED_524_FT4232HLREELQFP64_2 @TIMECARD_LIB.TIMECARD(SCH_1):UNNAMED_524_FT4232HLREELQFP64_I64_BDBUS4
   U18   30 BDBUS4 FT4232HL_REEL_QFP64-G223-10282A    I64 @TIMECARD_LIB.TIMECARD(SCH_1):PAGE524
   TP7    1      1 TP_PIONT-TP010CT020B030_PTH-TPA   I313 @TIMECARD_LIB.TIMECARD(SCH_1):PAGE524

UNNAMED_524_FT4232HLREELQFP64_3 @TIMECARD_LIB.TIMECARD(SCH_1):UNNAMED_524_FT4232HLREELQFP64_I64_BDBUS5
   U18   32 BDBUS5 FT4232HL_REEL_QFP64-G223-10282A    I64 @TIMECARD_LIB.TIMECARD(SCH_1):PAGE524
   TP8    1      1 TP_PIONT-TP010CT020B030_PTH-TPA   I315 @TIMECARD_LIB.TIMECARD(SCH_1):PAGE524

UNNAMED_524_FT4232HLREELQFP64_4 @TIMECARD_LIB.TIMECARD(SCH_1):UNNAMED_524_FT4232HLREELQFP64_I64_BDBUS6
   U18   33 BDBUS6 FT4232HL_REEL_QFP64-G223-10282A    I64 @TIMECARD_LIB.TIMECARD(SCH_1):PAGE524
   TP9    1      1 TP_PIONT-TP010CT020B030_PTH-TPA   I314 @TIMECARD_LIB.TIMECARD(SCH_1):PAGE524

UNNAMED_524_FT4232HLREELQFP64_5 @TIMECARD_LIB.TIMECARD(SCH_1):UNNAMED_524_FT4232HLREELQFP64_I64_BDBUS7
   U18   34 BDBUS7 FT4232HL_REEL_QFP64-G223-10282A    I64 @TIMECARD_LIB.TIMECARD(SCH_1):PAGE524
  TP10    1      1 TP_PIONT-TP010CT020B030_PTH-TPA   I316 @TIMECARD_LIB.TIMECARD(SCH_1):PAGE524

UNNAMED_524_FT4232HLREELQFP64_6 @TIMECARD_LIB.TIMECARD(SCH_1):UNNAMED_524_FT4232HLREELQFP64_I64_REF
   U18    6    REF FT4232HL_REEL_QFP64-G223-10282A    I64 @TIMECARD_LIB.TIMECARD(SCH_1):PAGE524
  R463    1      1 RESISTOR-G155-01202-01,12KOHM,A   I106 @TIMECARD_LIB.TIMECARD(SCH_1):PAGE524

UNNAMED_524_FT4232HLREELQFP64_7 @TIMECARD_LIB.TIMECARD(SCH_1):UNNAMED_524_FT4232HLREELQFP64_I64_RESET
   U18   14 RESET* FT4232HL_REEL_QFP64-G223-10282A    I64 @TIMECARD_LIB.TIMECARD(SCH_1):PAGE524
  R460    2      2 RESISTOR-G155-11001-01,1KOHM,1%   I121 @TIMECARD_LIB.TIMECARD(SCH_1):PAGE524

UNNAMED_524_FT4232HLREELQFP64_I @TIMECARD_LIB.TIMECARD(SCH_1):UNNAMED_524_FT4232HLREELQFP64_I64_ADBUS7
   U18   24 ADBUS7 FT4232HL_REEL_QFP64-G223-10282A    I64 @TIMECARD_LIB.TIMECARD(SCH_1):PAGE524
   TP5    1      1 TP_PIONT-TP010CT020B030_PTH-TPA   I311 @TIMECARD_LIB.TIMECARD(SCH_1):PAGE524

UNNAMED_524_POWERMOS3PNCHV1_I44 @TIMECARD_LIB.TIMECARD(SCH_1):UNNAMED_524_POWERMOS3PNCHV1_I445_D
   U30   15    EN* TS3A5018PWR_TSSOP16-G220-10324A   I425 @TIMECARD_LIB.TIMECARD(SCH_1):PAGE524
  R453    1      1 RESISTOR-G155-11001-01,1KOHM,1%   I442 @TIMECARD_LIB.TIMECARD(SCH_1):PAGE524
  R452    1      1 RESISTOR-G155-14701-01,4.7KOHMA   I443 @TIMECARD_LIB.TIMECARD(SCH_1):PAGE524
    Q1    3      D POWERMOS_3P_NCH_V1-G121-10200-A   I445 @TIMECARD_LIB.TIMECARD(SCH_1):PAGE524

UNNAMED_524_RESISTOR_I432_2 @TIMECARD_LIB.TIMECARD(SCH_1):UNNAMED_524_RESISTOR_I432_2
   U38   15    EN* TS3A5018PWR_TSSOP16-G220-10324A   I400 @TIMECARD_LIB.TIMECARD(SCH_1):PAGE524
  R459    2      2 RESISTOR-G155-11001-01,1KOHM,1%   I432 @TIMECARD_LIB.TIMECARD(SCH_1):PAGE524

UNNAMED_524_RESISTOR_I463_2 @TIMECARD_LIB.TIMECARD(SCH_1):UNNAMED_524_RESISTOR_I463_2
   U37   15    EN* TS3A5018PWR_TSSOP16-G220-10324A   I448 @TIMECARD_LIB.TIMECARD(SCH_1):PAGE524
  R484    2      2 RESISTOR-G155-11001-01,1KOHM,1%   I463 @TIMECARD_LIB.TIMECARD(SCH_1):PAGE524

UNNAMED_525_CAPACITOR_I14_1 @TIMECARD_LIB.TIMECARD(SCH_1):UNNAMED_525_CAPACITOR_I14_1
  R488    1      1 RESISTOR-G155-11002-01,10KOHM,A    I13 @TIMECARD_LIB.TIMECARD(SCH_1):PAGE525
  C302    1      1 CAPACITOR-G105-0B104-EK,0.1UF,A    I14 @TIMECARD_LIB.TIMECARD(SCH_1):PAGE525
   U41    7 ENABLE ISL80101IRAJZ_DFN10-G222-10136A    I29 @TIMECARD_LIB.TIMECARD(SCH_1):PAGE525
  R487    2      2 RESISTOR-G155-14701-01,4.7KOHMA    I65 @TIMECARD_LIB.TIMECARD(SCH_1):PAGE525

UNNAMED_525_CAPACITOR_I16_1 @TIMECARD_LIB.TIMECARD(SCH_1):UNNAMED_525_CAPACITOR_I16_1
   L23    2      2 FERRITEBEAD-G191-10101-01,26OHA    I10 @TIMECARD_LIB.TIMECARD(SCH_1):PAGE525
  C300    1      1 CAPACITOR-G107-0F106-EM,10UF,2A    I16 @TIMECARD_LIB.TIMECARD(SCH_1):PAGE525
  C304    1      1 CAPACITOR-G105-0B104-EK,0.1UF,A    I20 @TIMECARD_LIB.TIMECARD(SCH_1):PAGE525
   U41    9  VIN_1 ISL80101IRAJZ_DFN10-G222-10136A    I29 @TIMECARD_LIB.TIMECARD(SCH_1):PAGE525
   U41   10  VIN_2 ISL80101IRAJZ_DFN10-G222-10136A    I29 @TIMECARD_LIB.TIMECARD(SCH_1):PAGE525
  R487    1      1 RESISTOR-G155-14701-01,4.7KOHMA    I65 @TIMECARD_LIB.TIMECARD(SCH_1):PAGE525

UNNAMED_525_CAPACITOR_I18_1 @TIMECARD_LIB.TIMECARD(SCH_1):UNNAMED_525_CAPACITOR_I18_1
  C307    1      1 CAPACITOR-G104-0B103-EK,0.01UFA    I18 @TIMECARD_LIB.TIMECARD(SCH_1):PAGE525
   U41    6     SS ISL80101IRAJZ_DFN10-G222-10136A    I29 @TIMECARD_LIB.TIMECARD(SCH_1):PAGE525

UNNAMED_525_CAPACITOR_I7_1 @TIMECARD_LIB.TIMECARD(SCH_1):UNNAMED_525_CAPACITOR_I7_1
  C284    1      1 CAPACITOR-G107-0F226-CM,22UF,2A     I7 @TIMECARD_LIB.TIMECARD(SCH_1):PAGE525
  C298    1      1 CAPACITOR-G105-0B104-EK,0.1UF,A     I8 @TIMECARD_LIB.TIMECARD(SCH_1):PAGE525
   L23    1      1 FERRITEBEAD-G191-10101-01,26OHA    I10 @TIMECARD_LIB.TIMECARD(SCH_1):PAGE525
   CR1    C      C DIODE_2F-G122-10186-01   I102 @TIMECARD_LIB.TIMECARD(SCH_1):PAGE525
   CR2    C      C DIODE_2F-G122-10186-01   I104 @TIMECARD_LIB.TIMECARD(SCH_1):PAGE525

UNNAMED_525_ISL80101IRAJZDFN10_ @TIMECARD_LIB.TIMECARD(SCH_1):UNNAMED_525_ISL80101IRAJZDFN10_I29_SENSE
   U41    3 SENSE/ADJ ISL80101IRAJZ_DFN10-G222-10136A    I29 @TIMECARD_LIB.TIMECARD(SCH_1):PAGE525
  R490    2      2 RESISTOR-G155-11002-01,10KOHM,A    I66 @TIMECARD_LIB.TIMECARD(SCH_1):PAGE525
  R491    1      1 RESISTOR-G155-03241-01,3.24KOHA    I67 @TIMECARD_LIB.TIMECARD(SCH_1):PAGE525
  R489    1      1 RESISTOR-G155-03921-01,3.92KOHA    I68 @TIMECARD_LIB.TIMECARD(SCH_1):PAGE525

UNNAMED_527_FUSE_I244_1 @TIMECARD_LIB.TIMECARD(SCH_1):UNNAMED_527_FUSE_I244_1
    Q3    3      D POWERMOS_3P_PCH-G121-10216-01   I231 @TIMECARD_LIB.TIMECARD(SCH_1):PAGE527
   FU3    1      1 FUSE-G280-10049-01,1A   I244 @TIMECARD_LIB.TIMECARD(SCH_1):PAGE527
  R357    2      2 RESISTOR-G157-100R0-J0,0OHM,-   I245 @TIMECARD_LIB.TIMECARD(SCH_1):PAGE527

UNNAMED_527_POWERMOS3PNCHV1_I23 @TIMECARD_LIB.TIMECARD(SCH_1):UNNAMED_527_POWERMOS3PNCHV1_I232_D
    Q3    1      G POWERMOS_3P_PCH-G121-10216-01   I231 @TIMECARD_LIB.TIMECARD(SCH_1):PAGE527
    Q2    3      D POWERMOS_3P_NCH_V1-G121-10200-A   I232 @TIMECARD_LIB.TIMECARD(SCH_1):PAGE527
   R44    2      2 RESISTOR-G155-14701-01,4.7KOHMA   I233 @TIMECARD_LIB.TIMECARD(SCH_1):PAGE527

UNNAMED_527_RESISTOR_I126_1 @TIMECARD_LIB.TIMECARD(SCH_1):UNNAMED_527_RESISTOR_I126_1
   U11    2   SEL1 TS3USB3031RMGR_WQFN12-G220-103A   I108 @TIMECARD_LIB.TIMECARD(SCH_1):PAGE527
  R104    1      1 RESISTOR-G155-14701-01,4.7KOHMA   I126 @TIMECARD_LIB.TIMECARD(SCH_1):PAGE527

UNNAMED_527_RESISTOR_I201_2 @TIMECARD_LIB.TIMECARD(SCH_1):UNNAMED_527_RESISTOR_I201_2
  R102    2      2 RESISTOR-G155-11001-01,1KOHM,1%   I201 @TIMECARD_LIB.TIMECARD(SCH_1):PAGE527
  R103    1      1 RESISTOR-G155-11001-01,1KOHM,1%   I202 @TIMECARD_LIB.TIMECARD(SCH_1):PAGE527

UNNAMED_527_RESISTOR_I206_1 @TIMECARD_LIB.TIMECARD(SCH_1):UNNAMED_527_RESISTOR_I206_1
   U12    3    OC* TPS2051BDBVT_SOT23_5-G220-1033A    I79 @TIMECARD_LIB.TIMECARD(SCH_1):PAGE527
  R267    1      1 RESISTOR-G155-133R0-01,33OHM,1%   I206 @TIMECARD_LIB.TIMECARD(SCH_1):PAGE527

UNNAMED_5_24LC16BTISTTSSOP8_I15 @TIMECARD_LIB.TIMECARD(SCH_1):UNNAMED_5_24LC16BTISTTSSOP8_I151_A0
   U19    1     A0 24LC16BT_I_ST_TSSOP8-G221-1017A   I151 @TIMECARD_LIB.TIMECARD(SCH_1):PAGE5
  R158    2      2 RESISTOR-G155-14701-01,4.7KOHMA   I153 @TIMECARD_LIB.TIMECARD(SCH_1):PAGE5
  R159    1      1 RESISTOR-G155-14701-01,4.7KOHMA   I156 @TIMECARD_LIB.TIMECARD(SCH_1):PAGE5

UNNAMED_5_24LC16BTISTTSSOP8_I_1 @TIMECARD_LIB.TIMECARD(SCH_1):UNNAMED_5_24LC16BTISTTSSOP8_I151_A1
   U19    2     A1 24LC16BT_I_ST_TSSOP8-G221-1017A   I151 @TIMECARD_LIB.TIMECARD(SCH_1):PAGE5
  R160    2      2 RESISTOR-G155-14701-01,4.7KOHMA   I160 @TIMECARD_LIB.TIMECARD(SCH_1):PAGE5
  R161    1      1 RESISTOR-G155-14701-01,4.7KOHMA   I165 @TIMECARD_LIB.TIMECARD(SCH_1):PAGE5

UNNAMED_5_24LC16BTISTTSSOP8_I_2 @TIMECARD_LIB.TIMECARD(SCH_1):UNNAMED_5_24LC16BTISTTSSOP8_I151_A2
   U19    3     A2 24LC16BT_I_ST_TSSOP8-G221-1017A   I151 @TIMECARD_LIB.TIMECARD(SCH_1):PAGE5
  R162    2      2 RESISTOR-G155-14701-01,4.7KOHMA   I161 @TIMECARD_LIB.TIMECARD(SCH_1):PAGE5
  R163    1      1 RESISTOR-G155-14701-01,4.7KOHMA   I166 @TIMECARD_LIB.TIMECARD(SCH_1):PAGE5

UNNAMED_5_CONNHDR2X2MSSMT_I126_ @TIMECARD_LIB.TIMECARD(SCH_1):UNNAMED_5_CONNHDR2X2MSSMT_I126_1
   R58    1      1 RESISTOR-G155-133R0-01,33OHM,1%    I88 @TIMECARD_LIB.TIMECARD(SCH_1):PAGE5
    J9    1      1 CONN_HDR_2X2_M_S_SMT-G200-1068A   I126 @TIMECARD_LIB.TIMECARD(SCH_1):PAGE5

UNNAMED_5_CONNHDR2X2MSSMT_I12_1 @TIMECARD_LIB.TIMECARD(SCH_1):UNNAMED_5_CONNHDR2X2MSSMT_I126_3
   R59    1      1 RESISTOR-G155-133R0-01,33OHM,1%     I4 @TIMECARD_LIB.TIMECARD(SCH_1):PAGE5
    J9    3      3 CONN_HDR_2X2_M_S_SMT-G200-1068A   I126 @TIMECARD_LIB.TIMECARD(SCH_1):PAGE5

UNNAMED_5_PCA9546APWTSSOP16_I33 @TIMECARD_LIB.TIMECARD(SCH_1):UNNAMED_5_PCA9546APWTSSOP16_I33_A0
    U4    1     A0 PCA9546APW_TSSOP16-G223-10280-A    I33 @TIMECARD_LIB.TIMECARD(SCH_1):PAGE5
  R149    2      2 RESISTOR-G155-14701-01,4.7KOHMA    I82 @TIMECARD_LIB.TIMECARD(SCH_1):PAGE5
  R152    2      2 RESISTOR-G155-14701-01,4.7KOHMA    I85 @TIMECARD_LIB.TIMECARD(SCH_1):PAGE5

UNNAMED_5_PCA9546APWTSSOP16_I_1 @TIMECARD_LIB.TIMECARD(SCH_1):UNNAMED_5_PCA9546APWTSSOP16_I33_A1
    U4    2     A1 PCA9546APW_TSSOP16-G223-10280-A    I33 @TIMECARD_LIB.TIMECARD(SCH_1):PAGE5
  R150    2      2 RESISTOR-G155-14701-01,4.7KOHMA    I83 @TIMECARD_LIB.TIMECARD(SCH_1):PAGE5
  R153    2      2 RESISTOR-G155-14701-01,4.7KOHMA    I86 @TIMECARD_LIB.TIMECARD(SCH_1):PAGE5

UNNAMED_5_PCA9546APWTSSOP16_I_2 @TIMECARD_LIB.TIMECARD(SCH_1):UNNAMED_5_PCA9546APWTSSOP16_I33_A2
    U4   13     A2 PCA9546APW_TSSOP16-G223-10280-A    I33 @TIMECARD_LIB.TIMECARD(SCH_1):PAGE5
  R151    2      2 RESISTOR-G155-14701-01,4.7KOHMA    I84 @TIMECARD_LIB.TIMECARD(SCH_1):PAGE5
  R154    2      2 RESISTOR-G155-14701-01,4.7KOHMA    I87 @TIMECARD_LIB.TIMECARD(SCH_1):PAGE5

UNNAMED_6_LM75BDPTSSOP8_I34_A0 @TIMECARD_LIB.TIMECARD(SCH_1):UNNAMED_6_LM75BDPTSSOP8_I34_A0
  R338    1      1 RESISTOR-G155-11001-01,1KOHM,1%    I33 @TIMECARD_LIB.TIMECARD(SCH_1):PAGE6
    U8    7     A0 LM75BDP_TSSOP8-G220-10215-01    I34 @TIMECARD_LIB.TIMECARD(SCH_1):PAGE6
  R337    2      2 RESISTOR-G155-14701-01,4.7KOHMA    I36 @TIMECARD_LIB.TIMECARD(SCH_1):PAGE6

UNNAMED_6_LM75BDPTSSOP8_I34_A1 @TIMECARD_LIB.TIMECARD(SCH_1):UNNAMED_6_LM75BDPTSSOP8_I34_A1
  R336    1      1 RESISTOR-G155-11001-01,1KOHM,1%    I32 @TIMECARD_LIB.TIMECARD(SCH_1):PAGE6
    U8    6     A1 LM75BDP_TSSOP8-G220-10215-01    I34 @TIMECARD_LIB.TIMECARD(SCH_1):PAGE6
  R335    2      2 RESISTOR-G155-14701-01,4.7KOHMA    I35 @TIMECARD_LIB.TIMECARD(SCH_1):PAGE6

UNNAMED_6_LM75BDPTSSOP8_I34_A2 @TIMECARD_LIB.TIMECARD(SCH_1):UNNAMED_6_LM75BDPTSSOP8_I34_A2
  R334    1      1 RESISTOR-G155-11001-01,1KOHM,1%    I30 @TIMECARD_LIB.TIMECARD(SCH_1):PAGE6
  R333    2      2 RESISTOR-G155-14701-01,4.7KOHMA    I31 @TIMECARD_LIB.TIMECARD(SCH_1):PAGE6
    U8    5     A2 LM75BDP_TSSOP8-G220-10215-01    I34 @TIMECARD_LIB.TIMECARD(SCH_1):PAGE6

UNNAMED_6_LM75BDPTSSOP8_I59_A0 @TIMECARD_LIB.TIMECARD(SCH_1):UNNAMED_6_LM75BDPTSSOP8_I59_A0
   U35    7     A0 LM75BDP_TSSOP8-G220-10215-01    I59 @TIMECARD_LIB.TIMECARD(SCH_1):PAGE6
  R418    2      2 RESISTOR-G155-14701-01,4.7KOHMA    I69 @TIMECARD_LIB.TIMECARD(SCH_1):PAGE6
  R416    1      1 RESISTOR-G155-11001-01,1KOHM,1%    I72 @TIMECARD_LIB.TIMECARD(SCH_1):PAGE6

UNNAMED_6_LM75BDPTSSOP8_I59_A1 @TIMECARD_LIB.TIMECARD(SCH_1):UNNAMED_6_LM75BDPTSSOP8_I59_A1
   U35    6     A1 LM75BDP_TSSOP8-G220-10215-01    I59 @TIMECARD_LIB.TIMECARD(SCH_1):PAGE6
  R413    1      1 RESISTOR-G155-11001-01,1KOHM,1%    I60 @TIMECARD_LIB.TIMECARD(SCH_1):PAGE6
  R412    2      2 RESISTOR-G155-14701-01,4.7KOHMA    I70 @TIMECARD_LIB.TIMECARD(SCH_1):PAGE6

UNNAMED_6_LM75BDPTSSOP8_I59_A2 @TIMECARD_LIB.TIMECARD(SCH_1):UNNAMED_6_LM75BDPTSSOP8_I59_A2
   U35    5     A2 LM75BDP_TSSOP8-G220-10215-01    I59 @TIMECARD_LIB.TIMECARD(SCH_1):PAGE6
  R408    2      2 RESISTOR-G155-14701-01,4.7KOHMA    I71 @TIMECARD_LIB.TIMECARD(SCH_1):PAGE6
  R409    1      1 RESISTOR-G155-11001-01,1KOHM,1%    I73 @TIMECARD_LIB.TIMECARD(SCH_1):PAGE6

UNNAMED_6_LM75BDPTSSOP8_I81_A0 @TIMECARD_LIB.TIMECARD(SCH_1):UNNAMED_6_LM75BDPTSSOP8_I81_A0
   U36    7     A0 LM75BDP_TSSOP8-G220-10215-01    I81 @TIMECARD_LIB.TIMECARD(SCH_1):PAGE6
  R419    2      2 RESISTOR-G155-14701-01,4.7KOHMA    I84 @TIMECARD_LIB.TIMECARD(SCH_1):PAGE6
  R417    1      1 RESISTOR-G155-11001-01,1KOHM,1%    I93 @TIMECARD_LIB.TIMECARD(SCH_1):PAGE6

UNNAMED_6_LM75BDPTSSOP8_I81_A1 @TIMECARD_LIB.TIMECARD(SCH_1):UNNAMED_6_LM75BDPTSSOP8_I81_A1
   U36    6     A1 LM75BDP_TSSOP8-G220-10215-01    I81 @TIMECARD_LIB.TIMECARD(SCH_1):PAGE6
  R414    2      2 RESISTOR-G155-14701-01,4.7KOHMA    I85 @TIMECARD_LIB.TIMECARD(SCH_1):PAGE6
  R415    1      1 RESISTOR-G155-11001-01,1KOHM,1%    I94 @TIMECARD_LIB.TIMECARD(SCH_1):PAGE6

UNNAMED_6_LM75BDPTSSOP8_I81_A2 @TIMECARD_LIB.TIMECARD(SCH_1):UNNAMED_6_LM75BDPTSSOP8_I81_A2
   U36    5     A2 LM75BDP_TSSOP8-G220-10215-01    I81 @TIMECARD_LIB.TIMECARD(SCH_1):PAGE6
  R410    2      2 RESISTOR-G155-14701-01,4.7KOHMA    I86 @TIMECARD_LIB.TIMECARD(SCH_1):PAGE6
  R411    1      1 RESISTOR-G155-11001-01,1KOHM,1%    I95 @TIMECARD_LIB.TIMECARD(SCH_1):PAGE6

UNNAMED_8_ICP10100LGA10_I24_RES @TIMECARD_LIB.TIMECARD(SCH_1):UNNAMED_8_ICP10100LGA10_I24_RESV1
   U28    1 RESV_1 ICP_10100_LGA10-A222-00002-FB,A    I24 @TIMECARD_LIB.TIMECARD(SCH_1):PAGE8
  R343    1      1 RESISTOR-G155-100R0-J0,0OHM,-    I34 @TIMECARD_LIB.TIMECARD(SCH_1):PAGE8

UNNAMED_8_ICP10100LGA10_I24_R_1 @TIMECARD_LIB.TIMECARD(SCH_1):UNNAMED_8_ICP10100LGA10_I24_RESV2
   U28    3 RESV_2 ICP_10100_LGA10-A222-00002-FB,A    I24 @TIMECARD_LIB.TIMECARD(SCH_1):PAGE8
  R346    1      1 RESISTOR-G155-100R0-J0,0OHM,-    I33 @TIMECARD_LIB.TIMECARD(SCH_1):PAGE8

UNNAMED_8_ICP10100LGA10_I24_R_2 @TIMECARD_LIB.TIMECARD(SCH_1):UNNAMED_8_ICP10100LGA10_I24_RESV3
   U28    5 RESV_3 ICP_10100_LGA10-A222-00002-FB,A    I24 @TIMECARD_LIB.TIMECARD(SCH_1):PAGE8
  R347    1      1 RESISTOR-G155-100R0-J0,0OHM,-    I32 @TIMECARD_LIB.TIMECARD(SCH_1):PAGE8

UNNAMED_8_ICP10100LGA10_I24_R_3 @TIMECARD_LIB.TIMECARD(SCH_1):UNNAMED_8_ICP10100LGA10_I24_RESV4
   U28    6 RESV_4 ICP_10100_LGA10-A222-00002-FB,A    I24 @TIMECARD_LIB.TIMECARD(SCH_1):PAGE8
  R350    1      1 RESISTOR-G155-100R0-J0,0OHM,-    I31 @TIMECARD_LIB.TIMECARD(SCH_1):PAGE8

UNNAMED_8_ICP10100LGA10_I24_R_4 @TIMECARD_LIB.TIMECARD(SCH_1):UNNAMED_8_ICP10100LGA10_I24_RESV5
   U28    7 RESV_5 ICP_10100_LGA10-A222-00002-FB,A    I24 @TIMECARD_LIB.TIMECARD(SCH_1):PAGE8
  R351    1      1 RESISTOR-G155-100R0-J0,0OHM,-    I30 @TIMECARD_LIB.TIMECARD(SCH_1):PAGE8

UNNAMED_8_PCA9508DPTSSOP8_I51_E @TIMECARD_LIB.TIMECARD(SCH_1):UNNAMED_8_PCA9508DPTSSOP8_I51_EN
   U32    5     EN PCA9508DP_TSSOP8-G223-10278-01    I51 @TIMECARD_LIB.TIMECARD(SCH_1):PAGE8
  R314    2      2 RESISTOR-G155-14701-01,4.7KOHMA    I71 @TIMECARD_LIB.TIMECARD(SCH_1):PAGE8

UNNAMED_9_BNO080LGA28_I29_CAP @TIMECARD_LIB.TIMECARD(SCH_1):UNNAMED_9_BNO080LGA28_I29_CAP
   U29    9    CAP BNO080_LGA_28-A246-00002-FB,BNA    I29 @TIMECARD_LIB.TIMECARD(SCH_1):PAGE9
  C285    1      1 CAPACITOR-G105-0B104-CK,0.1UF,A    I53 @TIMECARD_LIB.TIMECARD(SCH_1):PAGE9

UNNAMED_9_BNO080LGA28_I29_CLKSE @TIMECARD_LIB.TIMECARD(SCH_1):UNNAMED_9_BNO080LGA28_I29_CLKSEL0
   U29   10 CLKSEL0 BNO080_LGA_28-A246-00002-FB,BNA    I29 @TIMECARD_LIB.TIMECARD(SCH_1):PAGE9
  R307    1      1 RESISTOR-G155-11001-01,1KOHM,1%    I47 @TIMECARD_LIB.TIMECARD(SCH_1):PAGE9
  R306    2      2 RESISTOR-G155-14701-01,4.7KOHMA    I55 @TIMECARD_LIB.TIMECARD(SCH_1):PAGE9

UNNAMED_9_BNO080LGA28_I29_HCS @TIMECARD_LIB.TIMECARD(SCH_1):UNNAMED_9_BNO080LGA28_I29_HCS
   U29   18  H_CS* BNO080_LGA_28-A246-00002-FB,BNA    I29 @TIMECARD_LIB.TIMECARD(SCH_1):PAGE9
  TP61    1      1 TP_PIONT-TP010CT020B030_PTH-TPA    I63 @TIMECARD_LIB.TIMECARD(SCH_1):PAGE9

UNNAMED_9_BNO080LGA28_I29_PS0 @TIMECARD_LIB.TIMECARD(SCH_1):UNNAMED_9_BNO080LGA28_I29_PS0
   U29    6 PS0/WAKE BNO080_LGA_28-A246-00002-FB,BNA    I29 @TIMECARD_LIB.TIMECARD(SCH_1):PAGE9
  R305    1      1 RESISTOR-G155-11001-01,1KOHM,1%    I49 @TIMECARD_LIB.TIMECARD(SCH_1):PAGE9

UNNAMED_9_BNO080LGA28_I29_PS1 @TIMECARD_LIB.TIMECARD(SCH_1):UNNAMED_9_BNO080LGA28_I29_PS1
   U29    5    PS1 BNO080_LGA_28-A246-00002-FB,BNA    I29 @TIMECARD_LIB.TIMECARD(SCH_1):PAGE9
  R303    1      1 RESISTOR-G155-11001-01,1KOHM,1%    I50 @TIMECARD_LIB.TIMECARD(SCH_1):PAGE9

UNNAMED_9_BNO080LGA28_I29_XOUT3 @TIMECARD_LIB.TIMECARD(SCH_1):UNNAMED_9_BNO080LGA28_I29_XOUT32
    Y1    1      1 XTAL_2-G131-10075-01    I16 @TIMECARD_LIB.TIMECARD(SCH_1):PAGE9
   U29   26 XOUT32/CLKSEL1 BNO080_LGA_28-A246-00002-FB,BNA    I29 @TIMECARD_LIB.TIMECARD(SCH_1):PAGE9
   C47    1      1 CAPACITOR-G104-0A120-FJ,12PF,5%    I54 @TIMECARD_LIB.TIMECARD(SCH_1):PAGE9
  R168    2      2 RESISTOR-G155-11004-01,1MOHM,1%    I70 @TIMECARD_LIB.TIMECARD(SCH_1):PAGE9

UNNAMED_9_CAPACITOR_I17_1 @TIMECARD_LIB.TIMECARD(SCH_1):UNNAMED_9_CAPACITOR_I17_1
    Y1    2      2 XTAL_2-G131-10075-01    I16 @TIMECARD_LIB.TIMECARD(SCH_1):PAGE9
   C51    1      1 CAPACITOR-G104-0A120-FJ,12PF,5%    I17 @TIMECARD_LIB.TIMECARD(SCH_1):PAGE9
   U29   27  XIN32 BNO080_LGA_28-A246-00002-FB,BNA    I29 @TIMECARD_LIB.TIMECARD(SCH_1):PAGE9
  R168    1      1 RESISTOR-G155-11004-01,1MOHM,1%    I70 @TIMECARD_LIB.TIMECARD(SCH_1):PAGE9

USB_PWR_EN @TIMECARD_LIB.TIMECARD(SCH_1):USB_PWR_EN
   C69    1      1 CAPACITOR-G105-0B104-EK,0.1UF,A    I74 @TIMECARD_LIB.TIMECARD(SCH_1):PAGE527
   U12    4     EN TPS2051BDBVT_SOT23_5-G220-1033A    I79 @TIMECARD_LIB.TIMECARD(SCH_1):PAGE527
   U10    4      Y CL5003148A-G220-10019-01   I147 @TIMECARD_LIB.TIMECARD(SCH_1):PAGE527
  R100    2      2 RESISTOR-G155-133R0-01,33OHM,1%   I155 @TIMECARD_LIB.TIMECARD(SCH_1):PAGE527
    Q2    1      G POWERMOS_3P_NCH_V1-G121-10200-A   I232 @TIMECARD_LIB.TIMECARD(SCH_1):PAGE527

VDD3V3_OSC_125M @TIMECARD_LIB.TIMECARD(SCH_1):VDD3V3_OSC_125M
    Y4    6    VDD OSC6P_V2-A130-00004-AW   I145 @TIMECARD_LIB.TIMECARD(SCH_1):PAGE522
  C247    1      1 CAPACITOR-G105-0C106-BM,10UF,2A   I154 @TIMECARD_LIB.TIMECARD(SCH_1):PAGE522
  R236    1      1 RESISTOR-G155-14701-01,4.7KOHMA   I156 @TIMECARD_LIB.TIMECARD(SCH_1):PAGE522
  C249    1      1 CAPACITOR-G105-0B104-EK,0.1UF,A   I158 @TIMECARD_LIB.TIMECARD(SCH_1):PAGE522
   L10    1      1 FERRITEBEAD-G191-10097-01,600OA   I159 @TIMECARD_LIB.TIMECARD(SCH_1):PAGE522

VDD3V3_OSC_200M @TIMECARD_LIB.TIMECARD(SCH_1):VDD3V3_OSC_200M
    Y3    6    VDD OSC6P_V2-A130-00003-AW   I144 @TIMECARD_LIB.TIMECARD(SCH_1):PAGE522
   L14    1      1 FERRITEBEAD-G191-10097-01,600OA   I146 @TIMECARD_LIB.TIMECARD(SCH_1):PAGE522
  C248    1      1 CAPACITOR-G105-0B104-EK,0.1UF,A   I147 @TIMECARD_LIB.TIMECARD(SCH_1):PAGE522
  R235    1      1 RESISTOR-G155-14701-01,4.7KOHMA   I149 @TIMECARD_LIB.TIMECARD(SCH_1):PAGE522
  C246    1      1 CAPACITOR-G105-0C106-BM,10UF,2A   I151 @TIMECARD_LIB.TIMECARD(SCH_1):PAGE522

VDD3V3_SHT31A @TIMECARD_LIB.TIMECARD(SCH_1):VDD3V3_SHT31A
  C275    1      1 CAPACITOR-G105-0B104-EK,0.1UF,A    I19 @TIMECARD_LIB.TIMECARD(SCH_1):PAGE7
   L17    2      2 FERRITEBEAD-G191-10097-01,600OA    I21 @TIMECARD_LIB.TIMECARD(SCH_1):PAGE7
  C274    1      1 CAPACITOR-G105-0C106-BM,10UF,2A    I23 @TIMECARD_LIB.TIMECARD(SCH_1):PAGE7
   U27    5    VDD SHT31A_DIS_B10KS_DFN8-A222-000A    I44 @TIMECARD_LIB.TIMECARD(SCH_1):PAGE7

VDD_BNO085 @TIMECARD_LIB.TIMECARD(SCH_1):VDD_BNO085
   L19    1      1 FERRITEBEAD-G191-10097-01,600OA    I22 @TIMECARD_LIB.TIMECARD(SCH_1):PAGE9
  C280    1      1 CAPACITOR-G105-0C106-BM,10UF,2A    I23 @TIMECARD_LIB.TIMECARD(SCH_1):PAGE9
  C281    1      1 CAPACITOR-G105-0B104-EK,0.1UF,A    I24 @TIMECARD_LIB.TIMECARD(SCH_1):PAGE9
   U29    3    VDD BNO080_LGA_28-A246-00002-FB,BNA    I29 @TIMECARD_LIB.TIMECARD(SCH_1):PAGE9
   U29   28  VDDIO BNO080_LGA_28-A246-00002-FB,BNA    I29 @TIMECARD_LIB.TIMECARD(SCH_1):PAGE9

VDD_PCA9546A @TIMECARD_LIB.TIMECARD(SCH_1):VDD_PCA9546A
   C38    1      1 CAPACITOR-G105-0B104-CK,0.1UF,A    I45 @TIMECARD_LIB.TIMECARD(SCH_1):PAGE5
   R61    1      1 RESISTOR-G155-100R0-J0,0OHM,-    I52 @TIMECARD_LIB.TIMECARD(SCH_1):PAGE5
    U4   16    VDD PCA9546APW_TSSOP16-G223-10280-A    I54 @TIMECARD_LIB.TIMECARD(SCH_1):PAGE5
   R62    1      1 RESISTOR-G155-100R0-J0,0OHM,-    I55 @TIMECARD_LIB.TIMECARD(SCH_1):PAGE5

VIN_XP1R0V @TIMECARD_LIB.TIMECARD(SCH_1):VIN_XP1R0V
   U26    2  VIN_1 TPS54824RNVR_VQFN18-G220-10657A    I11 @TIMECARD_LIB.TIMECARD(SCH_1):PAGE523
   U26   11  VIN_2 TPS54824RNVR_VQFN18-G220-10657A    I11 @TIMECARD_LIB.TIMECARD(SCH_1):PAGE523
  C257    1      1 CAPACITOR-G107-0F106-EM,10UF,2A    I13 @TIMECARD_LIB.TIMECARD(SCH_1):PAGE523
  C260    1      1 CAPACITOR-G107-0F106-EM,10UF,2A    I14 @TIMECARD_LIB.TIMECARD(SCH_1):PAGE523
  C261    1      1 CAPACITOR-G105-0B104-EK,0.1UF,A    I17 @TIMECARD_LIB.TIMECARD(SCH_1):PAGE523
  C262    1      1 CAPACITOR-G105-0B104-EK,0.1UF,A    I19 @TIMECARD_LIB.TIMECARD(SCH_1):PAGE523
    L9    2      2 FERRITEBEAD-G191-10101-01,26OHA    I48 @TIMECARD_LIB.TIMECARD(SCH_1):PAGE523
  R247    1      1 RESISTOR-G155-11002-01,10KOHM,A    I54 @TIMECARD_LIB.TIMECARD(SCH_1):PAGE523

VIN_XP3R3 @TIMECARD_LIB.TIMECARD(SCH_1):VIN_XP3R3
    L8    2      2 FERRITEBEAD-G191-10101-01,26OHA     I7 @TIMECARD_LIB.TIMECARD(SCH_1):PAGE517
   R53    1      1 RESISTOR-G152-10344-01,30KOHM,A    I13 @TIMECARD_LIB.TIMECARD(SCH_1):PAGE517
   C48    1      1 CAPACITOR-G107-0F106-EM,10UF,2A    I14 @TIMECARD_LIB.TIMECARD(SCH_1):PAGE517
   C50    1      1 CAPACITOR-G107-0F106-EM,10UF,2A    I15 @TIMECARD_LIB.TIMECARD(SCH_1):PAGE517
   C52    1      1 CAPACITOR-G105-0B104-EK,0.1UF,A    I16 @TIMECARD_LIB.TIMECARD(SCH_1):PAGE517
   C53    1      1 CAPACITOR-G105-0B104-EK,0.1UF,A    I21 @TIMECARD_LIB.TIMECARD(SCH_1):PAGE517
    U6    2  VIN_1 TPS54824RNVR_VQFN18-G220-10657A    I42 @TIMECARD_LIB.TIMECARD(SCH_1):PAGE517
    U6   11  VIN_2 TPS54824RNVR_VQFN18-G220-10657A    I42 @TIMECARD_LIB.TIMECARD(SCH_1):PAGE517

VIN_XP5R0V @TIMECARD_LIB.TIMECARD(SCH_1):VIN_XP5R0V
   R49    1      1 RESISTOR-G155-11002-01,10KOHM,A    I16 @TIMECARD_LIB.TIMECARD(SCH_1):PAGE516
    L7    2      2 FERRITEBEAD-G191-10101-01,26OHA    I17 @TIMECARD_LIB.TIMECARD(SCH_1):PAGE516
   C30    1      1 CAPACITOR-G107-0F106-EM,10UF,2A    I18 @TIMECARD_LIB.TIMECARD(SCH_1):PAGE516
   C32    1      1 CAPACITOR-G107-0F106-EM,10UF,2A    I19 @TIMECARD_LIB.TIMECARD(SCH_1):PAGE516
   C33    1      1 CAPACITOR-G105-0B104-EK,0.1UF,A    I20 @TIMECARD_LIB.TIMECARD(SCH_1):PAGE516
   C41    1      1 CAPACITOR-G105-0B104-EK,0.1UF,A    I22 @TIMECARD_LIB.TIMECARD(SCH_1):PAGE516
    U5    2  VIN_1 TPS54824RNVR_VQFN18-G220-10657A    I42 @TIMECARD_LIB.TIMECARD(SCH_1):PAGE516
    U5   11  VIN_2 TPS54824RNVR_VQFN18-G220-10657A    I42 @TIMECARD_LIB.TIMECARD(SCH_1):PAGE516

XP12R0V @TIMECARD_LIB.TIMECARD(SCH_1):XP12R0V
   C76    1      1 CAPACITOR-G105-0B104-EK,0.1UF,A     I6 @TIMECARD_LIB.TIMECARD(SCH_1):PAGE517
    L8    1      1 FERRITEBEAD-G191-10101-01,26OHA     I7 @TIMECARD_LIB.TIMECARD(SCH_1):PAGE517
   C74    1      1 CAPACITOR-G105-0B104-EK,0.1UF,A     I4 @TIMECARD_LIB.TIMECARD(SCH_1):PAGE516
    L7    1      1 FERRITEBEAD-G191-10101-01,26OHA    I17 @TIMECARD_LIB.TIMECARD(SCH_1):PAGE516
   R13    1      1 RESISTOR-G155-11002-01,10KOHM,A   I202 @TIMECARD_LIB.TIMECARD(SCH_1):PAGE15
   R15    1      1 RESISTOR-G155-11002-01,10KOHM,A   I203 @TIMECARD_LIB.TIMECARD(SCH_1):PAGE15
   CR3    C      C DIODE_2-G122-00005-01   I204 @TIMECARD_LIB.TIMECARD(SCH_1):PAGE15
    C9    1      1 CAPACITOR-G107-0F106-EM,10UF,2A   I206 @TIMECARD_LIB.TIMECARD(SCH_1):PAGE15
   C10    1      1 CAPACITOR-G107-0F106-EM,10UF,2A   I207 @TIMECARD_LIB.TIMECARD(SCH_1):PAGE15
    U1   13 VOUT_1 MP5022CGQV_Z_QFN22-G220-10510-A   I212 @TIMECARD_LIB.TIMECARD(SCH_1):PAGE15
    U1   14 VOUT_2 MP5022CGQV_Z_QFN22-G220-10510-A   I212 @TIMECARD_LIB.TIMECARD(SCH_1):PAGE15
    U1   15 VOUT_3 MP5022CGQV_Z_QFN22-G220-10510-A   I212 @TIMECARD_LIB.TIMECARD(SCH_1):PAGE15
    U1   16 VOUT_4 MP5022CGQV_Z_QFN22-G220-10510-A   I212 @TIMECARD_LIB.TIMECARD(SCH_1):PAGE15
    U1   17 VOUT_5 MP5022CGQV_Z_QFN22-G220-10510-A   I212 @TIMECARD_LIB.TIMECARD(SCH_1):PAGE15
    U1   18 VOUT_6 MP5022CGQV_Z_QFN22-G220-10510-A   I212 @TIMECARD_LIB.TIMECARD(SCH_1):PAGE15
    U1   19 VOUT_7 MP5022CGQV_Z_QFN22-G220-10510-A   I212 @TIMECARD_LIB.TIMECARD(SCH_1):PAGE15
    U1   20 VOUT_8 MP5022CGQV_Z_QFN22-G220-10510-A   I212 @TIMECARD_LIB.TIMECARD(SCH_1):PAGE15
  C255    1      1 CAPACITOR-G105-0B104-EK,0.1UF,A    I46 @TIMECARD_LIB.TIMECARD(SCH_1):PAGE523
    L9    1      1 FERRITEBEAD-G191-10101-01,26OHA    I48 @TIMECARD_LIB.TIMECARD(SCH_1):PAGE523
   FU1    2      2 FUSE-G280-10012-01,2.5A   I223 @TIMECARD_LIB.TIMECARD(SCH_1):PAGE15
  R262    2      2 RESISTOR-G155-11001-01,1KOHM,1%    I66 @TIMECARD_LIB.TIMECARD(SCH_1):PAGE14
  TP52    1      1 TP_PIONT-TP010CT020B030_PTH-TPA  I1206 @TIMECARD_LIB.TIMECARD(SCH_1):PAGE16

XP12R0V_A_AVIN @TIMECARD_LIB.TIMECARD(SCH_1):XP12R0V_A_AVIN
    C6    1      1 CAPACITOR-G107-0F106-EM,10UF,2A   I196 @TIMECARD_LIB.TIMECARD(SCH_1):PAGE15
    R9    2      2 RESISTOR-G156-049R9-01,49.9OHMA   I198 @TIMECARD_LIB.TIMECARD(SCH_1):PAGE15
    U1   12   AVIN MP5022CGQV_Z_QFN22-G220-10510-A   I212 @TIMECARD_LIB.TIMECARD(SCH_1):PAGE15

XP12R0V_A_EN @TIMECARD_LIB.TIMECARD(SCH_1):XP12R0V_A_EN
    C3    1      1 CAPACITOR-G105-0B104-EK,0.1UF,A   I156 @TIMECARD_LIB.TIMECARD(SCH_1):PAGE15
    R5    1      1 RESISTOR-G155-11002-01,10KOHM,A   I169 @TIMECARD_LIB.TIMECARD(SCH_1):PAGE15
    R4    2      2 RESISTOR-G155-11002-01,10KOHM,A   I170 @TIMECARD_LIB.TIMECARD(SCH_1):PAGE15
    U1    1     EN MP5022CGQV_Z_QFN22-G220-10510-A   I212 @TIMECARD_LIB.TIMECARD(SCH_1):PAGE15
  TP43    1      1 TP_PIONT-TP010CT020B030_PTH-TPA  I1691 @TIMECARD_LIB.TIMECARD(SCH_1):PAGE16

XP12R0V_A_FLTB @TIMECARD_LIB.TIMECARD(SCH_1):XP12R0V_A_FLTB
   R16    1      1 RESISTOR-G155-03921-01,3.92KOHA   I188 @TIMECARD_LIB.TIMECARD(SCH_1):PAGE15
   R15    2      2 RESISTOR-G155-11002-01,10KOHM,A   I203 @TIMECARD_LIB.TIMECARD(SCH_1):PAGE15
    U1    9   FLTB MP5022CGQV_Z_QFN22-G220-10510-A   I212 @TIMECARD_LIB.TIMECARD(SCH_1):PAGE15
  TP37    1      1 TP_PIONT-TP010CT020B030_PTH-TPA  I1682 @TIMECARD_LIB.TIMECARD(SCH_1):PAGE16

XP12R0V_A_IMON @TIMECARD_LIB.TIMECARD(SCH_1):XP12R0V_A_IMON
   R10    1      1 RESISTOR-G155-11002-01,10KOHM,A   I183 @TIMECARD_LIB.TIMECARD(SCH_1):PAGE15
    C7    1      1 CAPACITOR-G105-0B104-EK,0.1UF,A   I185 @TIMECARD_LIB.TIMECARD(SCH_1):PAGE15
    U1    8   IMON MP5022CGQV_Z_QFN22-G220-10510-A   I212 @TIMECARD_LIB.TIMECARD(SCH_1):PAGE15

XP12R0V_A_ISET @TIMECARD_LIB.TIMECARD(SCH_1):XP12R0V_A_ISET
   R46    2      2 RESISTOR-G155-02672-01,26.7K,1%   I171 @TIMECARD_LIB.TIMECARD(SCH_1):PAGE15
    U1    5   ISET MP5022CGQV_Z_QFN22-G220-10510-A   I212 @TIMECARD_LIB.TIMECARD(SCH_1):PAGE15

XP12R0V_A_OV @TIMECARD_LIB.TIMECARD(SCH_1):XP12R0V_A_OV
   R12    1      1 RESISTOR-G155-11002-01,10KOHM,A   I197 @TIMECARD_LIB.TIMECARD(SCH_1):PAGE15
   R11    2      2 RESISTOR-G155-01203-01,120KOHMA   I199 @TIMECARD_LIB.TIMECARD(SCH_1):PAGE15
    C8    1      1 CAPACITOR-G104-0B103-EK,0.01UFA   I201 @TIMECARD_LIB.TIMECARD(SCH_1):PAGE15
    U1   11     OV MP5022CGQV_Z_QFN22-G220-10510-A   I212 @TIMECARD_LIB.TIMECARD(SCH_1):PAGE15

XP12R0V_A_PG @TIMECARD_LIB.TIMECARD(SCH_1):XP12R0V_A_PG
   R14    1      1 RESISTOR-G155-03921-01,3.92KOHA   I186 @TIMECARD_LIB.TIMECARD(SCH_1):PAGE15
   R13    2      2 RESISTOR-G155-11002-01,10KOHM,A   I202 @TIMECARD_LIB.TIMECARD(SCH_1):PAGE15
    U1   10     PG MP5022CGQV_Z_QFN22-G220-10510-A   I212 @TIMECARD_LIB.TIMECARD(SCH_1):PAGE15
  TP36    1      1 TP_PIONT-TP010CT020B030_PTH-TPA  I1650 @TIMECARD_LIB.TIMECARD(SCH_1):PAGE16

XP12R0V_A_SS @TIMECARD_LIB.TIMECARD(SCH_1):XP12R0V_A_SS
    C5    1      1 CAPACITOR-G105-0B104-EK,0.1UF,A   I211 @TIMECARD_LIB.TIMECARD(SCH_1):PAGE15
    U1    6     SS MP5022CGQV_Z_QFN22-G220-10510-A   I212 @TIMECARD_LIB.TIMECARD(SCH_1):PAGE15

XP12R0V_A_TIMER @TIMECARD_LIB.TIMECARD(SCH_1):XP12R0V_A_TIMER
    C4    2      2 CAPACITOR-G104-0F224-BK,0.22UFA   I172 @TIMECARD_LIB.TIMECARD(SCH_1):PAGE15
    U1    4  TIMER MP5022CGQV_Z_QFN22-G220-10510-A   I212 @TIMECARD_LIB.TIMECARD(SCH_1):PAGE15

XP12R0V_EXT @TIMECARD_LIB.TIMECARD(SCH_1):XP12R0V_EXT
    P3    1      1 CONN_HDR_2X3_M_RA_TH-G200-1251A   I238 @TIMECARD_LIB.TIMECARD(SCH_1):PAGE15
    P3    2      2 CONN_HDR_2X3_M_RA_TH-G200-1251A   I238 @TIMECARD_LIB.TIMECARD(SCH_1):PAGE15
    P3    3      3 CONN_HDR_2X3_M_RA_TH-G200-1251A   I238 @TIMECARD_LIB.TIMECARD(SCH_1):PAGE15
  CR12    2    A_2 DIODE_3F-G122-10080-01   I239 @TIMECARD_LIB.TIMECARD(SCH_1):PAGE15

XP12R0V_IN @TIMECARD_LIB.TIMECARD(SCH_1):XP12R0V_IN
  CR10    C      C DIODE_2E-G122-10190-01   I159 @TIMECARD_LIB.TIMECARD(SCH_1):PAGE15
    C2    1      1 CAPACITOR-G105-0B104-EK,0.1UF,A   I160 @TIMECARD_LIB.TIMECARD(SCH_1):PAGE15
    R4    1      1 RESISTOR-G155-11002-01,10KOHM,A   I170 @TIMECARD_LIB.TIMECARD(SCH_1):PAGE15
    R9    1      1 RESISTOR-G156-049R9-01,49.9OHMA   I198 @TIMECARD_LIB.TIMECARD(SCH_1):PAGE15
   R11    1      1 RESISTOR-G155-01203-01,120KOHMA   I199 @TIMECARD_LIB.TIMECARD(SCH_1):PAGE15
    U1   21  VIN_1 MP5022CGQV_Z_QFN22-G220-10510-A   I212 @TIMECARD_LIB.TIMECARD(SCH_1):PAGE15
    U1   22  VIN_2 MP5022CGQV_Z_QFN22-G220-10510-A   I212 @TIMECARD_LIB.TIMECARD(SCH_1):PAGE15
    U1   23  VIN_3 MP5022CGQV_Z_QFN22-G220-10510-A   I212 @TIMECARD_LIB.TIMECARD(SCH_1):PAGE15
    U1   24  VIN_4 MP5022CGQV_Z_QFN22-G220-10510-A   I212 @TIMECARD_LIB.TIMECARD(SCH_1):PAGE15
    U1   25  VIN_5 MP5022CGQV_Z_QFN22-G220-10510-A   I212 @TIMECARD_LIB.TIMECARD(SCH_1):PAGE15
    U1   26  VIN_6 MP5022CGQV_Z_QFN22-G220-10510-A   I212 @TIMECARD_LIB.TIMECARD(SCH_1):PAGE15
   FU1    1      1 FUSE-G280-10012-01,2.5A   I223 @TIMECARD_LIB.TIMECARD(SCH_1):PAGE15
  C297    1      1 CAPACITOR-G107-0F106-EM,10UF,2A   I229 @TIMECARD_LIB.TIMECARD(SCH_1):PAGE15
  C299    1      1 CAPACITOR-G107-0F106-EM,10UF,2A   I230 @TIMECARD_LIB.TIMECARD(SCH_1):PAGE15
  C303    1      1 CAPACITOR-G107-0F106-EM,10UF,2A   I231 @TIMECARD_LIB.TIMECARD(SCH_1):PAGE15
  C301    1      1 CAPACITOR-G107-0F106-EM,10UF,2A   I232 @TIMECARD_LIB.TIMECARD(SCH_1):PAGE15
  CR12    3      C DIODE_3F-G122-10080-01   I239 @TIMECARD_LIB.TIMECARD(SCH_1):PAGE15
   L20    2      2 FERRITEBEAD-G191-10101-01,26OHA   I240 @TIMECARD_LIB.TIMECARD(SCH_1):PAGE15
  TP42    1      1 TP_PIONT-TP010CT020B030_PTH-TPA  I1665 @TIMECARD_LIB.TIMECARD(SCH_1):PAGE16

XP12R0V_PCIE @TIMECARD_LIB.TIMECARD(SCH_1):XP12R0V_PCIE
   GF1   B1 P_12V1 CONN_64P_GF-S_M_EF64_PCIE_P039A    I61 @TIMECARD_LIB.TIMECARD(SCH_1):PAGE3
   GF1   B2 P_12V2 CONN_64P_GF-S_M_EF64_PCIE_P039A    I61 @TIMECARD_LIB.TIMECARD(SCH_1):PAGE3
   GF1   A2 P_12V3 CONN_64P_GF-S_M_EF64_PCIE_P039A    I61 @TIMECARD_LIB.TIMECARD(SCH_1):PAGE3
   GF1   B3 P_12V4 CONN_64P_GF-S_M_EF64_PCIE_P039A    I61 @TIMECARD_LIB.TIMECARD(SCH_1):PAGE3
   GF1   A3 P_12V5 CONN_64P_GF-S_M_EF64_PCIE_P039A    I61 @TIMECARD_LIB.TIMECARD(SCH_1):PAGE3
  CR12    1    A_1 DIODE_3F-G122-10080-01   I239 @TIMECARD_LIB.TIMECARD(SCH_1):PAGE15
   L20    1      1 FERRITEBEAD-G191-10101-01,26OHA   I240 @TIMECARD_LIB.TIMECARD(SCH_1):PAGE15

XP1R0V_AGND @TIMECARD_LIB.TIMECARD(SCH_1):XP1R0V_AGND
  C263    2      2 CAPACITOR-G104-0B472-EK,4700PFA     I9 @TIMECARD_LIB.TIMECARD(SCH_1):PAGE523
  C264    2      2 CAPACITOR-G104-0A180-FJ,18PF,5%    I10 @TIMECARD_LIB.TIMECARD(SCH_1):PAGE523
   U26   12   AGND TPS54824RNVR_VQFN18-G220-10657A    I11 @TIMECARD_LIB.TIMECARD(SCH_1):PAGE523
  C259    2      2 CAPACITOR-G105-0B223-EK,0.022UA    I12 @TIMECARD_LIB.TIMECARD(SCH_1):PAGE523
  R248    2      2 RESISTOR-G155-11003-01,100KOHMA    I15 @TIMECARD_LIB.TIMECARD(SCH_1):PAGE523
   SP3    2      2 SOLDER_PREFORM-G380-10015-01    I39 @TIMECARD_LIB.TIMECARD(SCH_1):PAGE523
  R251    1      1 RESISTOR-G155-03322-01,33.2KOHA    I56 @TIMECARD_LIB.TIMECARD(SCH_1):PAGE523
  R252    1      1 RESISTOR-G156-100R0-J0,0OHM,-    I57 @TIMECARD_LIB.TIMECARD(SCH_1):PAGE523

XP1R0V_BT @TIMECARD_LIB.TIMECARD(SCH_1):XP1R0V_BT
   U26    1   BOOT TPS54824RNVR_VQFN18-G220-10657A    I11 @TIMECARD_LIB.TIMECARD(SCH_1):PAGE523
  R250    1      1 RESISTOR-G155-100R0-J0,0OHM,-    I23 @TIMECARD_LIB.TIMECARD(SCH_1):PAGE523

XP1R0V_COMP @TIMECARD_LIB.TIMECARD(SCH_1):XP1R0V_COMP
  C264    1      1 CAPACITOR-G104-0A180-FJ,18PF,5%    I10 @TIMECARD_LIB.TIMECARD(SCH_1):PAGE523
   U26   15   COMP TPS54824RNVR_VQFN18-G220-10657A    I11 @TIMECARD_LIB.TIMECARD(SCH_1):PAGE523
  R249    1      1 RESISTOR-G155-14701-01,4.7KOHMA    I16 @TIMECARD_LIB.TIMECARD(SCH_1):PAGE523

XP1R0V_FB_R_TO_AGND @TIMECARD_LIB.TIMECARD(SCH_1):XP1R0V_FB_R_TO_AGND
   U26   14     FB TPS54824RNVR_VQFN18-G220-10657A    I11 @TIMECARD_LIB.TIMECARD(SCH_1):PAGE523
  C267    2      2 CAPACITOR-G104-0B101-FK,100PF,A    I28 @TIMECARD_LIB.TIMECARD(SCH_1):PAGE523
  R255    2      2 RESISTOR-G155-02262-01,22.6K,1%    I29 @TIMECARD_LIB.TIMECARD(SCH_1):PAGE523
  R251    2      2 RESISTOR-G155-03322-01,33.2KOHA    I56 @TIMECARD_LIB.TIMECARD(SCH_1):PAGE523
  R252    2      2 RESISTOR-G156-100R0-J0,0OHM,-    I57 @TIMECARD_LIB.TIMECARD(SCH_1):PAGE523

XP1R0V_FPGA @TIMECARD_LIB.TIMECARD(SCH_1):XP1R0V_FPGA
   L34    2      2 FERRITEBEAD-G191-10100-01,120OA    I37 @TIMECARD_LIB.TIMECARD(SCH_1):PAGE164
   L12    2      2 FERRITEBEAD-G191-10100-01,120OA   I139 @TIMECARD_LIB.TIMECARD(SCH_1):PAGE164
  C148    1      1 CAPACITOR-G105-0B104-CK,0.1UF,A   I250 @TIMECARD_LIB.TIMECARD(SCH_1):PAGE164
  C155    1      1 CAPACITOR-G107-0F476-AM,47UF,2A   I266 @TIMECARD_LIB.TIMECARD(SCH_1):PAGE164
  C179    1      1 CAPACITOR-G107-0F476-AM,47UF,2A   I274 @TIMECARD_LIB.TIMECARD(SCH_1):PAGE164
  C178    1      1 CAPACITOR-G105-0B104-CK,0.1UF,A   I283 @TIMECARD_LIB.TIMECARD(SCH_1):PAGE164
    L5    2      2 INDUCTOR_2-G190-10418-01,1.0UHA    I25 @TIMECARD_LIB.TIMECARD(SCH_1):PAGE523
  R254    1      1 RESISTOR-G155-120R0-01,20OHM,1%    I30 @TIMECARD_LIB.TIMECARD(SCH_1):PAGE523
  C268    1      1 CAPACITOR-G105-0B104-CK,0.1UF,A    I33 @TIMECARD_LIB.TIMECARD(SCH_1):PAGE523
  C269    1      1 CAPACITOR-G107-0F476-AM,47UF,2A    I34 @TIMECARD_LIB.TIMECARD(SCH_1):PAGE523
  C270    1      1 CAPACITOR-G107-0F476-AM,47UF,2A    I35 @TIMECARD_LIB.TIMECARD(SCH_1):PAGE523
  C271    1      1 CAPACITOR-G107-0F476-AM,47UF,2A    I37 @TIMECARD_LIB.TIMECARD(SCH_1):PAGE523
  TP54    1      1 TP_PIONT-TP010CT020B030_PTH-TPA  I1210 @TIMECARD_LIB.TIMECARD(SCH_1):PAGE16

XP1R0V_FPGA_MGTAVCC @TIMECARD_LIB.TIMECARD(SCH_1):XP1R0V_FPGA_MGTAVCC
   L34    1      1 FERRITEBEAD-G191-10100-01,120OA    I37 @TIMECARD_LIB.TIMECARD(SCH_1):PAGE164
   U24  D10 MGTAVCC_1 XC7A200T_2FBG484C_FBG484-G240-A   I138 @TIMECARD_LIB.TIMECARD(SCH_1):PAGE164
   U24   D6 MGTAVCC_2 XC7A200T_2FBG484C_FBG484-G240-A   I138 @TIMECARD_LIB.TIMECARD(SCH_1):PAGE164
   U24   E8 MGTAVCC_3 XC7A200T_2FBG484C_FBG484-G240-A   I138 @TIMECARD_LIB.TIMECARD(SCH_1):PAGE164
   U24   F7 MGTAVCC_4 XC7A200T_2FBG484C_FBG484-G240-A   I138 @TIMECARD_LIB.TIMECARD(SCH_1):PAGE164
   U24   F9 MGTAVCC_5 XC7A200T_2FBG484C_FBG484-G240-A   I138 @TIMECARD_LIB.TIMECARD(SCH_1):PAGE164
  C131    1      1 CAPACITOR-G105-0F475-BM,4.7UF,A   I248 @TIMECARD_LIB.TIMECARD(SCH_1):PAGE164
  C218    1      1 CAPACITOR-G105-0B104-CK,0.1UF,A   I251 @TIMECARD_LIB.TIMECARD(SCH_1):PAGE164
  C105    1      1 CAPACITOR-G105-0B104-CK,0.1UF,A   I252 @TIMECARD_LIB.TIMECARD(SCH_1):PAGE164
  C111    1      1 CAPACITOR-G105-0B104-CK,0.1UF,A   I253 @TIMECARD_LIB.TIMECARD(SCH_1):PAGE164
  C118    1      1 CAPACITOR-G105-0B104-CK,0.1UF,A   I254 @TIMECARD_LIB.TIMECARD(SCH_1):PAGE164
  C124    1      1 CAPACITOR-G105-0B104-CK,0.1UF,A   I255 @TIMECARD_LIB.TIMECARD(SCH_1):PAGE164
  C137    1      1 CAPACITOR-G107-0F476-AM,47UF,2A   I281 @TIMECARD_LIB.TIMECARD(SCH_1):PAGE164

XP1R0V_FPGA_PG @TIMECARD_LIB.TIMECARD(SCH_1):XP1R0V_FPGA_PG
  R140    1      1 RESISTOR-G155-100R0-J0,0OHM,-    I18 @TIMECARD_LIB.TIMECARD(SCH_1):PAGE68
  R245    1      1 RESISTOR-G155-100R0-J0,0OHM,-   I104 @TIMECARD_LIB.TIMECARD(SCH_1):PAGE523
  TP39    1      1 TP_PIONT-TP010CT020B030_PTH-TPA  I1652 @TIMECARD_LIB.TIMECARD(SCH_1):PAGE16

XP1R0V_FPGA_VCCINT @TIMECARD_LIB.TIMECARD(SCH_1):XP1R0V_FPGA_VCCINT
   U24  J11 VCCBRAM_1 XC7A200T_2FBG484C_FBG484-G240-A   I138 @TIMECARD_LIB.TIMECARD(SCH_1):PAGE164
   U24  L11 VCCBRAM_2 XC7A200T_2FBG484C_FBG484-G240-A   I138 @TIMECARD_LIB.TIMECARD(SCH_1):PAGE164
   U24  N11 VCCBRAM_3 XC7A200T_2FBG484C_FBG484-G240-A   I138 @TIMECARD_LIB.TIMECARD(SCH_1):PAGE164
   U24  H10 VCCINT_1 XC7A200T_2FBG484C_FBG484-G240-A   I138 @TIMECARD_LIB.TIMECARD(SCH_1):PAGE164
   U24   H8 VCCINT_2 XC7A200T_2FBG484C_FBG484-G240-A   I138 @TIMECARD_LIB.TIMECARD(SCH_1):PAGE164
   U24   J7 VCCINT_3 XC7A200T_2FBG484C_FBG484-G240-A   I138 @TIMECARD_LIB.TIMECARD(SCH_1):PAGE164
   U24   J9 VCCINT_4 XC7A200T_2FBG484C_FBG484-G240-A   I138 @TIMECARD_LIB.TIMECARD(SCH_1):PAGE164
   U24   K8 VCCINT_5 XC7A200T_2FBG484C_FBG484-G240-A   I138 @TIMECARD_LIB.TIMECARD(SCH_1):PAGE164
   U24   L7 VCCINT_6 XC7A200T_2FBG484C_FBG484-G240-A   I138 @TIMECARD_LIB.TIMECARD(SCH_1):PAGE164
   U24   M8 VCCINT_7 XC7A200T_2FBG484C_FBG484-G240-A   I138 @TIMECARD_LIB.TIMECARD(SCH_1):PAGE164
   U24   N7 VCCINT_8 XC7A200T_2FBG484C_FBG484-G240-A   I138 @TIMECARD_LIB.TIMECARD(SCH_1):PAGE164
   U24  P10 VCCINT_9 XC7A200T_2FBG484C_FBG484-G240-A   I138 @TIMECARD_LIB.TIMECARD(SCH_1):PAGE164
   U24   P8 VCCINT_10 XC7A200T_2FBG484C_FBG484-G240-A   I138 @TIMECARD_LIB.TIMECARD(SCH_1):PAGE164
   U24   R7 VCCINT_11 XC7A200T_2FBG484C_FBG484-G240-A   I138 @TIMECARD_LIB.TIMECARD(SCH_1):PAGE164
   U24   R9 VCCINT_12 XC7A200T_2FBG484C_FBG484-G240-A   I138 @TIMECARD_LIB.TIMECARD(SCH_1):PAGE164
   U24  T10 VCCINT_13 XC7A200T_2FBG484C_FBG484-G240-A   I138 @TIMECARD_LIB.TIMECARD(SCH_1):PAGE164
   U24   T8 VCCINT_14 XC7A200T_2FBG484C_FBG484-G240-A   I138 @TIMECARD_LIB.TIMECARD(SCH_1):PAGE164
   L12    1      1 FERRITEBEAD-G191-10100-01,120OA   I139 @TIMECARD_LIB.TIMECARD(SCH_1):PAGE164
  C176    1      1 CAPACITOR-G109-0G107-BM,100UF,A   I172 @TIMECARD_LIB.TIMECARD(SCH_1):PAGE164
  C175    1      1 CAPACITOR-G109-0G107-BM,100UF,A   I173 @TIMECARD_LIB.TIMECARD(SCH_1):PAGE164
  C201    1      1 CAPACITOR-G105-0B104-CK,0.1UF,A   I182 @TIMECARD_LIB.TIMECARD(SCH_1):PAGE164
  C207    1      1 CAPACITOR-G105-0B104-CK,0.1UF,A   I183 @TIMECARD_LIB.TIMECARD(SCH_1):PAGE164
  C214    1      1 CAPACITOR-G105-0B104-CK,0.1UF,A   I184 @TIMECARD_LIB.TIMECARD(SCH_1):PAGE164
  C222    1      1 CAPACITOR-G105-0B104-CK,0.1UF,A   I185 @TIMECARD_LIB.TIMECARD(SCH_1):PAGE164
  C109    1      1 CAPACITOR-G105-0B104-CK,0.1UF,A   I186 @TIMECARD_LIB.TIMECARD(SCH_1):PAGE164
  C114    1      1 CAPACITOR-G105-0B104-CK,0.1UF,A   I187 @TIMECARD_LIB.TIMECARD(SCH_1):PAGE164
  C121    1      1 CAPACITOR-G105-0B104-CK,0.1UF,A   I188 @TIMECARD_LIB.TIMECARD(SCH_1):PAGE164
  C129    1      1 CAPACITOR-G105-0B104-CK,0.1UF,A   I189 @TIMECARD_LIB.TIMECARD(SCH_1):PAGE164
  C133    1      1 CAPACITOR-G105-0B104-CK,0.1UF,A   I190 @TIMECARD_LIB.TIMECARD(SCH_1):PAGE164
  C141    1      1 CAPACITOR-G105-0B104-CK,0.1UF,A   I191 @TIMECARD_LIB.TIMECARD(SCH_1):PAGE164
  C147    1      1 CAPACITOR-G105-0B104-CK,0.1UF,A   I192 @TIMECARD_LIB.TIMECARD(SCH_1):PAGE164
  C152    1      1 CAPACITOR-G105-0B104-CK,0.1UF,A   I193 @TIMECARD_LIB.TIMECARD(SCH_1):PAGE164
  C156    1      1 CAPACITOR-G105-0B104-CK,0.1UF,A   I194 @TIMECARD_LIB.TIMECARD(SCH_1):PAGE164
  C161    1      1 CAPACITOR-G105-0B104-CK,0.1UF,A   I195 @TIMECARD_LIB.TIMECARD(SCH_1):PAGE164
  C166    1      1 CAPACITOR-G105-0B104-CK,0.1UF,A   I196 @TIMECARD_LIB.TIMECARD(SCH_1):PAGE164
  C169    1      1 CAPACITOR-G105-0B104-CK,0.1UF,A   I197 @TIMECARD_LIB.TIMECARD(SCH_1):PAGE164
  C171    1      1 CAPACITOR-G105-0B104-CK,0.1UF,A   I198 @TIMECARD_LIB.TIMECARD(SCH_1):PAGE164
  C177    1      1 CAPACITOR-G109-0G107-BM,100UF,A   I277 @TIMECARD_LIB.TIMECARD(SCH_1):PAGE164
  C173    1      1 CAPACITOR-G107-0F476-AM,47UF,2A   I280 @TIMECARD_LIB.TIMECARD(SCH_1):PAGE164

XP1R0V_PG @TIMECARD_LIB.TIMECARD(SCH_1):XP1R0V_PG
   U26   18  PGOOD TPS54824RNVR_VQFN18-G220-10657A    I11 @TIMECARD_LIB.TIMECARD(SCH_1):PAGE523
  R243    2      2 RESISTOR-G155-14701-01,4.7KOHMA    I44 @TIMECARD_LIB.TIMECARD(SCH_1):PAGE523
  C258    2      2 CAPACITOR-G104-0B103-EK,0.01UFA    I50 @TIMECARD_LIB.TIMECARD(SCH_1):PAGE523
  R245    2      2 RESISTOR-G155-100R0-J0,0OHM,-   I104 @TIMECARD_LIB.TIMECARD(SCH_1):PAGE523

XP1R0V_RT @TIMECARD_LIB.TIMECARD(SCH_1):XP1R0V_RT
   U26   13 RT/CLK TPS54824RNVR_VQFN18-G220-10657A    I11 @TIMECARD_LIB.TIMECARD(SCH_1):PAGE523
  R248    1      1 RESISTOR-G155-11003-01,100KOHMA    I15 @TIMECARD_LIB.TIMECARD(SCH_1):PAGE523

XP1R0V_SS @TIMECARD_LIB.TIMECARD(SCH_1):XP1R0V_SS
   U26   16 SS/TRK TPS54824RNVR_VQFN18-G220-10657A    I11 @TIMECARD_LIB.TIMECARD(SCH_1):PAGE523
  C259    1      1 CAPACITOR-G105-0B223-EK,0.022UA    I12 @TIMECARD_LIB.TIMECARD(SCH_1):PAGE523

XP1R0V_SW @TIMECARD_LIB.TIMECARD(SCH_1):XP1R0V_SW
   U26    6   SW_1 TPS54824RNVR_VQFN18-G220-10657A    I11 @TIMECARD_LIB.TIMECARD(SCH_1):PAGE523
   U26    7   SW_2 TPS54824RNVR_VQFN18-G220-10657A    I11 @TIMECARD_LIB.TIMECARD(SCH_1):PAGE523
  C265    2      2 CAPACITOR-G105-0B104-EK,0.1UF,A    I24 @TIMECARD_LIB.TIMECARD(SCH_1):PAGE523
    L5    1      1 INDUCTOR_2-G190-10418-01,1.0UHA    I25 @TIMECARD_LIB.TIMECARD(SCH_1):PAGE523
  C266    1      1 CAPACITOR-G105-0A102-FJ,1000PFA    I31 @TIMECARD_LIB.TIMECARD(SCH_1):PAGE523

XP1R2V_EN_R @TIMECARD_LIB.TIMECARD(SCH_1):XP1R2V_EN_R
  R165    1      1 RESISTOR-G155-11002-01,10KOHM,A     I2 @TIMECARD_LIB.TIMECARD(SCH_1):PAGE68
  C184    1      1 CAPACITOR-G105-0B104-EK,0.1UF,A     I3 @TIMECARD_LIB.TIMECARD(SCH_1):PAGE68
   U20    7 ENABLE ISL80101IRAJZ_DFN10-G222-10136A     I6 @TIMECARD_LIB.TIMECARD(SCH_1):PAGE68
  R140    2      2 RESISTOR-G155-100R0-J0,0OHM,-    I18 @TIMECARD_LIB.TIMECARD(SCH_1):PAGE68
  R177    2      2 RESISTOR-G152-00055-01,1.13KOHA    I26 @TIMECARD_LIB.TIMECARD(SCH_1):PAGE68

XP1R2V_FB @TIMECARD_LIB.TIMECARD(SCH_1):XP1R2V_FB
   U20    3 SENSE/ADJ ISL80101IRAJZ_DFN10-G222-10136A     I6 @TIMECARD_LIB.TIMECARD(SCH_1):PAGE68
  R186    2      2 RESISTOR-G155-03001-01,3KOHM,1%    I14 @TIMECARD_LIB.TIMECARD(SCH_1):PAGE68
  R189    2      2 RESISTOR-G155-03241-01,3.24KOHA    I16 @TIMECARD_LIB.TIMECARD(SCH_1):PAGE68
  R185    2      2 RESISTOR-G155-04221-01,4.22KOHA    I59 @TIMECARD_LIB.TIMECARD(SCH_1):PAGE68

XP1R2V_FPGA @TIMECARD_LIB.TIMECARD(SCH_1):XP1R2V_FPGA
   U20    1 VOUT_1 ISL80101IRAJZ_DFN10-G222-10136A     I6 @TIMECARD_LIB.TIMECARD(SCH_1):PAGE68
   U20    2 VOUT_2 ISL80101IRAJZ_DFN10-G222-10136A     I6 @TIMECARD_LIB.TIMECARD(SCH_1):PAGE68
  R185    1      1 RESISTOR-G155-04221-01,4.22KOHA    I59 @TIMECARD_LIB.TIMECARD(SCH_1):PAGE68
  C194    1      1 CAPACITOR-G107-0F106-EM,10UF,2A    I60 @TIMECARD_LIB.TIMECARD(SCH_1):PAGE68
  C196    1      1 CAPACITOR-G105-0B104-EK,0.1UF,A    I61 @TIMECARD_LIB.TIMECARD(SCH_1):PAGE68
   L35    2      2 FERRITEBEAD-G191-10100-01,120OA    I36 @TIMECARD_LIB.TIMECARD(SCH_1):PAGE164
  C136    1      1 CAPACITOR-G105-0B104-CK,0.1UF,A   I249 @TIMECARD_LIB.TIMECARD(SCH_1):PAGE164
  C143    1      1 CAPACITOR-G107-0F476-AM,47UF,2A   I265 @TIMECARD_LIB.TIMECARD(SCH_1):PAGE164
  TP55    1      1 TP_PIONT-TP010CT020B030_PTH-TPA  I1212 @TIMECARD_LIB.TIMECARD(SCH_1):PAGE16

XP1R2V_FPGA_PG @TIMECARD_LIB.TIMECARD(SCH_1):XP1R2V_FPGA_PG
  R181    2      2 RESISTOR-G155-100R0-J0,0OHM,-    I10 @TIMECARD_LIB.TIMECARD(SCH_1):PAGE68
  R141    1      1 RESISTOR-G155-100R0-J0,0OHM,-    I42 @TIMECARD_LIB.TIMECARD(SCH_1):PAGE68
  TP40    1      1 TP_PIONT-TP010CT020B030_PTH-TPA  I1653 @TIMECARD_LIB.TIMECARD(SCH_1):PAGE16

XP1R2V_PG_R @TIMECARD_LIB.TIMECARD(SCH_1):XP1R2V_PG_R
   U20    4     PG ISL80101IRAJZ_DFN10-G222-10136A     I6 @TIMECARD_LIB.TIMECARD(SCH_1):PAGE68
  C192    1      1 CAPACITOR-G104-0B103-EK,0.01UFA     I9 @TIMECARD_LIB.TIMECARD(SCH_1):PAGE68
  R181    1      1 RESISTOR-G155-100R0-J0,0OHM,-    I10 @TIMECARD_LIB.TIMECARD(SCH_1):PAGE68
  R178    2      2 RESISTOR-G155-14701-01,4.7KOHMA    I11 @TIMECARD_LIB.TIMECARD(SCH_1):PAGE68

XP1R2V_SS @TIMECARD_LIB.TIMECARD(SCH_1):XP1R2V_SS
  C190    1      1 CAPACITOR-G104-0B103-EK,0.01UFA     I5 @TIMECARD_LIB.TIMECARD(SCH_1):PAGE68
   U20    6     SS ISL80101IRAJZ_DFN10-G222-10136A     I6 @TIMECARD_LIB.TIMECARD(SCH_1):PAGE68

XP1R2V_VIN @TIMECARD_LIB.TIMECARD(SCH_1):XP1R2V_VIN
   U20    9  VIN_1 ISL80101IRAJZ_DFN10-G222-10136A     I6 @TIMECARD_LIB.TIMECARD(SCH_1):PAGE68
   U20   10  VIN_2 ISL80101IRAJZ_DFN10-G222-10136A     I6 @TIMECARD_LIB.TIMECARD(SCH_1):PAGE68
   L11    2      2 FERRITEBEAD-G191-10101-01,26OHA    I25 @TIMECARD_LIB.TIMECARD(SCH_1):PAGE68
  R177    1      1 RESISTOR-G152-00055-01,1.13KOHA    I26 @TIMECARD_LIB.TIMECARD(SCH_1):PAGE68
  C185    1      1 CAPACITOR-G107-0F106-EM,10UF,2A    I27 @TIMECARD_LIB.TIMECARD(SCH_1):PAGE68
  C188    1      1 CAPACITOR-G105-0B104-EK,0.1UF,A    I35 @TIMECARD_LIB.TIMECARD(SCH_1):PAGE68

XP1R8V_EN_R @TIMECARD_LIB.TIMECARD(SCH_1):XP1R8V_EN_R
  R141    2      2 RESISTOR-G155-100R0-J0,0OHM,-    I42 @TIMECARD_LIB.TIMECARD(SCH_1):PAGE68
  R174    1      1 RESISTOR-G155-11002-01,10KOHM,A    I44 @TIMECARD_LIB.TIMECARD(SCH_1):PAGE68
  R166    2      2 RESISTOR-G152-00055-01,1.13KOHA    I45 @TIMECARD_LIB.TIMECARD(SCH_1):PAGE68
  C187    1      1 CAPACITOR-G105-0B104-EK,0.1UF,A    I46 @TIMECARD_LIB.TIMECARD(SCH_1):PAGE68
   U21    7 ENABLE ISL80101IRAJZ_DFN10-G222-10136A    I52 @TIMECARD_LIB.TIMECARD(SCH_1):PAGE68

XP1R8V_FB @TIMECARD_LIB.TIMECARD(SCH_1):XP1R8V_FB
   U21    3 SENSE/ADJ ISL80101IRAJZ_DFN10-G222-10136A    I52 @TIMECARD_LIB.TIMECARD(SCH_1):PAGE68
  R187    2      2 RESISTOR-G155-04221-01,4.22KOHA    I78 @TIMECARD_LIB.TIMECARD(SCH_1):PAGE68
  R188    2      2 RESISTOR-G155-03241-01,3.24KOHA    I79 @TIMECARD_LIB.TIMECARD(SCH_1):PAGE68
  R190    2      2 RESISTOR-G155-03241-01,3.24KOHA    I80 @TIMECARD_LIB.TIMECARD(SCH_1):PAGE68

XP1R8V_FPGA @TIMECARD_LIB.TIMECARD(SCH_1):XP1R8V_FPGA
   U21    1 VOUT_1 ISL80101IRAJZ_DFN10-G222-10136A    I52 @TIMECARD_LIB.TIMECARD(SCH_1):PAGE68
   U21    2 VOUT_2 ISL80101IRAJZ_DFN10-G222-10136A    I52 @TIMECARD_LIB.TIMECARD(SCH_1):PAGE68
  R187    1      1 RESISTOR-G155-04221-01,4.22KOHA    I78 @TIMECARD_LIB.TIMECARD(SCH_1):PAGE68
  C195    1      1 CAPACITOR-G107-0F106-EM,10UF,2A    I81 @TIMECARD_LIB.TIMECARD(SCH_1):PAGE68
  C197    1      1 CAPACITOR-G105-0B104-EK,0.1UF,A    I83 @TIMECARD_LIB.TIMECARD(SCH_1):PAGE68
   L33    2      2 FERRITEBEAD-G191-10100-01,120OA   I102 @TIMECARD_LIB.TIMECARD(SCH_1):PAGE164
  C158    1      1 CAPACITOR-G107-0F226-CM,22UF,2A   I176 @TIMECARD_LIB.TIMECARD(SCH_1):PAGE164
  C150    1      1 CAPACITOR-G105-0B104-CK,0.1UF,A   I276 @TIMECARD_LIB.TIMECARD(SCH_1):PAGE164
  C276    1      1 CAPACITOR-G105-0B104-EK,0.1UF,A    I16 @TIMECARD_LIB.TIMECARD(SCH_1):PAGE8
   L18    1      1 FERRITEBEAD-G191-10097-01,600OA    I18 @TIMECARD_LIB.TIMECARD(SCH_1):PAGE8
  TP56    1      1 TP_PIONT-TP010CT020B030_PTH-TPA  I1215 @TIMECARD_LIB.TIMECARD(SCH_1):PAGE16

XP1R8V_FPGA_PG @TIMECARD_LIB.TIMECARD(SCH_1):XP1R8V_FPGA_PG
  R142    1      1 RESISTOR-G155-11000-01,100OHM,A    I44 @TIMECARD_LIB.TIMECARD(SCH_1):PAGE516
  R182    2      2 RESISTOR-G155-100R0-J0,0OHM,-    I74 @TIMECARD_LIB.TIMECARD(SCH_1):PAGE68
  R226    1      1 RESISTOR-G155-13300-01,330OHM,A   I122 @TIMECARD_LIB.TIMECARD(SCH_1):PAGE515
  R225    1      1 RESISTOR-G155-13300-01,330OHM,A   I152 @TIMECARD_LIB.TIMECARD(SCH_1):PAGE515
  TP41    1      1 TP_PIONT-TP010CT020B030_PTH-TPA  I1654 @TIMECARD_LIB.TIMECARD(SCH_1):PAGE16

XP1R8V_FPGA_VCCAUX @TIMECARD_LIB.TIMECARD(SCH_1):XP1R8V_FPGA_VCCAUX
   L33    1      1 FERRITEBEAD-G191-10100-01,120OA   I102 @TIMECARD_LIB.TIMECARD(SCH_1):PAGE164
   U24  K10 VCCADC_0 XC7A200T_2FBG484C_FBG484-G240-A   I138 @TIMECARD_LIB.TIMECARD(SCH_1):PAGE164
   U24  H12 VCCAUX_1 XC7A200T_2FBG484C_FBG484-G240-A   I138 @TIMECARD_LIB.TIMECARD(SCH_1):PAGE164
   U24  K12 VCCAUX_2 XC7A200T_2FBG484C_FBG484-G240-A   I138 @TIMECARD_LIB.TIMECARD(SCH_1):PAGE164
   U24  M12 VCCAUX_3 XC7A200T_2FBG484C_FBG484-G240-A   I138 @TIMECARD_LIB.TIMECARD(SCH_1):PAGE164
   U24  P12 VCCAUX_4 XC7A200T_2FBG484C_FBG484-G240-A   I138 @TIMECARD_LIB.TIMECARD(SCH_1):PAGE164
   U24  R11 VCCAUX_5 XC7A200T_2FBG484C_FBG484-G240-A   I138 @TIMECARD_LIB.TIMECARD(SCH_1):PAGE164
   U24  E12 VCCBATT_0 XC7A200T_2FBG484C_FBG484-G240-A   I138 @TIMECARD_LIB.TIMECARD(SCH_1):PAGE164
  C120    1      1 CAPACITOR-G105-0F475-BM,4.7UF,A   I177 @TIMECARD_LIB.TIMECARD(SCH_1):PAGE164
  C200    1      1 CAPACITOR-G105-0B104-CK,0.1UF,A   I199 @TIMECARD_LIB.TIMECARD(SCH_1):PAGE164
  C206    1      1 CAPACITOR-G105-0B104-CK,0.1UF,A   I200 @TIMECARD_LIB.TIMECARD(SCH_1):PAGE164
  C212    1      1 CAPACITOR-G105-0B104-CK,0.1UF,A   I201 @TIMECARD_LIB.TIMECARD(SCH_1):PAGE164
  C219    1      1 CAPACITOR-G105-0B104-CK,0.1UF,A   I202 @TIMECARD_LIB.TIMECARD(SCH_1):PAGE164
  C106    1      1 CAPACITOR-G105-0B104-CK,0.1UF,A   I203 @TIMECARD_LIB.TIMECARD(SCH_1):PAGE164
  C113    1      1 CAPACITOR-G105-0B104-CK,0.1UF,A   I204 @TIMECARD_LIB.TIMECARD(SCH_1):PAGE164
  C128    1      1 CAPACITOR-G105-0F475-BM,4.7UF,A   I243 @TIMECARD_LIB.TIMECARD(SCH_1):PAGE164
  C138    1      1 CAPACITOR-G105-0F475-BM,4.7UF,A   I275 @TIMECARD_LIB.TIMECARD(SCH_1):PAGE164

XP1R8V_ICP10100 @TIMECARD_LIB.TIMECARD(SCH_1):XP1R8V_ICP10100
   R70    1      1 RESISTOR-G155-14701-01,4.7KOHMA     I3 @TIMECARD_LIB.TIMECARD(SCH_1):PAGE8
   R71    1      1 RESISTOR-G155-14701-01,4.7KOHMA     I5 @TIMECARD_LIB.TIMECARD(SCH_1):PAGE8
   L18    2      2 FERRITEBEAD-G191-10097-01,600OA    I18 @TIMECARD_LIB.TIMECARD(SCH_1):PAGE8
  C278    1      1 CAPACITOR-G105-0B104-EK,0.1UF,A    I19 @TIMECARD_LIB.TIMECARD(SCH_1):PAGE8
  C277    1      1 CAPACITOR-G105-0C106-BM,10UF,2A    I21 @TIMECARD_LIB.TIMECARD(SCH_1):PAGE8
   U28   10    VDD ICP_10100_LGA10-A222-00002-FB,A    I24 @TIMECARD_LIB.TIMECARD(SCH_1):PAGE8
  R350    2      2 RESISTOR-G155-100R0-J0,0OHM,-    I31 @TIMECARD_LIB.TIMECARD(SCH_1):PAGE8
  R347    2      2 RESISTOR-G155-100R0-J0,0OHM,-    I32 @TIMECARD_LIB.TIMECARD(SCH_1):PAGE8
  C313    1      1 CAPACITOR-G105-0B104-CK,0.1UF,A    I41 @TIMECARD_LIB.TIMECARD(SCH_1):PAGE8
   U32    1  VCC_A PCA9508DP_TSSOP8-G223-10278-01    I52 @TIMECARD_LIB.TIMECARD(SCH_1):PAGE8

XP1R8V_PG_R @TIMECARD_LIB.TIMECARD(SCH_1):XP1R8V_PG_R
   U21    4     PG ISL80101IRAJZ_DFN10-G222-10136A    I52 @TIMECARD_LIB.TIMECARD(SCH_1):PAGE68
  C193    1      1 CAPACITOR-G104-0B103-EK,0.01UFA    I71 @TIMECARD_LIB.TIMECARD(SCH_1):PAGE68
  R179    2      2 RESISTOR-G155-14701-01,4.7KOHMA    I73 @TIMECARD_LIB.TIMECARD(SCH_1):PAGE68
  R182    1      1 RESISTOR-G155-100R0-J0,0OHM,-    I74 @TIMECARD_LIB.TIMECARD(SCH_1):PAGE68

XP1R8V_SS @TIMECARD_LIB.TIMECARD(SCH_1):XP1R8V_SS
  C191    1      1 CAPACITOR-G104-0B103-EK,0.01UFA    I49 @TIMECARD_LIB.TIMECARD(SCH_1):PAGE68
   U21    6     SS ISL80101IRAJZ_DFN10-G222-10136A    I52 @TIMECARD_LIB.TIMECARD(SCH_1):PAGE68

XP1R8V_VIN @TIMECARD_LIB.TIMECARD(SCH_1):XP1R8V_VIN
    L6    2      2 FERRITEBEAD-G191-10101-01,26OHA    I43 @TIMECARD_LIB.TIMECARD(SCH_1):PAGE68
  R166    1      1 RESISTOR-G152-00055-01,1.13KOHA    I45 @TIMECARD_LIB.TIMECARD(SCH_1):PAGE68
  C186    1      1 CAPACITOR-G107-0F106-EM,10UF,2A    I47 @TIMECARD_LIB.TIMECARD(SCH_1):PAGE68
  C189    1      1 CAPACITOR-G105-0B104-EK,0.1UF,A    I51 @TIMECARD_LIB.TIMECARD(SCH_1):PAGE68
   U21    9  VIN_1 ISL80101IRAJZ_DFN10-G222-10136A    I52 @TIMECARD_LIB.TIMECARD(SCH_1):PAGE68
   U21   10  VIN_2 ISL80101IRAJZ_DFN10-G222-10136A    I52 @TIMECARD_LIB.TIMECARD(SCH_1):PAGE68

XP2R5V_FPGA @TIMECARD_LIB.TIMECARD(SCH_1):XP2R5V_FPGA
   R61    2      2 RESISTOR-G155-100R0-J0,0OHM,-    I52 @TIMECARD_LIB.TIMECARD(SCH_1):PAGE5
   U24  AA7 VCCO_34_1 XC7A200T_2FBG484C_FBG484-G240-A   I138 @TIMECARD_LIB.TIMECARD(SCH_1):PAGE164
   U24  AB4 VCCO_34_2 XC7A200T_2FBG484C_FBG484-G240-A   I138 @TIMECARD_LIB.TIMECARD(SCH_1):PAGE164
   U24   R5 VCCO_34_3 XC7A200T_2FBG484C_FBG484-G240-A   I138 @TIMECARD_LIB.TIMECARD(SCH_1):PAGE164
   U24   T2 VCCO_34_4 XC7A200T_2FBG484C_FBG484-G240-A   I138 @TIMECARD_LIB.TIMECARD(SCH_1):PAGE164
   U24   V6 VCCO_34_5 XC7A200T_2FBG484C_FBG484-G240-A   I138 @TIMECARD_LIB.TIMECARD(SCH_1):PAGE164
   U24   W3 VCCO_34_6 XC7A200T_2FBG484C_FBG484-G240-A   I138 @TIMECARD_LIB.TIMECARD(SCH_1):PAGE164
   U24   C1 VCCO_35_1 XC7A200T_2FBG484C_FBG484-G240-A   I138 @TIMECARD_LIB.TIMECARD(SCH_1):PAGE164
   U24   F2 VCCO_35_2 XC7A200T_2FBG484C_FBG484-G240-A   I138 @TIMECARD_LIB.TIMECARD(SCH_1):PAGE164
   U24   H6 VCCO_35_3 XC7A200T_2FBG484C_FBG484-G240-A   I138 @TIMECARD_LIB.TIMECARD(SCH_1):PAGE164
   U24   J3 VCCO_35_4 XC7A200T_2FBG484C_FBG484-G240-A   I138 @TIMECARD_LIB.TIMECARD(SCH_1):PAGE164
   U24   M4 VCCO_35_5 XC7A200T_2FBG484C_FBG484-G240-A   I138 @TIMECARD_LIB.TIMECARD(SCH_1):PAGE164
   U24   N1 VCCO_35_6 XC7A200T_2FBG484C_FBG484-G240-A   I138 @TIMECARD_LIB.TIMECARD(SCH_1):PAGE164
  C204    1      1 CAPACITOR-G105-0B104-CK,0.1UF,A   I231 @TIMECARD_LIB.TIMECARD(SCH_1):PAGE164
  C208    1      1 CAPACITOR-G105-0B104-CK,0.1UF,A   I232 @TIMECARD_LIB.TIMECARD(SCH_1):PAGE164
  C213    1      1 CAPACITOR-G105-0B104-CK,0.1UF,A   I233 @TIMECARD_LIB.TIMECARD(SCH_1):PAGE164
  C220    1      1 CAPACITOR-G105-0B104-CK,0.1UF,A   I234 @TIMECARD_LIB.TIMECARD(SCH_1):PAGE164
  C108    1      1 CAPACITOR-G105-0B104-CK,0.1UF,A   I235 @TIMECARD_LIB.TIMECARD(SCH_1):PAGE164
  C116    1      1 CAPACITOR-G105-0B104-CK,0.1UF,A   I236 @TIMECARD_LIB.TIMECARD(SCH_1):PAGE164
  C122    1      1 CAPACITOR-G105-0B104-CK,0.1UF,A   I237 @TIMECARD_LIB.TIMECARD(SCH_1):PAGE164
  C127    1      1 CAPACITOR-G105-0B104-CK,0.1UF,A   I238 @TIMECARD_LIB.TIMECARD(SCH_1):PAGE164
  C135    1      1 CAPACITOR-G105-0B104-CK,0.1UF,A   I239 @TIMECARD_LIB.TIMECARD(SCH_1):PAGE164
  C142    1      1 CAPACITOR-G105-0B104-CK,0.1UF,A   I240 @TIMECARD_LIB.TIMECARD(SCH_1):PAGE164
  C146    1      1 CAPACITOR-G105-0B104-CK,0.1UF,A   I241 @TIMECARD_LIB.TIMECARD(SCH_1):PAGE164
  C151    1      1 CAPACITOR-G105-0B104-CK,0.1UF,A   I242 @TIMECARD_LIB.TIMECARD(SCH_1):PAGE164
  C160    1      1 CAPACITOR-G105-0F475-BM,4.7UF,A   I245 @TIMECARD_LIB.TIMECARD(SCH_1):PAGE164
  C168    1      1 CAPACITOR-G107-0F226-CM,22UF,2A   I267 @TIMECARD_LIB.TIMECARD(SCH_1):PAGE164
  C164    1      1 CAPACITOR-G107-0F226-CM,22UF,2A   I268 @TIMECARD_LIB.TIMECARD(SCH_1):PAGE164
  R231    1      1 RESISTOR-G155-04221-01,4.22KOHA   I146 @TIMECARD_LIB.TIMECARD(SCH_1):PAGE515
  C239    1      1 CAPACITOR-G107-0F106-EM,10UF,2A   I147 @TIMECARD_LIB.TIMECARD(SCH_1):PAGE515
  C242    1      1 CAPACITOR-G105-0B104-EK,0.1UF,A   I149 @TIMECARD_LIB.TIMECARD(SCH_1):PAGE515
   U25    1 VOUT_1 ISL80101IRAJZ_DFN10-G222-10136A   I151 @TIMECARD_LIB.TIMECARD(SCH_1):PAGE515
   U25    2 VOUT_2 ISL80101IRAJZ_DFN10-G222-10136A   I151 @TIMECARD_LIB.TIMECARD(SCH_1):PAGE515
  R139    2      2 RESISTOR-G155-133R0-01,33OHM,1%    I60 @TIMECARD_LIB.TIMECARD(SCH_1):PAGE14
  TP57    1      1 TP_PIONT-TP010CT020B030_PTH-TPA  I1217 @TIMECARD_LIB.TIMECARD(SCH_1):PAGE16
  R355    2      2 RESISTOR-G155-11002-01,10KOHM,A   I120 @TIMECARD_LIB.TIMECARD(SCH_1):PAGE163
  R358    2      2 RESISTOR-G155-11002-01,10KOHM,A   I126 @TIMECARD_LIB.TIMECARD(SCH_1):PAGE163
  C291    1      1 CAPACITOR-G107-0F226-CM,22UF,2A   I290 @TIMECARD_LIB.TIMECARD(SCH_1):PAGE164
  C292    1      1 CAPACITOR-G107-0F226-CM,22UF,2A   I291 @TIMECARD_LIB.TIMECARD(SCH_1):PAGE164
   C93    1      1 CAPACITOR-G105-0F475-BM,4.7UF,A   I292 @TIMECARD_LIB.TIMECARD(SCH_1):PAGE164
  R438    2      2 RESISTOR-G155-11002-01,10KOHM,A   I132 @TIMECARD_LIB.TIMECARD(SCH_1):PAGE163
  R439    2      2 RESISTOR-G155-11002-01,10KOHM,A   I133 @TIMECARD_LIB.TIMECARD(SCH_1):PAGE163

XP3R3V @TIMECARD_LIB.TIMECARD(SCH_1):XP3R3V
   R56    1      1 RESISTOR-G155-14701-01,4.7KOHMA    I63 @TIMECARD_LIB.TIMECARD(SCH_1):PAGE3
   R51    1      1 RESISTOR-G155-11002-01,10KOHM,A     I3 @TIMECARD_LIB.TIMECARD(SCH_1):PAGE517
    L2    2      2 INDUCTOR_2-G190-10424-01,4.7UHA    I28 @TIMECARD_LIB.TIMECARD(SCH_1):PAGE517
   R17    1      1 RESISTOR-G155-120R0-01,20OHM,1%    I33 @TIMECARD_LIB.TIMECARD(SCH_1):PAGE517
   C18    1      1 CAPACITOR-G105-0B104-CK,0.1UF,A    I36 @TIMECARD_LIB.TIMECARD(SCH_1):PAGE517
   C20    1      1 CAPACITOR-G107-0F226-CM,22UF,2A    I37 @TIMECARD_LIB.TIMECARD(SCH_1):PAGE517
   C21    1      1 CAPACITOR-G107-0F226-CM,22UF,2A    I38 @TIMECARD_LIB.TIMECARD(SCH_1):PAGE517
   C22    1      1 CAPACITOR-G107-0F226-CM,22UF,2A    I40 @TIMECARD_LIB.TIMECARD(SCH_1):PAGE517
   R47    1      1 RESISTOR-G155-11002-01,10KOHM,A     I1 @TIMECARD_LIB.TIMECARD(SCH_1):PAGE516
  R178    1      1 RESISTOR-G155-14701-01,4.7KOHMA    I11 @TIMECARD_LIB.TIMECARD(SCH_1):PAGE68
   L11    1      1 FERRITEBEAD-G191-10101-01,26OHA    I25 @TIMECARD_LIB.TIMECARD(SCH_1):PAGE68
    L6    1      1 FERRITEBEAD-G191-10101-01,26OHA    I43 @TIMECARD_LIB.TIMECARD(SCH_1):PAGE68
  R179    1      1 RESISTOR-G155-14701-01,4.7KOHMA    I73 @TIMECARD_LIB.TIMECARD(SCH_1):PAGE68
  C180    1      1 CAPACITOR-G107-0F226-CM,22UF,2A    I93 @TIMECARD_LIB.TIMECARD(SCH_1):PAGE68
  C182    1      1 CAPACITOR-G105-0B104-EK,0.1UF,A    I94 @TIMECARD_LIB.TIMECARD(SCH_1):PAGE68
  C181    1      1 CAPACITOR-G107-0F226-CM,22UF,2A    I97 @TIMECARD_LIB.TIMECARD(SCH_1):PAGE68
  C183    1      1 CAPACITOR-G105-0B104-EK,0.1UF,A    I98 @TIMECARD_LIB.TIMECARD(SCH_1):PAGE68
  C232    1      1 CAPACITOR-G107-0F226-CM,22UF,2A    I61 @TIMECARD_LIB.TIMECARD(SCH_1):PAGE515
  C233    1      1 CAPACITOR-G105-0B104-CK,0.1UF,A    I63 @TIMECARD_LIB.TIMECARD(SCH_1):PAGE515
  R260    1      1 RESISTOR-G155-11001-01,1KOHM,1%    I67 @TIMECARD_LIB.TIMECARD(SCH_1):PAGE515
   U22    3    VCC NCP45560IMNTWG_H_DFN12-G222-10A    I76 @TIMECARD_LIB.TIMECARD(SCH_1):PAGE515
  C235    1      1 CAPACITOR-G105-0B104-CK,0.1UF,A    I80 @TIMECARD_LIB.TIMECARD(SCH_1):PAGE515
   U22    1  VIN_1 NCP45560IMNTWG_H_DFN12-G222-10A    I82 @TIMECARD_LIB.TIMECARD(SCH_1):PAGE515
   U22   13  VIN_2 NCP45560IMNTWG_H_DFN12-G222-10A    I82 @TIMECARD_LIB.TIMECARD(SCH_1):PAGE515
   L13    1      1 FERRITEBEAD-G191-10101-01,26OHA   I135 @TIMECARD_LIB.TIMECARD(SCH_1):PAGE515
  C224    1      1 CAPACITOR-G107-0F226-CM,22UF,2A   I154 @TIMECARD_LIB.TIMECARD(SCH_1):PAGE515
  C226    1      1 CAPACITOR-G105-0B104-EK,0.1UF,A   I155 @TIMECARD_LIB.TIMECARD(SCH_1):PAGE515
   L14    2      2 FERRITEBEAD-G191-10097-01,600OA   I146 @TIMECARD_LIB.TIMECARD(SCH_1):PAGE522
  C244    1      1 CAPACITOR-G105-0B104-EK,0.1UF,A   I152 @TIMECARD_LIB.TIMECARD(SCH_1):PAGE522
  C245    1      1 CAPACITOR-G105-0B104-EK,0.1UF,A   I153 @TIMECARD_LIB.TIMECARD(SCH_1):PAGE522
   L10    2      2 FERRITEBEAD-G191-10097-01,600OA   I159 @TIMECARD_LIB.TIMECARD(SCH_1):PAGE522
  R243    1      1 RESISTOR-G155-14701-01,4.7KOHMA    I44 @TIMECARD_LIB.TIMECARD(SCH_1):PAGE523
  TP53    1      1 TP_PIONT-TP010CT020B030_PTH-TPA  I1208 @TIMECARD_LIB.TIMECARD(SCH_1):PAGE16
  C312    1      1 CAPACITOR-G105-0B104-CK,0.1UF,A    I39 @TIMECARD_LIB.TIMECARD(SCH_1):PAGE8
   U32    8  VCC_B PCA9508DP_TSSOP8-G223-10278-01    I52 @TIMECARD_LIB.TIMECARD(SCH_1):PAGE8
   L21    2      2 FERRITEBEAD-G191-10101-01,26OHA   I132 @TIMECARD_LIB.TIMECARD(SCH_1):PAGE3

XP3R3V_AGND @TIMECARD_LIB.TIMECARD(SCH_1):XP3R3V_AGND
   C49    2      2 CAPACITOR-G105-0B223-EK,0.022UA     I9 @TIMECARD_LIB.TIMECARD(SCH_1):PAGE517
   R35    2      2 RESISTOR-G155-11003-01,100KOHMA    I10 @TIMECARD_LIB.TIMECARD(SCH_1):PAGE517
   C54    2      2 CAPACITOR-G105-0B222-FK,2200PFA    I17 @TIMECARD_LIB.TIMECARD(SCH_1):PAGE517
   C55    2      2 CAPACITOR-G104-0A180-FJ,18PF,5%    I19 @TIMECARD_LIB.TIMECARD(SCH_1):PAGE517
   SP2    2      2 SOLDER_PREFORM-G380-10015-01    I24 @TIMECARD_LIB.TIMECARD(SCH_1):PAGE517
   R38    2      2 RESISTOR-G155-04421-01,4.42KOHA    I26 @TIMECARD_LIB.TIMECARD(SCH_1):PAGE517
   R54    1      1 RESISTOR-G156-100R0-J0,0OHM,-    I41 @TIMECARD_LIB.TIMECARD(SCH_1):PAGE517
    U6   12   AGND TPS54824RNVR_VQFN18-G220-10657A    I42 @TIMECARD_LIB.TIMECARD(SCH_1):PAGE517

XP3R3V_AUX_PCIE @TIMECARD_LIB.TIMECARD(SCH_1):XP3R3V_AUX_PCIE
   GF1  B10 P_3V3AUX CONN_64P_GF-S_M_EF64_PCIE_P039A    I61 @TIMECARD_LIB.TIMECARD(SCH_1):PAGE3
  C288    1      1 CAPACITOR-G105-0B104-EK,0.1UF,A   I127 @TIMECARD_LIB.TIMECARD(SCH_1):PAGE3
  C287    1      1 CAPACITOR-G105-0C106-BM,10UF,2A   I129 @TIMECARD_LIB.TIMECARD(SCH_1):PAGE3
  R119    2      2 RESISTOR-G155-13300-01,330OHM,A   I192 @TIMECARD_LIB.TIMECARD(SCH_1):PAGE14

XP3R3V_BT @TIMECARD_LIB.TIMECARD(SCH_1):XP3R3V_BT
   R37    1      1 RESISTOR-G155-100R0-J0,0OHM,-    I25 @TIMECARD_LIB.TIMECARD(SCH_1):PAGE517
    U6    1   BOOT TPS54824RNVR_VQFN18-G220-10657A    I42 @TIMECARD_LIB.TIMECARD(SCH_1):PAGE517

XP3R3V_COMP @TIMECARD_LIB.TIMECARD(SCH_1):XP3R3V_COMP
   R36    1      1 RESISTOR-G155-11002-01,10KOHM,A    I18 @TIMECARD_LIB.TIMECARD(SCH_1):PAGE517
   C55    1      1 CAPACITOR-G104-0A180-FJ,18PF,5%    I19 @TIMECARD_LIB.TIMECARD(SCH_1):PAGE517
    U6   15   COMP TPS54824RNVR_VQFN18-G220-10657A    I42 @TIMECARD_LIB.TIMECARD(SCH_1):PAGE517

XP3R3V_EN @TIMECARD_LIB.TIMECARD(SCH_1):XP3R3V_EN
   R52    1      1 RESISTOR-G155-05101-01,5.1KOHMA    I11 @TIMECARD_LIB.TIMECARD(SCH_1):PAGE517
   C46    1      1 CAPACITOR-G105-0B104-CK,0.1UF,A    I12 @TIMECARD_LIB.TIMECARD(SCH_1):PAGE517
   R53    2      2 RESISTOR-G152-10344-01,30KOHM,A    I13 @TIMECARD_LIB.TIMECARD(SCH_1):PAGE517
    U6   17     EN TPS54824RNVR_VQFN18-G220-10657A    I42 @TIMECARD_LIB.TIMECARD(SCH_1):PAGE517
  C286    1      1 CAPACITOR-G105-0B224-DK,0.22UFA    I51 @TIMECARD_LIB.TIMECARD(SCH_1):PAGE517
  TP59    1      1 TP_PIONT-TP010CT020B030_PTH-TPA  I1663 @TIMECARD_LIB.TIMECARD(SCH_1):PAGE16

XP3R3V_FB_R_TO_AGND @TIMECARD_LIB.TIMECARD(SCH_1):XP3R3V_FB_R_TO_AGND
   R38    1      1 RESISTOR-G155-04421-01,4.42KOHA    I26 @TIMECARD_LIB.TIMECARD(SCH_1):PAGE517
   C16    2      2 CAPACITOR-G104-0B101-FK,100PF,A    I30 @TIMECARD_LIB.TIMECARD(SCH_1):PAGE517
   R40    2      2 RESISTOR-G155-12002-01,20KOHM,A    I31 @TIMECARD_LIB.TIMECARD(SCH_1):PAGE517
   R54    2      2 RESISTOR-G156-100R0-J0,0OHM,-    I41 @TIMECARD_LIB.TIMECARD(SCH_1):PAGE517
    U6   14     FB TPS54824RNVR_VQFN18-G220-10657A    I42 @TIMECARD_LIB.TIMECARD(SCH_1):PAGE517

XP3R3V_FPGA @TIMECARD_LIB.TIMECARD(SCH_1):XP3R3V_FPGA
   C37    1      1 CAPACITOR-G105-0B104-CK,0.1UF,A     I4 @TIMECARD_LIB.TIMECARD(SCH_1):PAGE3
   R20    1      1 RESISTOR-G155-14701-01,4.7KOHMA    I14 @TIMECARD_LIB.TIMECARD(SCH_1):PAGE6
   R21    1      1 RESISTOR-G155-14701-01,4.7KOHMA    I16 @TIMECARD_LIB.TIMECARD(SCH_1):PAGE6
  R333    1      1 RESISTOR-G155-14701-01,4.7KOHMA    I31 @TIMECARD_LIB.TIMECARD(SCH_1):PAGE6
  R335    1      1 RESISTOR-G155-14701-01,4.7KOHMA    I35 @TIMECARD_LIB.TIMECARD(SCH_1):PAGE6
  R337    1      1 RESISTOR-G155-14701-01,4.7KOHMA    I36 @TIMECARD_LIB.TIMECARD(SCH_1):PAGE6
   C39    2      2 CAPACITOR-G105-0B104-EK,0.1UF,A    I37 @TIMECARD_LIB.TIMECARD(SCH_1):PAGE6
    U8    8    VCC LM75BDP_TSSOP8-G220-10215-01    I38 @TIMECARD_LIB.TIMECARD(SCH_1):PAGE6
  R340    1      1 RESISTOR-G155-14701-01,4.7KOHMA    I41 @TIMECARD_LIB.TIMECARD(SCH_1):PAGE6
   R64    1      1 RESISTOR-G155-14701-01,4.7KOHMA     I3 @TIMECARD_LIB.TIMECARD(SCH_1):PAGE7
   R65    1      1 RESISTOR-G155-14701-01,4.7KOHMA     I4 @TIMECARD_LIB.TIMECARD(SCH_1):PAGE7
   R68    1      1 RESISTOR-G155-14701-01,4.7KOHMA     I8 @TIMECARD_LIB.TIMECARD(SCH_1):PAGE7
   R74    1      1 RESISTOR-G155-14701-01,4.7KOHMA     I6 @TIMECARD_LIB.TIMECARD(SCH_1):PAGE9
   R75    1      1 RESISTOR-G155-14701-01,4.7KOHMA     I7 @TIMECARD_LIB.TIMECARD(SCH_1):PAGE9
   C17    1      1 CAPACITOR-G105-0B104-CK,0.1UF,A    I92 @TIMECARD_LIB.TIMECARD(SCH_1):PAGE3
    U2    8    VCC G220_10198_01-G223-10197-01   I100 @TIMECARD_LIB.TIMECARD(SCH_1):PAGE3
   R25    1      1 RESISTOR-G155-14701-01,4.7KOHMA   I103 @TIMECARD_LIB.TIMECARD(SCH_1):PAGE3
   R62    2      2 RESISTOR-G155-100R0-J0,0OHM,-    I55 @TIMECARD_LIB.TIMECARD(SCH_1):PAGE5
  R146    1      1 RESISTOR-G155-11002-01,10KOHM,A    I60 @TIMECARD_LIB.TIMECARD(SCH_1):PAGE5
  R194    1      1 RESISTOR-G155-14701-01,4.7KOHMA   I329 @TIMECARD_LIB.TIMECARD(SCH_1):PAGE127
  R193    1      1 RESISTOR-G155-14701-01,4.7KOHMA   I330 @TIMECARD_LIB.TIMECARD(SCH_1):PAGE127
  R210    2      2 RESISTOR-G155-13300-01,330OHM,A   I338 @TIMECARD_LIB.TIMECARD(SCH_1):PAGE127
  R209    2      2 RESISTOR-G155-14701-01,4.7KOHMA   I339 @TIMECARD_LIB.TIMECARD(SCH_1):PAGE127
  R219    1      1 RESISTOR-G155-11002-01,10KOHM,A   I392 @TIMECARD_LIB.TIMECARD(SCH_1):PAGE127
  R215    1      1 RESISTOR-G155-11002-01,10KOHM,A   I394 @TIMECARD_LIB.TIMECARD(SCH_1):PAGE127
  R213    1      1 RESISTOR-G155-11002-01,10KOHM,A   I396 @TIMECARD_LIB.TIMECARD(SCH_1):PAGE127
  R217    1      1 RESISTOR-G155-11000-01,100OHM,A   I402 @TIMECARD_LIB.TIMECARD(SCH_1):PAGE127
  R221    1      1 RESISTOR-G155-11000-01,100OHM,A   I403 @TIMECARD_LIB.TIMECARD(SCH_1):PAGE127
  R211    1      1 RESISTOR-G155-11000-01,100OHM,A   I404 @TIMECARD_LIB.TIMECARD(SCH_1):PAGE127
   U24  F12 VCCO_0_1 XC7A200T_2FBG484C_FBG484-G240-A   I138 @TIMECARD_LIB.TIMECARD(SCH_1):PAGE164
   U24  T12 VCCO_0_2 XC7A200T_2FBG484C_FBG484-G240-A   I138 @TIMECARD_LIB.TIMECARD(SCH_1):PAGE164
   U24 AA17 VCCO_13_1 XC7A200T_2FBG484C_FBG484-G240-A   I138 @TIMECARD_LIB.TIMECARD(SCH_1):PAGE164
   U24 AB14 VCCO_13_2 XC7A200T_2FBG484C_FBG484-G240-A   I138 @TIMECARD_LIB.TIMECARD(SCH_1):PAGE164
   U24  V16 VCCO_13_3 XC7A200T_2FBG484C_FBG484-G240-A   I138 @TIMECARD_LIB.TIMECARD(SCH_1):PAGE164
   U24  W13 VCCO_13_4 XC7A200T_2FBG484C_FBG484-G240-A   I138 @TIMECARD_LIB.TIMECARD(SCH_1):PAGE164
   U24  Y10 VCCO_13_5 XC7A200T_2FBG484C_FBG484-G240-A   I138 @TIMECARD_LIB.TIMECARD(SCH_1):PAGE164
   U24  M14 VCCO_14_1 XC7A200T_2FBG484C_FBG484-G240-A   I138 @TIMECARD_LIB.TIMECARD(SCH_1):PAGE164
   U24  P18 VCCO_14_2 XC7A200T_2FBG484C_FBG484-G240-A   I138 @TIMECARD_LIB.TIMECARD(SCH_1):PAGE164
   U24  R15 VCCO_14_3 XC7A200T_2FBG484C_FBG484-G240-A   I138 @TIMECARD_LIB.TIMECARD(SCH_1):PAGE164
   U24  T22 VCCO_14_4 XC7A200T_2FBG484C_FBG484-G240-A   I138 @TIMECARD_LIB.TIMECARD(SCH_1):PAGE164
   U24  U19 VCCO_14_5 XC7A200T_2FBG484C_FBG484-G240-A   I138 @TIMECARD_LIB.TIMECARD(SCH_1):PAGE164
   U24  Y20 VCCO_14_6 XC7A200T_2FBG484C_FBG484-G240-A   I138 @TIMECARD_LIB.TIMECARD(SCH_1):PAGE164
   U24  G19 VCCO_15_1 XC7A200T_2FBG484C_FBG484-G240-A   I138 @TIMECARD_LIB.TIMECARD(SCH_1):PAGE164
   U24  H16 VCCO_15_2 XC7A200T_2FBG484C_FBG484-G240-A   I138 @TIMECARD_LIB.TIMECARD(SCH_1):PAGE164
   U24  J13 VCCO_15_3 XC7A200T_2FBG484C_FBG484-G240-A   I138 @TIMECARD_LIB.TIMECARD(SCH_1):PAGE164
   U24  K20 VCCO_15_4 XC7A200T_2FBG484C_FBG484-G240-A   I138 @TIMECARD_LIB.TIMECARD(SCH_1):PAGE164
   U24  L17 VCCO_15_5 XC7A200T_2FBG484C_FBG484-G240-A   I138 @TIMECARD_LIB.TIMECARD(SCH_1):PAGE164
   U24  N21 VCCO_15_6 XC7A200T_2FBG484C_FBG484-G240-A   I138 @TIMECARD_LIB.TIMECARD(SCH_1):PAGE164
   U24  A17 VCCO_16_1 XC7A200T_2FBG484C_FBG484-G240-A   I138 @TIMECARD_LIB.TIMECARD(SCH_1):PAGE164
   U24  B14 VCCO_16_2 XC7A200T_2FBG484C_FBG484-G240-A   I138 @TIMECARD_LIB.TIMECARD(SCH_1):PAGE164
   U24  C21 VCCO_16_3 XC7A200T_2FBG484C_FBG484-G240-A   I138 @TIMECARD_LIB.TIMECARD(SCH_1):PAGE164
   U24  D18 VCCO_16_4 XC7A200T_2FBG484C_FBG484-G240-A   I138 @TIMECARD_LIB.TIMECARD(SCH_1):PAGE164
   U24  E15 VCCO_16_5 XC7A200T_2FBG484C_FBG484-G240-A   I138 @TIMECARD_LIB.TIMECARD(SCH_1):PAGE164
   U24  F22 VCCO_16_6 XC7A200T_2FBG484C_FBG484-G240-A   I138 @TIMECARD_LIB.TIMECARD(SCH_1):PAGE164
  C172    1      1 CAPACITOR-G109-0G107-BM,100UF,A   I174 @TIMECARD_LIB.TIMECARD(SCH_1):PAGE164
  C174    1      1 CAPACITOR-G109-0G107-BM,100UF,A   I178 @TIMECARD_LIB.TIMECARD(SCH_1):PAGE164
  C202    1      1 CAPACITOR-G105-0B104-CK,0.1UF,A   I205 @TIMECARD_LIB.TIMECARD(SCH_1):PAGE164
  C210    1      1 CAPACITOR-G105-0B104-CK,0.1UF,A   I206 @TIMECARD_LIB.TIMECARD(SCH_1):PAGE164
  C215    1      1 CAPACITOR-G105-0B104-CK,0.1UF,A   I207 @TIMECARD_LIB.TIMECARD(SCH_1):PAGE164
  C103    1      1 CAPACITOR-G105-0B104-CK,0.1UF,A   I208 @TIMECARD_LIB.TIMECARD(SCH_1):PAGE164
  C112    1      1 CAPACITOR-G105-0B104-CK,0.1UF,A   I209 @TIMECARD_LIB.TIMECARD(SCH_1):PAGE164
  C119    1      1 CAPACITOR-G105-0B104-CK,0.1UF,A   I210 @TIMECARD_LIB.TIMECARD(SCH_1):PAGE164
  C126    1      1 CAPACITOR-G105-0B104-CK,0.1UF,A   I211 @TIMECARD_LIB.TIMECARD(SCH_1):PAGE164
  C132    1      1 CAPACITOR-G105-0B104-CK,0.1UF,A   I212 @TIMECARD_LIB.TIMECARD(SCH_1):PAGE164
  C139    1      1 CAPACITOR-G105-0B104-CK,0.1UF,A   I213 @TIMECARD_LIB.TIMECARD(SCH_1):PAGE164
  C144    1      1 CAPACITOR-G105-0B104-CK,0.1UF,A   I214 @TIMECARD_LIB.TIMECARD(SCH_1):PAGE164
  C149    1      1 CAPACITOR-G105-0B104-CK,0.1UF,A   I215 @TIMECARD_LIB.TIMECARD(SCH_1):PAGE164
  C203    1      1 CAPACITOR-G105-0B104-CK,0.1UF,A   I216 @TIMECARD_LIB.TIMECARD(SCH_1):PAGE164
  C211    1      1 CAPACITOR-G105-0B104-CK,0.1UF,A   I217 @TIMECARD_LIB.TIMECARD(SCH_1):PAGE164
  C216    1      1 CAPACITOR-G105-0B104-CK,0.1UF,A   I218 @TIMECARD_LIB.TIMECARD(SCH_1):PAGE164
  C221    1      1 CAPACITOR-G105-0B104-CK,0.1UF,A   I219 @TIMECARD_LIB.TIMECARD(SCH_1):PAGE164
  C107    1      1 CAPACITOR-G105-0B104-CK,0.1UF,A   I220 @TIMECARD_LIB.TIMECARD(SCH_1):PAGE164
  C115    1      1 CAPACITOR-G105-0B104-CK,0.1UF,A   I221 @TIMECARD_LIB.TIMECARD(SCH_1):PAGE164
  C223    1      1 CAPACITOR-G105-0B104-CK,0.1UF,A   I222 @TIMECARD_LIB.TIMECARD(SCH_1):PAGE164
  C130    1      1 CAPACITOR-G105-0B104-CK,0.1UF,A   I223 @TIMECARD_LIB.TIMECARD(SCH_1):PAGE164
  C134    1      1 CAPACITOR-G105-0B104-CK,0.1UF,A   I224 @TIMECARD_LIB.TIMECARD(SCH_1):PAGE164
  C140    1      1 CAPACITOR-G105-0B104-CK,0.1UF,A   I225 @TIMECARD_LIB.TIMECARD(SCH_1):PAGE164
  C145    1      1 CAPACITOR-G105-0B104-CK,0.1UF,A   I226 @TIMECARD_LIB.TIMECARD(SCH_1):PAGE164
  C153    1      1 CAPACITOR-G105-0B104-CK,0.1UF,A   I227 @TIMECARD_LIB.TIMECARD(SCH_1):PAGE164
  C157    1      1 CAPACITOR-G105-0B104-CK,0.1UF,A   I228 @TIMECARD_LIB.TIMECARD(SCH_1):PAGE164
  C162    1      1 CAPACITOR-G105-0B104-CK,0.1UF,A   I229 @TIMECARD_LIB.TIMECARD(SCH_1):PAGE164
  C165    1      1 CAPACITOR-G105-0B104-CK,0.1UF,A   I230 @TIMECARD_LIB.TIMECARD(SCH_1):PAGE164
  C154    1      1 CAPACITOR-G105-0F475-BM,4.7UF,A   I270 @TIMECARD_LIB.TIMECARD(SCH_1):PAGE164
  C159    1      1 CAPACITOR-G105-0F475-BM,4.7UF,A   I271 @TIMECARD_LIB.TIMECARD(SCH_1):PAGE164
  C163    1      1 CAPACITOR-G105-0F475-BM,4.7UF,A   I272 @TIMECARD_LIB.TIMECARD(SCH_1):PAGE164
  C167    1      1 CAPACITOR-G105-0F475-BM,4.7UF,A   I273 @TIMECARD_LIB.TIMECARD(SCH_1):PAGE164
  C170    1      1 CAPACITOR-G105-0F475-BM,4.7UF,A   I282 @TIMECARD_LIB.TIMECARD(SCH_1):PAGE164
  C237    1      1 CAPACITOR-G105-0B104-CK,0.1UF,A    I64 @TIMECARD_LIB.TIMECARD(SCH_1):PAGE515
  R295    1      1 RESISTOR-G155-11002-01,10KOHM,A    I69 @TIMECARD_LIB.TIMECARD(SCH_1):PAGE515
  C240    1      1 CAPACITOR-G107-0F226-CM,22UF,2A    I71 @TIMECARD_LIB.TIMECARD(SCH_1):PAGE515
  C241    1      1 CAPACITOR-G107-0F226-CM,22UF,2A    I72 @TIMECARD_LIB.TIMECARD(SCH_1):PAGE515
  C243    1      1 CAPACITOR-G107-0F226-CM,22UF,2A    I74 @TIMECARD_LIB.TIMECARD(SCH_1):PAGE515
  C238    1      1 CAPACITOR-G107-0F226-CM,22UF,2A    I81 @TIMECARD_LIB.TIMECARD(SCH_1):PAGE515
   U22    7  BLEED NCP45560IMNTWG_H_DFN12-G222-10A    I82 @TIMECARD_LIB.TIMECARD(SCH_1):PAGE515
   U22    8 VOUT_1 NCP45560IMNTWG_H_DFN12-G222-10A    I82 @TIMECARD_LIB.TIMECARD(SCH_1):PAGE515
   U22    9 VOUT_2 NCP45560IMNTWG_H_DFN12-G222-10A    I82 @TIMECARD_LIB.TIMECARD(SCH_1):PAGE515
   U22   10 VOUT_3 NCP45560IMNTWG_H_DFN12-G222-10A    I82 @TIMECARD_LIB.TIMECARD(SCH_1):PAGE515
   U22   11 VOUT_4 NCP45560IMNTWG_H_DFN12-G222-10A    I82 @TIMECARD_LIB.TIMECARD(SCH_1):PAGE515
   U22   12 VOUT_5 NCP45560IMNTWG_H_DFN12-G222-10A    I82 @TIMECARD_LIB.TIMECARD(SCH_1):PAGE515
  R229    1      1 RESISTOR-G155-14701-01,4.7KOHMA   I139 @TIMECARD_LIB.TIMECARD(SCH_1):PAGE515
  R138    2      2 RESISTOR-G155-13300-01,330OHM,A    I63 @TIMECARD_LIB.TIMECARD(SCH_1):PAGE14
  R257    2      2 RESISTOR-G155-13300-01,330OHM,A    I67 @TIMECARD_LIB.TIMECARD(SCH_1):PAGE14
  R258    2      2 RESISTOR-G155-13300-01,330OHM,A    I68 @TIMECARD_LIB.TIMECARD(SCH_1):PAGE14
  R259    2      2 RESISTOR-G155-13300-01,330OHM,A    I69 @TIMECARD_LIB.TIMECARD(SCH_1):PAGE14
  R261    2      2 RESISTOR-G155-13300-01,330OHM,A    I70 @TIMECARD_LIB.TIMECARD(SCH_1):PAGE14
  R268    1      1 RESISTOR-G155-11003-01,100KOHMA    I38 @TIMECARD_LIB.TIMECARD(SCH_1):PAGE11
  R269    1      1 RESISTOR-G155-11003-01,100KOHMA    I40 @TIMECARD_LIB.TIMECARD(SCH_1):PAGE11
   C81    1      1 CAPACITOR-G105-0B104-CK,0.1UF,A    I43 @TIMECARD_LIB.TIMECARD(SCH_1):PAGE11
   L19    2      2 FERRITEBEAD-G191-10097-01,600OA    I22 @TIMECARD_LIB.TIMECARD(SCH_1):PAGE9
   C40    1      1 CAPACITOR-G105-0B104-EK,0.1UF,A    I18 @TIMECARD_LIB.TIMECARD(SCH_1):PAGE7
  C279    1      1 CAPACITOR-G105-0B104-EK,0.1UF,A    I21 @TIMECARD_LIB.TIMECARD(SCH_1):PAGE9
   L17    1      1 FERRITEBEAD-G191-10097-01,600OA    I21 @TIMECARD_LIB.TIMECARD(SCH_1):PAGE7
  R279    2      2 RESISTOR-G155-13300-01,330OHM,A    I72 @TIMECARD_LIB.TIMECARD(SCH_1):PAGE14
  R280    2      2 RESISTOR-G155-13300-01,330OHM,A    I74 @TIMECARD_LIB.TIMECARD(SCH_1):PAGE14
  TP58    1      1 TP_PIONT-TP010CT020B030_PTH-TPA  I1219 @TIMECARD_LIB.TIMECARD(SCH_1):PAGE16
  R296    1      1 RESISTOR-G155-14701-01,4.7KOHMA    I38 @TIMECARD_LIB.TIMECARD(SCH_1):PAGE7
  R300    1      1 RESISTOR-G155-14701-01,4.7KOHMA    I41 @TIMECARD_LIB.TIMECARD(SCH_1):PAGE7
  R304    1      1 RESISTOR-G155-14701-01,4.7KOHMA    I37 @TIMECARD_LIB.TIMECARD(SCH_1):PAGE9
  R289    1      1 RESISTOR-G155-14701-01,4.7KOHMA    I38 @TIMECARD_LIB.TIMECARD(SCH_1):PAGE9
  R291    1      1 RESISTOR-G155-14701-01,4.7KOHMA    I44 @TIMECARD_LIB.TIMECARD(SCH_1):PAGE9
  R290    1      1 RESISTOR-G155-14701-01,4.7KOHMA    I51 @TIMECARD_LIB.TIMECARD(SCH_1):PAGE9
  R306    1      1 RESISTOR-G155-14701-01,4.7KOHMA    I55 @TIMECARD_LIB.TIMECARD(SCH_1):PAGE9
  R341    1      1 RESISTOR-G155-14701-01,4.7KOHMA    I65 @TIMECARD_LIB.TIMECARD(SCH_1):PAGE9
  R342    1      1 RESISTOR-G155-14701-01,4.7KOHMA    I66 @TIMECARD_LIB.TIMECARD(SCH_1):PAGE9
  R365    1      1 RESISTOR-G155-14701-01,4.7KOHMA    I88 @TIMECARD_LIB.TIMECARD(SCH_1):PAGE12
  R147    1      1 RESISTOR-G155-11002-01,10KOHM,A    I80 @TIMECARD_LIB.TIMECARD(SCH_1):PAGE5
  R148    1      1 RESISTOR-G155-11002-01,10KOHM,A    I81 @TIMECARD_LIB.TIMECARD(SCH_1):PAGE5
  R149    1      1 RESISTOR-G155-14701-01,4.7KOHMA    I82 @TIMECARD_LIB.TIMECARD(SCH_1):PAGE5
  R150    1      1 RESISTOR-G155-14701-01,4.7KOHMA    I83 @TIMECARD_LIB.TIMECARD(SCH_1):PAGE5
  R151    1      1 RESISTOR-G155-14701-01,4.7KOHMA    I84 @TIMECARD_LIB.TIMECARD(SCH_1):PAGE5
    U7    4    VCC AT24MAC402_SOT23_5-A221-00002-A    I89 @TIMECARD_LIB.TIMECARD(SCH_1):PAGE5
  C225    1      1 CAPACITOR-G105-0B104-EK,0.1UF,A    I92 @TIMECARD_LIB.TIMECARD(SCH_1):PAGE5
 R1992    1      1 RESISTOR-G155-14701-01,4.7KOHMA    I94 @TIMECARD_LIB.TIMECARD(SCH_1):PAGE5
   R19    1      1 RESISTOR-G155-11002-01,10KOHM,A    I95 @TIMECARD_LIB.TIMECARD(SCH_1):PAGE5
 R1991    1      1 RESISTOR-G155-11002-01,10KOHM,A    I96 @TIMECARD_LIB.TIMECARD(SCH_1):PAGE5
  R422    1      1 RESISTOR-G155-14701-01,4.7KOHMA    I64 @TIMECARD_LIB.TIMECARD(SCH_1):PAGE6
   U36    8    VCC LM75BDP_TSSOP8-G220-10215-01    I66 @TIMECARD_LIB.TIMECARD(SCH_1):PAGE6
  C305    2      2 CAPACITOR-G105-0B104-EK,0.1UF,A    I67 @TIMECARD_LIB.TIMECARD(SCH_1):PAGE6
  R418    1      1 RESISTOR-G155-14701-01,4.7KOHMA    I69 @TIMECARD_LIB.TIMECARD(SCH_1):PAGE6
  R412    1      1 RESISTOR-G155-14701-01,4.7KOHMA    I70 @TIMECARD_LIB.TIMECARD(SCH_1):PAGE6
  R408    1      1 RESISTOR-G155-14701-01,4.7KOHMA    I71 @TIMECARD_LIB.TIMECARD(SCH_1):PAGE6
  R419    1      1 RESISTOR-G155-14701-01,4.7KOHMA    I84 @TIMECARD_LIB.TIMECARD(SCH_1):PAGE6
  R414    1      1 RESISTOR-G155-14701-01,4.7KOHMA    I85 @TIMECARD_LIB.TIMECARD(SCH_1):PAGE6
  R410    1      1 RESISTOR-G155-14701-01,4.7KOHMA    I86 @TIMECARD_LIB.TIMECARD(SCH_1):PAGE6
  R423    1      1 RESISTOR-G155-14701-01,4.7KOHMA    I88 @TIMECARD_LIB.TIMECARD(SCH_1):PAGE6
   U35    8    VCC LM75BDP_TSSOP8-G220-10215-01    I90 @TIMECARD_LIB.TIMECARD(SCH_1):PAGE6
  C306    2      2 CAPACITOR-G105-0B104-EK,0.1UF,A    I91 @TIMECARD_LIB.TIMECARD(SCH_1):PAGE6
  R405    1      1 RESISTOR-G155-11002-01,10KOHM,A   I432 @TIMECARD_LIB.TIMECARD(SCH_1):PAGE127
  R404    1      1 RESISTOR-G155-11002-01,10KOHM,A   I434 @TIMECARD_LIB.TIMECARD(SCH_1):PAGE127
  R403    1      1 RESISTOR-G155-11002-01,10KOHM,A   I435 @TIMECARD_LIB.TIMECARD(SCH_1):PAGE127
  R133    1      1 RESISTOR-G155-133R0-01,33OHM,1%   I446 @TIMECARD_LIB.TIMECARD(SCH_1):PAGE127
   U13    8    VCC 74HCT2G125DP_TSSOP8-G220-00055A   I204 @TIMECARD_LIB.TIMECARD(SCH_1):PAGE12
  R377    1      1 RESISTOR-G155-14701-01,4.7KOHMA   I206 @TIMECARD_LIB.TIMECARD(SCH_1):PAGE12
   C83    1      1 CAPACITOR-G105-0B104-CK,0.1UF,A   I207 @TIMECARD_LIB.TIMECARD(SCH_1):PAGE12
   U14    8    VCC 74HCT2G125DP_TSSOP8-G220-00055A   I226 @TIMECARD_LIB.TIMECARD(SCH_1):PAGE12
   C82    1      1 CAPACITOR-G105-0B104-CK,0.1UF,A   I231 @TIMECARD_LIB.TIMECARD(SCH_1):PAGE12
  R368    1      1 RESISTOR-G155-14701-01,4.7KOHMA   I233 @TIMECARD_LIB.TIMECARD(SCH_1):PAGE12
  R379    1      1 RESISTOR-G155-14701-01,4.7KOHMA   I234 @TIMECARD_LIB.TIMECARD(SCH_1):PAGE12
   U15    8    VCC 74HCT2G125DP_TSSOP8-G220-00055A   I255 @TIMECARD_LIB.TIMECARD(SCH_1):PAGE12
  R361    1      1 RESISTOR-G155-14701-01,4.7KOHMA   I261 @TIMECARD_LIB.TIMECARD(SCH_1):PAGE12
  R381    1      1 RESISTOR-G155-14701-01,4.7KOHMA   I262 @TIMECARD_LIB.TIMECARD(SCH_1):PAGE12
   C85    1      1 CAPACITOR-G105-0B104-CK,0.1UF,A   I272 @TIMECARD_LIB.TIMECARD(SCH_1):PAGE12
   U16    8    VCC 74HCT2G125DP_TSSOP8-G220-00055A   I273 @TIMECARD_LIB.TIMECARD(SCH_1):PAGE12
  R331    1      1 RESISTOR-G155-14701-01,4.7KOHMA   I280 @TIMECARD_LIB.TIMECARD(SCH_1):PAGE12
  R383    1      1 RESISTOR-G155-14701-01,4.7KOHMA   I281 @TIMECARD_LIB.TIMECARD(SCH_1):PAGE12
   C84    1      1 CAPACITOR-G105-0B104-CK,0.1UF,A   I289 @TIMECARD_LIB.TIMECARD(SCH_1):PAGE12
   U33    3    VCC IS32FL3207_QWLA3_TR_QFN29-A223A   I219 @TIMECARD_LIB.TIMECARD(SCH_1):PAGE14
  C315    1      1 CAPACITOR-G105-0B104-EK,0.1UF,A   I237 @TIMECARD_LIB.TIMECARD(SCH_1):PAGE14
  C314    1      1 CAPACITOR-G105-0C106-BM,10UF,2A   I238 @TIMECARD_LIB.TIMECARD(SCH_1):PAGE14
  R317    1      1 RESISTOR-G155-11002-01,10KOHM,A   I259 @TIMECARD_LIB.TIMECARD(SCH_1):PAGE14
  R318    1      1 RESISTOR-G155-11002-01,10KOHM,A   I261 @TIMECARD_LIB.TIMECARD(SCH_1):PAGE14
  R282    1      1 RESISTOR-G155-14701-01,4.7KOHMA    I69 @TIMECARD_LIB.TIMECARD(SCH_1):PAGE8
  R281    1      1 RESISTOR-G155-14701-01,4.7KOHMA    I70 @TIMECARD_LIB.TIMECARD(SCH_1):PAGE8
  R320    1      1 RESISTOR-G155-14701-01,4.7KOHMA   I264 @TIMECARD_LIB.TIMECARD(SCH_1):PAGE14
  DS14    2      2 LED_4P_V14-G170-10189-01   I265 @TIMECARD_LIB.TIMECARD(SCH_1):PAGE14
  DS15    2      2 LED_4P_V14-G170-10189-01   I266 @TIMECARD_LIB.TIMECARD(SCH_1):PAGE14
  DS16    2      2 LED_4P_V14-G170-10189-01   I267 @TIMECARD_LIB.TIMECARD(SCH_1):PAGE14
  DS17    2      2 LED_4P_V14-G170-10189-01   I268 @TIMECARD_LIB.TIMECARD(SCH_1):PAGE14
  DS18    2      2 LED_4P_V14-G170-10189-01   I269 @TIMECARD_LIB.TIMECARD(SCH_1):PAGE14
  R314    1      1 RESISTOR-G155-14701-01,4.7KOHMA    I71 @TIMECARD_LIB.TIMECARD(SCH_1):PAGE8
    U3    5    VCC 74LVC1G07_SC70_5-G220-10017-01   I135 @TIMECARD_LIB.TIMECARD(SCH_1):PAGE3
  R325    1      1 RESISTOR-G155-11002-01,10KOHM,A  I1602 @TIMECARD_LIB.TIMECARD(SCH_1):PAGE16
  R327    1      1 RESISTOR-G155-11002-01,10KOHM,A  I1603 @TIMECARD_LIB.TIMECARD(SCH_1):PAGE16
  R308    1      1 RESISTOR-G155-11002-01,10KOHM,A  I1604 @TIMECARD_LIB.TIMECARD(SCH_1):PAGE16
  R292    1      1 RESISTOR-G155-11002-01,10KOHM,A  I1605 @TIMECARD_LIB.TIMECARD(SCH_1):PAGE16
  R285    1      1 RESISTOR-G155-11002-01,10KOHM,A  I1606 @TIMECARD_LIB.TIMECARD(SCH_1):PAGE16
  R172    1      1 RESISTOR-G155-11002-01,10KOHM,A  I1607 @TIMECARD_LIB.TIMECARD(SCH_1):PAGE16
  R170    1      1 RESISTOR-G155-11002-01,10KOHM,A  I1608 @TIMECARD_LIB.TIMECARD(SCH_1):PAGE16
  R283    1      1 RESISTOR-G155-11002-01,10KOHM,A  I1609 @TIMECARD_LIB.TIMECARD(SCH_1):PAGE16
   U19    8    VCC 24LC16BT_I_ST_TSSOP8-G221-1017A   I148 @TIMECARD_LIB.TIMECARD(SCH_1):PAGE5
  R158    1      1 RESISTOR-G155-14701-01,4.7KOHMA   I153 @TIMECARD_LIB.TIMECARD(SCH_1):PAGE5
  R160    1      1 RESISTOR-G155-14701-01,4.7KOHMA   I160 @TIMECARD_LIB.TIMECARD(SCH_1):PAGE5
  R162    1      1 RESISTOR-G155-14701-01,4.7KOHMA   I161 @TIMECARD_LIB.TIMECARD(SCH_1):PAGE5
    R3    1      1 RESISTOR-G155-14701-01,4.7KOHMA   I169 @TIMECARD_LIB.TIMECARD(SCH_1):PAGE5
    C1    1      1 CAPACITOR-G105-0B104-EK,0.1UF,A   I171 @TIMECARD_LIB.TIMECARD(SCH_1):PAGE5
   L24    1      1 FERRITEBEAD-G191-10100-01,120OA   I108 @TIMECARD_LIB.TIMECARD(SCH_1):PAGE525
   L16    2      2 FERRITEBEAD-G191-10100-01,120OA    I55 @TIMECARD_LIB.TIMECARD(SCH_1):PAGE11
  R107    1      1 RESISTOR-G155-14701-01,4.7KOHMA    I83 @TIMECARD_LIB.TIMECARD(SCH_1):PAGE527
   C67    1      1 CAPACITOR-G105-0B104-CK,0.1UF,A   I103 @TIMECARD_LIB.TIMECARD(SCH_1):PAGE527
   U11   12    VCC TS3USB3031RMGR_WQFN12-G220-103A   I108 @TIMECARD_LIB.TIMECARD(SCH_1):PAGE527
   C68    1      1 CAPACITOR-G105-0B104-EK,0.1UF,A   I144 @TIMECARD_LIB.TIMECARD(SCH_1):PAGE527
   U10    5    VCC CL5003148A-G220-10019-01   I146 @TIMECARD_LIB.TIMECARD(SCH_1):PAGE527
  R287    2      2 RESISTOR-G155-14701-01,4.7KOHMA   I211 @TIMECARD_LIB.TIMECARD(SCH_1):PAGE527
  R265    1      1 RESISTOR-G155-11003-01,100KOHMA   I221 @TIMECARD_LIB.TIMECARD(SCH_1):PAGE527
  R264    1      1 RESISTOR-G155-11003-01,100KOHMA   I222 @TIMECARD_LIB.TIMECARD(SCH_1):PAGE527
  R457    1      1 RESISTOR-G155-14701-01,4.7KOHMA   I431 @TIMECARD_LIB.TIMECARD(SCH_1):PAGE524
  R450    2      2 RESISTOR-G155-14701-01,4.7KOHMA   I440 @TIMECARD_LIB.TIMECARD(SCH_1):PAGE524
  R452    2      2 RESISTOR-G155-14701-01,4.7KOHMA   I443 @TIMECARD_LIB.TIMECARD(SCH_1):PAGE524
  R482    1      1 RESISTOR-G155-14701-01,4.7KOHMA   I464 @TIMECARD_LIB.TIMECARD(SCH_1):PAGE524
  R474    1      1 RESISTOR-G155-11003-01,100KOHMA   I466 @TIMECARD_LIB.TIMECARD(SCH_1):PAGE524
  R475    1      1 RESISTOR-G155-11003-01,100KOHMA   I467 @TIMECARD_LIB.TIMECARD(SCH_1):PAGE524
  R476    1      1 RESISTOR-G155-11003-01,100KOHMA   I468 @TIMECARD_LIB.TIMECARD(SCH_1):PAGE524
  R477    1      1 RESISTOR-G155-11003-01,100KOHMA   I469 @TIMECARD_LIB.TIMECARD(SCH_1):PAGE524
   U30   16    V_P TS3A5018PWR_TSSOP16-G220-10324A   I473 @TIMECARD_LIB.TIMECARD(SCH_1):PAGE524
   C89    1      1 CAPACITOR-G105-0B104-EK,0.1UF,A   I474 @TIMECARD_LIB.TIMECARD(SCH_1):PAGE524
   C92    1      1 CAPACITOR-G105-0B104-EK,0.1UF,A   I476 @TIMECARD_LIB.TIMECARD(SCH_1):PAGE524
   U37   16    V_P TS3A5018PWR_TSSOP16-G220-10324A   I478 @TIMECARD_LIB.TIMECARD(SCH_1):PAGE524
   U38   16    V_P TS3A5018PWR_TSSOP16-G220-10324A   I481 @TIMECARD_LIB.TIMECARD(SCH_1):PAGE524
   C97    1      1 CAPACITOR-G105-0B104-EK,0.1UF,A   I482 @TIMECARD_LIB.TIMECARD(SCH_1):PAGE524
   U39    5    VCC NLASB3157DFT2G_SC88-G223-10187A   I485 @TIMECARD_LIB.TIMECARD(SCH_1):PAGE524
  C123    1      1 CAPACITOR-G105-0B104-EK,0.1UF,A   I486 @TIMECARD_LIB.TIMECARD(SCH_1):PAGE524
  C102    1      1 CAPACITOR-G105-0B104-EK,0.1UF,A   I490 @TIMECARD_LIB.TIMECARD(SCH_1):PAGE524
   U40    5    VCC NLASB3157DFT2G_SC88-G223-10187A   I491 @TIMECARD_LIB.TIMECARD(SCH_1):PAGE524
   U23    8    VCC MT25QL128ABA1ESE_SOP8-G221-102A   I456 @TIMECARD_LIB.TIMECARD(SCH_1):PAGE127
  R199    2      2 RESISTOR-G155-14701-01,4.7KOHMA   I462 @TIMECARD_LIB.TIMECARD(SCH_1):PAGE127
  R201    2      2 RESISTOR-G155-14701-01,4.7KOHMA   I463 @TIMECARD_LIB.TIMECARD(SCH_1):PAGE127
  R202    2      2 RESISTOR-G155-14701-01,4.7KOHMA   I464 @TIMECARD_LIB.TIMECARD(SCH_1):PAGE127
  R200    2      2 RESISTOR-G155-14701-01,4.7KOHMA   I465 @TIMECARD_LIB.TIMECARD(SCH_1):PAGE127
  R191    1      1 RESISTOR-G155-14701-01,4.7KOHMA   I471 @TIMECARD_LIB.TIMECARD(SCH_1):PAGE127
  C199    1      1 CAPACITOR-G105-0B104-CK,0.1UF,A   I472 @TIMECARD_LIB.TIMECARD(SCH_1):PAGE127
  C198    1      1 CAPACITOR-G105-0F475-BM,4.7UF,A   I473 @TIMECARD_LIB.TIMECARD(SCH_1):PAGE127
    J5   11     11 CONN_HDR_2X6_F_S_SMT-G200-1313A  I1614 @TIMECARD_LIB.TIMECARD(SCH_1):PAGE16
    J5   12     12 CONN_HDR_2X6_F_S_SMT-G200-1313A  I1614 @TIMECARD_LIB.TIMECARD(SCH_1):PAGE16
  R502    1      1 RESISTOR-G155-14701-01,4.7KOHMA   I247 @TIMECARD_LIB.TIMECARD(SCH_1):PAGE161
   U34    5  SENSE TPS3808G18DBVR_SOT23_6-G222-00A   I139 @TIMECARD_LIB.TIMECARD(SCH_1):PAGE3
   U34    6    VDD TPS3808G18DBVR_SOT23_6-G222-00A   I139 @TIMECARD_LIB.TIMECARD(SCH_1):PAGE3
   R63    1      1 RESISTOR-G155-14701-01,4.7KOHMA   I144 @TIMECARD_LIB.TIMECARD(SCH_1):PAGE3
  R167    1      1 RESISTOR-G155-11002-01,10KOHM,A   I148 @TIMECARD_LIB.TIMECARD(SCH_1):PAGE3
  R164    1      1 RESISTOR-G155-11003-01,100KOHMA   I151 @TIMECARD_LIB.TIMECARD(SCH_1):PAGE3
  R435    2      2 RESISTOR-G155-11003-01,100KOHMA   I251 @TIMECARD_LIB.TIMECARD(SCH_1):PAGE161
  R223    2      2 RESISTOR-G155-11001-01,1KOHM,1%   I252 @TIMECARD_LIB.TIMECARD(SCH_1):PAGE161

XP3R3V_FPGA_EN_R @TIMECARD_LIB.TIMECARD(SCH_1):XP3R3V_FPGA_EN_R
  R237    1      1 RESISTOR-G155-11002-01,10KOHM,A    I56 @TIMECARD_LIB.TIMECARD(SCH_1):PAGE515
  R260    2      2 RESISTOR-G155-11001-01,1KOHM,1%    I67 @TIMECARD_LIB.TIMECARD(SCH_1):PAGE515
   U22    2     EN NCP45560IMNTWG_H_DFN12-G222-10A    I82 @TIMECARD_LIB.TIMECARD(SCH_1):PAGE515
  C229    1      1 CAPACITOR-G105-0B104-CK,0.1UF,A    I87 @TIMECARD_LIB.TIMECARD(SCH_1):PAGE515
  R226    2      2 RESISTOR-G155-13300-01,330OHM,A   I122 @TIMECARD_LIB.TIMECARD(SCH_1):PAGE515
  C294    1      1 CAPACITOR-G105-0B224-DK,0.22UFA   I169 @TIMECARD_LIB.TIMECARD(SCH_1):PAGE515

XP3R3V_FPGA_SR @TIMECARD_LIB.TIMECARD(SCH_1):XP3R3V_FPGA_SR
  C236    1      1 CAPACITOR-G105-0B104-EK,0.1UF,A    I66 @TIMECARD_LIB.TIMECARD(SCH_1):PAGE515
   U22    5     SR NCP45560IMNTWG_H_DFN12-G222-10A    I82 @TIMECARD_LIB.TIMECARD(SCH_1):PAGE515

XP3R3V_FT4232 @TIMECARD_LIB.TIMECARD(SCH_1):XP3R3V_FT4232
   U18   56 VCCIO_1 FT4232HL_REEL_QFP64-G223-10282A    I64 @TIMECARD_LIB.TIMECARD(SCH_1):PAGE524
   U18   42 VCCIO_2 FT4232HL_REEL_QFP64-G223-10282A    I64 @TIMECARD_LIB.TIMECARD(SCH_1):PAGE524
   U18   31 VCCIO_3 FT4232HL_REEL_QFP64-G223-10282A    I64 @TIMECARD_LIB.TIMECARD(SCH_1):PAGE524
   U18   20 VCCIO_4 FT4232HL_REEL_QFP64-G223-10282A    I64 @TIMECARD_LIB.TIMECARD(SCH_1):PAGE524
   U18   50 VREGIN FT4232HL_REEL_QFP64-G223-10282A    I64 @TIMECARD_LIB.TIMECARD(SCH_1):PAGE524
   L22    1      1 FERRITEBEAD-G191-10097-01,600OA   I118 @TIMECARD_LIB.TIMECARD(SCH_1):PAGE524
    L4    1      1 FERRITEBEAD-G191-10097-01,600OA   I127 @TIMECARD_LIB.TIMECARD(SCH_1):PAGE524
   C91    1      1 CAPACITOR-G105-0F475-BM,4.7UF,A   I128 @TIMECARD_LIB.TIMECARD(SCH_1):PAGE524
  R480    2      2 RESISTOR-G155-11003-01,100KOHMA   I149 @TIMECARD_LIB.TIMECARD(SCH_1):PAGE524
  R481    2      2 RESISTOR-G155-11003-01,100KOHMA   I150 @TIMECARD_LIB.TIMECARD(SCH_1):PAGE524
  R349    2      2 RESISTOR-G155-11003-01,100KOHMA   I184 @TIMECARD_LIB.TIMECARD(SCH_1):PAGE524
  R478    2      2 RESISTOR-G155-11003-01,100KOHMA   I190 @TIMECARD_LIB.TIMECARD(SCH_1):PAGE524
  R479    2      2 RESISTOR-G155-11003-01,100KOHMA   I191 @TIMECARD_LIB.TIMECARD(SCH_1):PAGE524
  R466    2      2 RESISTOR-G155-11003-01,100KOHMA   I198 @TIMECARD_LIB.TIMECARD(SCH_1):PAGE524
   U31    6    ORG CAT93C46VI_GT3_SOIC8-G221-1007A   I200 @TIMECARD_LIB.TIMECARD(SCH_1):PAGE524
   U31    8    VCC CAT93C46VI_GT3_SOIC8-G221-1007A   I201 @TIMECARD_LIB.TIMECARD(SCH_1):PAGE524
  R447    1      1 RESISTOR-G155-11002-01,10KOHM,A   I206 @TIMECARD_LIB.TIMECARD(SCH_1):PAGE524
  R446    1      1 RESISTOR-G155-11002-01,10KOHM,A   I207 @TIMECARD_LIB.TIMECARD(SCH_1):PAGE524
  R444    1      1 RESISTOR-G155-11002-01,10KOHM,A   I208 @TIMECARD_LIB.TIMECARD(SCH_1):PAGE524
   U41    1 VOUT_1 ISL80101IRAJZ_DFN10-G222-10136A    I29 @TIMECARD_LIB.TIMECARD(SCH_1):PAGE525
   U41    2 VOUT_2 ISL80101IRAJZ_DFN10-G222-10136A    I29 @TIMECARD_LIB.TIMECARD(SCH_1):PAGE525
  C309    1      1 CAPACITOR-G105-0B104-EK,0.1UF,A    I56 @TIMECARD_LIB.TIMECARD(SCH_1):PAGE525
  C308    1      1 CAPACITOR-G107-0F106-EM,10UF,2A    I64 @TIMECARD_LIB.TIMECARD(SCH_1):PAGE525
  R490    1      1 RESISTOR-G155-11002-01,10KOHM,A    I66 @TIMECARD_LIB.TIMECARD(SCH_1):PAGE525
   TP3    1      1 TP_PIONT-TP010CT020B030_PTH-TPA  I1610 @TIMECARD_LIB.TIMECARD(SCH_1):PAGE16
  R169    2      2 RESISTOR-G155-13300-01,330OHM,A   I288 @TIMECARD_LIB.TIMECARD(SCH_1):PAGE14
   C95    1      1 CAPACITOR-G105-0B104-EK,0.1UF,A   I375 @TIMECARD_LIB.TIMECARD(SCH_1):PAGE524
   C88    1      1 CAPACITOR-G105-0B104-EK,0.1UF,A   I378 @TIMECARD_LIB.TIMECARD(SCH_1):PAGE524
   L24    2      2 FERRITEBEAD-G191-10100-01,120OA   I108 @TIMECARD_LIB.TIMECARD(SCH_1):PAGE525

XP3R3V_FT_PG @TIMECARD_LIB.TIMECARD(SCH_1):XP3R3V_FT_PG
   U41    4     PG ISL80101IRAJZ_DFN10-G222-10136A    I29 @TIMECARD_LIB.TIMECARD(SCH_1):PAGE525
  R456    1      1 RESISTOR-G155-11000-01,100OHM,A   I368 @TIMECARD_LIB.TIMECARD(SCH_1):PAGE524

XP3R3V_GPS @TIMECARD_LIB.TIMECARD(SCH_1):XP3R3V_GPS
  R115    1      1 RESISTOR-G155-14701-01,4.7KOHMA    I21 @TIMECARD_LIB.TIMECARD(SCH_1):PAGE11
   C79    1      1 CAPACITOR-G107-0F106-EM,10UF,2A    I24 @TIMECARD_LIB.TIMECARD(SCH_1):PAGE11
   C80    1      1 CAPACITOR-G105-0B104-CK,0.1UF,A    I26 @TIMECARD_LIB.TIMECARD(SCH_1):PAGE11
    P2    2      2 CONN_HDR_2X4_F_S_SMT-G200-1307A    I36 @TIMECARD_LIB.TIMECARD(SCH_1):PAGE11
  C273    1      1 CAPACITOR-G105-0B104-CK,0.1UF,A    I45 @TIMECARD_LIB.TIMECARD(SCH_1):PAGE11
   L16    1      1 FERRITEBEAD-G191-10100-01,120OA    I55 @TIMECARD_LIB.TIMECARD(SCH_1):PAGE11

XP3R3V_PCIE @TIMECARD_LIB.TIMECARD(SCH_1):XP3R3V_PCIE
   GF1   B8 P_3V3_1 CONN_64P_GF-S_M_EF64_PCIE_P039A    I61 @TIMECARD_LIB.TIMECARD(SCH_1):PAGE3
   GF1   A9 P_3V3_2 CONN_64P_GF-S_M_EF64_PCIE_P039A    I61 @TIMECARD_LIB.TIMECARD(SCH_1):PAGE3
   GF1  A10 P_3V3_3 CONN_64P_GF-S_M_EF64_PCIE_P039A    I61 @TIMECARD_LIB.TIMECARD(SCH_1):PAGE3
  C289    1      1 CAPACITOR-G105-0C106-BM,10UF,2A   I124 @TIMECARD_LIB.TIMECARD(SCH_1):PAGE3
  C290    1      1 CAPACITOR-G105-0B104-EK,0.1UF,A   I126 @TIMECARD_LIB.TIMECARD(SCH_1):PAGE3
  R118    2      2 RESISTOR-G155-13300-01,330OHM,A   I190 @TIMECARD_LIB.TIMECARD(SCH_1):PAGE14
   L21    1      1 FERRITEBEAD-G191-10101-01,26OHA   I132 @TIMECARD_LIB.TIMECARD(SCH_1):PAGE3

XP3R3V_PG @TIMECARD_LIB.TIMECARD(SCH_1):XP3R3V_PG
  R244    1      1 RESISTOR-G155-100R0-J0,0OHM,-   I109 @TIMECARD_LIB.TIMECARD(SCH_1):PAGE523
  R263    2      2 RESISTOR-G155-100R0-J0,0OHM,-    I47 @TIMECARD_LIB.TIMECARD(SCH_1):PAGE517
  TP38    1      1 TP_PIONT-TP010CT020B030_PTH-TPA  I1651 @TIMECARD_LIB.TIMECARD(SCH_1):PAGE16

XP3R3V_RT @TIMECARD_LIB.TIMECARD(SCH_1):XP3R3V_RT
   R35    1      1 RESISTOR-G155-11003-01,100KOHMA    I10 @TIMECARD_LIB.TIMECARD(SCH_1):PAGE517
    U6   13 RT/CLK TPS54824RNVR_VQFN18-G220-10657A    I42 @TIMECARD_LIB.TIMECARD(SCH_1):PAGE517

XP3R3V_SS @TIMECARD_LIB.TIMECARD(SCH_1):XP3R3V_SS
   C49    1      1 CAPACITOR-G105-0B223-EK,0.022UA     I9 @TIMECARD_LIB.TIMECARD(SCH_1):PAGE517
    U6   16 SS/TRK TPS54824RNVR_VQFN18-G220-10657A    I42 @TIMECARD_LIB.TIMECARD(SCH_1):PAGE517

XP3R3V_SW @TIMECARD_LIB.TIMECARD(SCH_1):XP3R3V_SW
   C56    2      2 CAPACITOR-G105-0B104-EK,0.1UF,A    I27 @TIMECARD_LIB.TIMECARD(SCH_1):PAGE517
    L2    1      1 INDUCTOR_2-G190-10424-01,4.7UHA    I28 @TIMECARD_LIB.TIMECARD(SCH_1):PAGE517
   C57    1      1 CAPACITOR-G105-0A102-FJ,1000PFA    I29 @TIMECARD_LIB.TIMECARD(SCH_1):PAGE517
    U6    6   SW_1 TPS54824RNVR_VQFN18-G220-10657A    I42 @TIMECARD_LIB.TIMECARD(SCH_1):PAGE517
    U6    7   SW_2 TPS54824RNVR_VQFN18-G220-10657A    I42 @TIMECARD_LIB.TIMECARD(SCH_1):PAGE517

XP3R3V_VPHY @TIMECARD_LIB.TIMECARD(SCH_1):XP3R3V_VPHY
   U18    4   VPHY FT4232HL_REEL_QFP64-G223-10282A    I64 @TIMECARD_LIB.TIMECARD(SCH_1):PAGE524
   L22    2      2 FERRITEBEAD-G191-10097-01,600OA   I118 @TIMECARD_LIB.TIMECARD(SCH_1):PAGE524
  C101    1      1 CAPACITOR-G105-0B104-EK,0.1UF,A   I373 @TIMECARD_LIB.TIMECARD(SCH_1):PAGE524
   C99    1      1 CAPACITOR-G105-0F475-BM,4.7UF,A   I380 @TIMECARD_LIB.TIMECARD(SCH_1):PAGE524

XP3R3V_VPLL @TIMECARD_LIB.TIMECARD(SCH_1):XP3R3V_VPLL
   U18    9   VPLL FT4232HL_REEL_QFP64-G223-10282A    I64 @TIMECARD_LIB.TIMECARD(SCH_1):PAGE524
    L4    2      2 FERRITEBEAD-G191-10097-01,600OA   I127 @TIMECARD_LIB.TIMECARD(SCH_1):PAGE524
  C100    1      1 CAPACITOR-G105-0B104-EK,0.1UF,A   I374 @TIMECARD_LIB.TIMECARD(SCH_1):PAGE524
   C98    1      1 CAPACITOR-G105-0F475-BM,4.7UF,A   I379 @TIMECARD_LIB.TIMECARD(SCH_1):PAGE524

XP5R0V @TIMECARD_LIB.TIMECARD(SCH_1):XP5R0V
    R6    1      1 RESISTOR-G155-120R0-01,20OHM,1%    I31 @TIMECARD_LIB.TIMECARD(SCH_1):PAGE516
   C12    1      1 CAPACITOR-G105-0B104-CK,0.1UF,A    I32 @TIMECARD_LIB.TIMECARD(SCH_1):PAGE516
   C13    1      1 CAPACITOR-G107-0F226-CM,22UF,2A    I33 @TIMECARD_LIB.TIMECARD(SCH_1):PAGE516
   C14    1      1 CAPACITOR-G107-0F226-CM,22UF,2A    I35 @TIMECARD_LIB.TIMECARD(SCH_1):PAGE516
    L1    2      2 INDUCTOR_2-G190-10424-01,4.7UHA    I36 @TIMECARD_LIB.TIMECARD(SCH_1):PAGE516
   C15    1      1 CAPACITOR-G107-0F226-CM,22UF,2A    I40 @TIMECARD_LIB.TIMECARD(SCH_1):PAGE516
  R180    2      2 RESISTOR-G155-11001-01,1KOHM,1%    I44 @TIMECARD_LIB.TIMECARD(SCH_1):PAGE14
  C272    1      1 CAPACITOR-G105-0B104-EK,0.1UF,A    I44 @TIMECARD_LIB.TIMECARD(SCH_1):PAGE11
  TP60    1      1 TP_PIONT-TP010CT020B030_PTH-TPA  I1233 @TIMECARD_LIB.TIMECARD(SCH_1):PAGE16
   CR1    A      A DIODE_2F-G122-10186-01   I102 @TIMECARD_LIB.TIMECARD(SCH_1):PAGE525
   L15    1      1 FERRITEBEAD-G191-10100-01,120OA    I56 @TIMECARD_LIB.TIMECARD(SCH_1):PAGE11
    L3    2      2 FERRITEBEAD-G191-10101-01,26OHA    I91 @TIMECARD_LIB.TIMECARD(SCH_1):PAGE527
   C62    1      1 CAPACITOR-G105-0B104-EK,0.1UF,A    I93 @TIMECARD_LIB.TIMECARD(SCH_1):PAGE527

XP5R0V_AGND @TIMECARD_LIB.TIMECARD(SCH_1):XP5R0V_AGND
   C31    2      2 CAPACITOR-G105-0B223-EK,0.022UA    I11 @TIMECARD_LIB.TIMECARD(SCH_1):PAGE516
   R29    2      2 RESISTOR-G155-11003-01,100KOHMA    I12 @TIMECARD_LIB.TIMECARD(SCH_1):PAGE516
   C42    2      2 CAPACITOR-G105-0B222-FK,2200PFA    I13 @TIMECARD_LIB.TIMECARD(SCH_1):PAGE516
   C43    2      2 CAPACITOR-G104-0A180-FJ,18PF,5%    I15 @TIMECARD_LIB.TIMECARD(SCH_1):PAGE516
   SP1    2      2 SOLDER_PREFORM-G380-10015-01    I24 @TIMECARD_LIB.TIMECARD(SCH_1):PAGE516
   R32    2      2 RESISTOR-G155-03241-01,3.24KOHA    I25 @TIMECARD_LIB.TIMECARD(SCH_1):PAGE516
   R50    1      1 RESISTOR-G156-100R0-J0,0OHM,-    I28 @TIMECARD_LIB.TIMECARD(SCH_1):PAGE516
    U5   12   AGND TPS54824RNVR_VQFN18-G220-10657A    I42 @TIMECARD_LIB.TIMECARD(SCH_1):PAGE516

XP5R0V_BT @TIMECARD_LIB.TIMECARD(SCH_1):XP5R0V_BT
   R31    1      1 RESISTOR-G155-100R0-J0,0OHM,-    I26 @TIMECARD_LIB.TIMECARD(SCH_1):PAGE516
    U5    1   BOOT TPS54824RNVR_VQFN18-G220-10657A    I42 @TIMECARD_LIB.TIMECARD(SCH_1):PAGE516

XP5R0V_COMP @TIMECARD_LIB.TIMECARD(SCH_1):XP5R0V_COMP
   R30    1      1 RESISTOR-G155-12201-01,2.2KOHMA    I14 @TIMECARD_LIB.TIMECARD(SCH_1):PAGE516
   C43    1      1 CAPACITOR-G104-0A180-FJ,18PF,5%    I15 @TIMECARD_LIB.TIMECARD(SCH_1):PAGE516
    U5   15   COMP TPS54824RNVR_VQFN18-G220-10657A    I42 @TIMECARD_LIB.TIMECARD(SCH_1):PAGE516

XP5R0V_FB_R_TO_AGND @TIMECARD_LIB.TIMECARD(SCH_1):XP5R0V_FB_R_TO_AGND
   R32    1      1 RESISTOR-G155-03241-01,3.24KOHA    I25 @TIMECARD_LIB.TIMECARD(SCH_1):PAGE516
   R50    2      2 RESISTOR-G156-100R0-J0,0OHM,-    I28 @TIMECARD_LIB.TIMECARD(SCH_1):PAGE516
   C11    2      2 CAPACITOR-G104-0B101-FK,100PF,A    I29 @TIMECARD_LIB.TIMECARD(SCH_1):PAGE516
   R34    2      2 RESISTOR-G155-02402-01,24KOHM,A    I30 @TIMECARD_LIB.TIMECARD(SCH_1):PAGE516
    U5   14     FB TPS54824RNVR_VQFN18-G220-10657A    I42 @TIMECARD_LIB.TIMECARD(SCH_1):PAGE516

XP5R0V_FT4232 @TIMECARD_LIB.TIMECARD(SCH_1):XP5R0V_FT4232
   U17    5      5 CL1001485A-G122-00019-01     I3 @TIMECARD_LIB.TIMECARD(SCH_1):PAGE524
   R18    1      1 RESISTOR-G155-14701-01,4.7KOHMA    I27 @TIMECARD_LIB.TIMECARD(SCH_1):PAGE524
   CR2    A      A DIODE_2F-G122-10186-01   I104 @TIMECARD_LIB.TIMECARD(SCH_1):PAGE525
   TP4    1      1 TP_PIONT-TP010CT020B030_PTH-TPA  I1612 @TIMECARD_LIB.TIMECARD(SCH_1):PAGE16
   C94    1      1 CAPACITOR-G105-0B104-EK,0.1UF,A   I377 @TIMECARD_LIB.TIMECARD(SCH_1):PAGE524
   J13   A4 VBUS_1 CONN_USB_14P_GH4_F_RA_TH-G200-A   I495 @TIMECARD_LIB.TIMECARD(SCH_1):PAGE524
   J13   A9 VBUS_2 CONN_USB_14P_GH4_F_RA_TH-G200-A   I495 @TIMECARD_LIB.TIMECARD(SCH_1):PAGE524
   J13   B4 VBUS_3 CONN_USB_14P_GH4_F_RA_TH-G200-A   I495 @TIMECARD_LIB.TIMECARD(SCH_1):PAGE524
   J13   B9 VBUS_4 CONN_USB_14P_GH4_F_RA_TH-G200-A   I495 @TIMECARD_LIB.TIMECARD(SCH_1):PAGE524

XP5R0V_MAC @TIMECARD_LIB.TIMECARD(SCH_1):XP5R0V_MAC
   C58    1      1 CAPACITOR-G107-0F106-EM,10UF,2A    I47 @TIMECARD_LIB.TIMECARD(SCH_1):PAGE527
   C59    1      1 CAPACITOR-G105-0B104-EK,0.1UF,A    I48 @TIMECARD_LIB.TIMECARD(SCH_1):PAGE527
   C60    1      1 CAPACITOR-G105-0B104-EK,0.1UF,A    I66 @TIMECARD_LIB.TIMECARD(SCH_1):PAGE527
   C70    1      1 CAPACITOR-G105-0B104-EK,0.1UF,A    I77 @TIMECARD_LIB.TIMECARD(SCH_1):PAGE527
   U12    5     IN TPS2051BDBVT_SOT23_5-G220-1033A    I79 @TIMECARD_LIB.TIMECARD(SCH_1):PAGE527
    L3    1      1 FERRITEBEAD-G191-10101-01,26OHA    I91 @TIMECARD_LIB.TIMECARD(SCH_1):PAGE527
  C282    1      1 CAPACITOR-G107-0F106-EM,10UF,2A   I208 @TIMECARD_LIB.TIMECARD(SCH_1):PAGE527
  C283    1      1 CAPACITOR-G107-0F106-EM,10UF,2A   I209 @TIMECARD_LIB.TIMECARD(SCH_1):PAGE527
MAC_PIN5    1      1 NUT-A200-00029-FB   I230 @TIMECARD_LIB.TIMECARD(SCH_1):PAGE527
    Q3    2      S POWERMOS_3P_PCH-G121-10216-01   I231 @TIMECARD_LIB.TIMECARD(SCH_1):PAGE527
   R44    1      1 RESISTOR-G155-14701-01,4.7KOHMA   I233 @TIMECARD_LIB.TIMECARD(SCH_1):PAGE527
  R357    1      1 RESISTOR-G157-100R0-J0,0OHM,-   I245 @TIMECARD_LIB.TIMECARD(SCH_1):PAGE527

XP5R0V_MAC_USB @TIMECARD_LIB.TIMECARD(SCH_1):XP5R0V_MAC_USB
   C64    1      1 CAPACITOR-G107-0F106-EM,10UF,2A    I51 @TIMECARD_LIB.TIMECARD(SCH_1):PAGE527
   C65    1      1 CAPACITOR-G105-0B104-EK,0.1UF,A    I56 @TIMECARD_LIB.TIMECARD(SCH_1):PAGE527
   C66    1      1 CAPACITOR-G105-0B104-EK,0.1UF,A    I57 @TIMECARD_LIB.TIMECARD(SCH_1):PAGE527
   U12    1    OUT TPS2051BDBVT_SOT23_5-G220-1033A    I79 @TIMECARD_LIB.TIMECARD(SCH_1):PAGE527
   C71    1      1 CAPACITOR-G105-0B104-EK,0.1UF,A    I85 @TIMECARD_LIB.TIMECARD(SCH_1):PAGE527
    P1    6      6 CONN_HDR_2X10_M_S_SMT-G200-130A   I193 @TIMECARD_LIB.TIMECARD(SCH_1):PAGE527
   FU3    2      2 FUSE-G280-10049-01,1A   I244 @TIMECARD_LIB.TIMECARD(SCH_1):PAGE527

XP5R0V_PG @TIMECARD_LIB.TIMECARD(SCH_1):XP5R0V_PG
   R47    2      2 RESISTOR-G155-11002-01,10KOHM,A     I1 @TIMECARD_LIB.TIMECARD(SCH_1):PAGE516
   C75    2      2 CAPACITOR-G104-0B103-EK,0.01UFA     I7 @TIMECARD_LIB.TIMECARD(SCH_1):PAGE516
    U5   18  PGOOD TPS54824RNVR_VQFN18-G220-10657A    I42 @TIMECARD_LIB.TIMECARD(SCH_1):PAGE516
  R294    1      1 RESISTOR-G155-133R0-01,33OHM,1%    I45 @TIMECARD_LIB.TIMECARD(SCH_1):PAGE516

XP5R0V_RT @TIMECARD_LIB.TIMECARD(SCH_1):XP5R0V_RT
   R29    1      1 RESISTOR-G155-11003-01,100KOHMA    I12 @TIMECARD_LIB.TIMECARD(SCH_1):PAGE516
    U5   13 RT/CLK TPS54824RNVR_VQFN18-G220-10657A    I42 @TIMECARD_LIB.TIMECARD(SCH_1):PAGE516

XP5R0V_SS @TIMECARD_LIB.TIMECARD(SCH_1):XP5R0V_SS
   C31    1      1 CAPACITOR-G105-0B223-EK,0.022UA    I11 @TIMECARD_LIB.TIMECARD(SCH_1):PAGE516
    U5   16 SS/TRK TPS54824RNVR_VQFN18-G220-10657A    I42 @TIMECARD_LIB.TIMECARD(SCH_1):PAGE516

XP5R0V_SW @TIMECARD_LIB.TIMECARD(SCH_1):XP5R0V_SW
   C44    2      2 CAPACITOR-G105-0B104-EK,0.1UF,A    I27 @TIMECARD_LIB.TIMECARD(SCH_1):PAGE516
    L1    1      1 INDUCTOR_2-G190-10424-01,4.7UHA    I36 @TIMECARD_LIB.TIMECARD(SCH_1):PAGE516
   C45    1      1 CAPACITOR-G105-0A102-FJ,1000PFA    I37 @TIMECARD_LIB.TIMECARD(SCH_1):PAGE516
    U5    6   SW_1 TPS54824RNVR_VQFN18-G220-10657A    I42 @TIMECARD_LIB.TIMECARD(SCH_1):PAGE516
    U5    7   SW_2 TPS54824RNVR_VQFN18-G220-10657A    I42 @TIMECARD_LIB.TIMECARD(SCH_1):PAGE516

XP5R0V_USB_CONN @TIMECARD_LIB.TIMECARD(SCH_1):XP5R0V_USB_CONN
   J11    1      1 CONN_USB_1X5_G2_GH4_F_RA_SMT-GA     I2 @TIMECARD_LIB.TIMECARD(SCH_1):PAGE527
    U9    5      5 CL1001485A-G122-00019-01     I4 @TIMECARD_LIB.TIMECARD(SCH_1):PAGE527
   C63    1      1 CAPACITOR-G105-0B104-EK,0.1UF,A    I15 @TIMECARD_LIB.TIMECARD(SCH_1):PAGE527
   C61    1      1 CAPACITOR-G107-0F106-EM,10UF,2A    I16 @TIMECARD_LIB.TIMECARD(SCH_1):PAGE527
  R101    1      1 RESISTOR-G155-11001-01,1KOHM,1%   I200 @TIMECARD_LIB.TIMECARD(SCH_1):PAGE527

XP5R0V_USB_CONN_DET @TIMECARD_LIB.TIMECARD(SCH_1):XP5R0V_USB_CONN_DET
   U11    1   SEL0 TS3USB3031RMGR_WQFN12-G220-103A   I108 @TIMECARD_LIB.TIMECARD(SCH_1):PAGE527
   U10    2      B CL5003148A-G220-10019-01   I147 @TIMECARD_LIB.TIMECARD(SCH_1):PAGE527
  R101    2      2 RESISTOR-G155-11001-01,1KOHM,1%   I200 @TIMECARD_LIB.TIMECARD(SCH_1):PAGE527
  R102    1      1 RESISTOR-G155-11001-01,1KOHM,1%   I201 @TIMECARD_LIB.TIMECARD(SCH_1):PAGE527
  R266    2      2 RESISTOR-G155-133R0-01,33OHM,1%   I204 @TIMECARD_LIB.TIMECARD(SCH_1):PAGE527

XP5R0V_VCC_ANT @TIMECARD_LIB.TIMECARD(SCH_1):XP5R0V_VCC_ANT
   C72    1      1 CAPACITOR-G107-0F106-EM,10UF,2A    I12 @TIMECARD_LIB.TIMECARD(SCH_1):PAGE11
   C73    1      1 CAPACITOR-G105-0B104-EK,0.1UF,A    I13 @TIMECARD_LIB.TIMECARD(SCH_1):PAGE11
   C78    1      1 CAPACITOR-G105-0B104-EK,0.1UF,A    I15 @TIMECARD_LIB.TIMECARD(SCH_1):PAGE11
    P2    1      1 CONN_HDR_2X4_F_S_SMT-G200-1307A    I36 @TIMECARD_LIB.TIMECARD(SCH_1):PAGE11
   L15    2      2 FERRITEBEAD-G191-10100-01,120OA    I56 @TIMECARD_LIB.TIMECARD(SCH_1):PAGE11

END GLOBAL SIGNAL CROSS REFERENCE
GLOBAL PART CROSS REFERENCE - 05-Sep-2022 AT 15:23:30

  C1 CAPACITOR-G105-0B104-EK,0.1UF,A
     1 XP3R3V_FPGA @TIMECARD_LIB.TIMECARD(SCH_1):XP3R3V_FPGA   I171 @TIMECARD_LIB.TIMECARD(SCH_1):PAGE5
     2     SG @TIMECARD_LIB.TIMECARD(SCH_1):SG   I171 @TIMECARD_LIB.TIMECARD(SCH_1):PAGE5

  C2 CAPACITOR-G105-0B104-EK,0.1UF,A
     1 XP12R0V_IN @TIMECARD_LIB.TIMECARD(SCH_1):XP12R0V_IN   I160 @TIMECARD_LIB.TIMECARD(SCH_1):PAGE15
     2     SG @TIMECARD_LIB.TIMECARD(SCH_1):SG   I160 @TIMECARD_LIB.TIMECARD(SCH_1):PAGE15

  C3 CAPACITOR-G105-0B104-EK,0.1UF,A
     1 XP12R0V_A_EN @TIMECARD_LIB.TIMECARD(SCH_1):XP12R0V_A_EN   I156 @TIMECARD_LIB.TIMECARD(SCH_1):PAGE15
     2     SG @TIMECARD_LIB.TIMECARD(SCH_1):SG   I156 @TIMECARD_LIB.TIMECARD(SCH_1):PAGE15

  C4 CAPACITOR-G104-0F224-BK,0.22UFA
     1     SG @TIMECARD_LIB.TIMECARD(SCH_1):SG   I172 @TIMECARD_LIB.TIMECARD(SCH_1):PAGE15
     2 XP12R0V_A_TIMER @TIMECARD_LIB.TIMECARD(SCH_1):XP12R0V_A_TIMER   I172 @TIMECARD_LIB.TIMECARD(SCH_1):PAGE15

  C5 CAPACITOR-G105-0B104-EK,0.1UF,A
     1 XP12R0V_A_SS @TIMECARD_LIB.TIMECARD(SCH_1):XP12R0V_A_SS   I211 @TIMECARD_LIB.TIMECARD(SCH_1):PAGE15
     2     SG @TIMECARD_LIB.TIMECARD(SCH_1):SG   I211 @TIMECARD_LIB.TIMECARD(SCH_1):PAGE15

  C6 CAPACITOR-G107-0F106-EM,10UF,2A
     1 XP12R0V_A_AVIN @TIMECARD_LIB.TIMECARD(SCH_1):XP12R0V_A_AVIN   I196 @TIMECARD_LIB.TIMECARD(SCH_1):PAGE15
     2     SG @TIMECARD_LIB.TIMECARD(SCH_1):SG   I196 @TIMECARD_LIB.TIMECARD(SCH_1):PAGE15

  C7 CAPACITOR-G105-0B104-EK,0.1UF,A
     1 XP12R0V_A_IMON @TIMECARD_LIB.TIMECARD(SCH_1):XP12R0V_A_IMON   I185 @TIMECARD_LIB.TIMECARD(SCH_1):PAGE15
     2     SG @TIMECARD_LIB.TIMECARD(SCH_1):SG   I185 @TIMECARD_LIB.TIMECARD(SCH_1):PAGE15

  C8 CAPACITOR-G104-0B103-EK,0.01UFA
     1 XP12R0V_A_OV @TIMECARD_LIB.TIMECARD(SCH_1):XP12R0V_A_OV   I201 @TIMECARD_LIB.TIMECARD(SCH_1):PAGE15
     2     SG @TIMECARD_LIB.TIMECARD(SCH_1):SG   I201 @TIMECARD_LIB.TIMECARD(SCH_1):PAGE15

  C9 CAPACITOR-G107-0F106-EM,10UF,2A
     1 XP12R0V @TIMECARD_LIB.TIMECARD(SCH_1):XP12R0V   I206 @TIMECARD_LIB.TIMECARD(SCH_1):PAGE15
     2     SG @TIMECARD_LIB.TIMECARD(SCH_1):SG   I206 @TIMECARD_LIB.TIMECARD(SCH_1):PAGE15

 C10 CAPACITOR-G107-0F106-EM,10UF,2A
     1 XP12R0V @TIMECARD_LIB.TIMECARD(SCH_1):XP12R0V   I207 @TIMECARD_LIB.TIMECARD(SCH_1):PAGE15
     2     SG @TIMECARD_LIB.TIMECARD(SCH_1):SG   I207 @TIMECARD_LIB.TIMECARD(SCH_1):PAGE15

 C11 CAPACITOR-G104-0B101-FK,100PF,A
     1 UNNAMED_516_CAPACITOR_I29_1 @TIMECARD_LIB.TIMECARD(SCH_1):UNNAMED_516_CAPACITOR_I29_1    I29 @TIMECARD_LIB.TIMECARD(SCH_1):PAGE516
     2 XP5R0V_FB_R_TO_AGND @TIMECARD_LIB.TIMECARD(SCH_1):XP5R0V_FB_R_TO_AGND    I29 @TIMECARD_LIB.TIMECARD(SCH_1):PAGE516

 C12 CAPACITOR-G105-0B104-CK,0.1UF,A
     1 XP5R0V @TIMECARD_LIB.TIMECARD(SCH_1):XP5R0V    I32 @TIMECARD_LIB.TIMECARD(SCH_1):PAGE516
     2     SG @TIMECARD_LIB.TIMECARD(SCH_1):SG    I32 @TIMECARD_LIB.TIMECARD(SCH_1):PAGE516

 C13 CAPACITOR-G107-0F226-CM,22UF,2A
     1 XP5R0V @TIMECARD_LIB.TIMECARD(SCH_1):XP5R0V    I33 @TIMECARD_LIB.TIMECARD(SCH_1):PAGE516
     2     SG @TIMECARD_LIB.TIMECARD(SCH_1):SG    I33 @TIMECARD_LIB.TIMECARD(SCH_1):PAGE516

 C14 CAPACITOR-G107-0F226-CM,22UF,2A
     1 XP5R0V @TIMECARD_LIB.TIMECARD(SCH_1):XP5R0V    I35 @TIMECARD_LIB.TIMECARD(SCH_1):PAGE516
     2     SG @TIMECARD_LIB.TIMECARD(SCH_1):SG    I35 @TIMECARD_LIB.TIMECARD(SCH_1):PAGE516

 C15 CAPACITOR-G107-0F226-CM,22UF,2A
     1 XP5R0V @TIMECARD_LIB.TIMECARD(SCH_1):XP5R0V    I40 @TIMECARD_LIB.TIMECARD(SCH_1):PAGE516
     2     SG @TIMECARD_LIB.TIMECARD(SCH_1):SG    I40 @TIMECARD_LIB.TIMECARD(SCH_1):PAGE516

 C16 CAPACITOR-G104-0B101-FK,100PF,A
     1 UNNAMED_517_CAPACITOR_I30_1 @TIMECARD_LIB.TIMECARD(SCH_1):UNNAMED_517_CAPACITOR_I30_1    I30 @TIMECARD_LIB.TIMECARD(SCH_1):PAGE517
     2 XP3R3V_FB_R_TO_AGND @TIMECARD_LIB.TIMECARD(SCH_1):XP3R3V_FB_R_TO_AGND    I30 @TIMECARD_LIB.TIMECARD(SCH_1):PAGE517

 C17 CAPACITOR-G105-0B104-CK,0.1UF,A
     1 XP3R3V_FPGA @TIMECARD_LIB.TIMECARD(SCH_1):XP3R3V_FPGA    I92 @TIMECARD_LIB.TIMECARD(SCH_1):PAGE3
     2     SG @TIMECARD_LIB.TIMECARD(SCH_1):SG    I92 @TIMECARD_LIB.TIMECARD(SCH_1):PAGE3

 C18 CAPACITOR-G105-0B104-CK,0.1UF,A
     1 XP3R3V @TIMECARD_LIB.TIMECARD(SCH_1):XP3R3V    I36 @TIMECARD_LIB.TIMECARD(SCH_1):PAGE517
     2     SG @TIMECARD_LIB.TIMECARD(SCH_1):SG    I36 @TIMECARD_LIB.TIMECARD(SCH_1):PAGE517

 C19 CAPACITOR-G105-0B104-CK,0.1UF,A
     1 C_PCIEREFCLKP @TIMECARD_LIB.TIMECARD(SCH_1):C_PCIEREFCLKP    I36 @TIMECARD_LIB.TIMECARD(SCH_1):PAGE3
     2 PCIE_REFCLKP @TIMECARD_LIB.TIMECARD(SCH_1):PCIE_REFCLKP    I36 @TIMECARD_LIB.TIMECARD(SCH_1):PAGE3

 C20 CAPACITOR-G107-0F226-CM,22UF,2A
     1 XP3R3V @TIMECARD_LIB.TIMECARD(SCH_1):XP3R3V    I37 @TIMECARD_LIB.TIMECARD(SCH_1):PAGE517
     2     SG @TIMECARD_LIB.TIMECARD(SCH_1):SG    I37 @TIMECARD_LIB.TIMECARD(SCH_1):PAGE517

 C21 CAPACITOR-G107-0F226-CM,22UF,2A
     1 XP3R3V @TIMECARD_LIB.TIMECARD(SCH_1):XP3R3V    I38 @TIMECARD_LIB.TIMECARD(SCH_1):PAGE517
     2     SG @TIMECARD_LIB.TIMECARD(SCH_1):SG    I38 @TIMECARD_LIB.TIMECARD(SCH_1):PAGE517

 C22 CAPACITOR-G107-0F226-CM,22UF,2A
     1 XP3R3V @TIMECARD_LIB.TIMECARD(SCH_1):XP3R3V    I40 @TIMECARD_LIB.TIMECARD(SCH_1):PAGE517
     2     SG @TIMECARD_LIB.TIMECARD(SCH_1):SG    I40 @TIMECARD_LIB.TIMECARD(SCH_1):PAGE517

 C23 CAPACITOR-G105-0B104-CK,0.1UF,A
     1 C_PCIEREFCLKN @TIMECARD_LIB.TIMECARD(SCH_1):C_PCIEREFCLKN    I37 @TIMECARD_LIB.TIMECARD(SCH_1):PAGE3
     2 PCIE_REFCLKN @TIMECARD_LIB.TIMECARD(SCH_1):PCIE_REFCLKN    I37 @TIMECARD_LIB.TIMECARD(SCH_1):PAGE3

 C24 CAPACITOR-G105-0B104-CK,0.1UF,A
     1 C_CPU_RX_PCIE_MGT0_TXP @TIMECARD_LIB.TIMECARD(SCH_1):C_CPU_RX_PCIE_MGT0_TXP    I35 @TIMECARD_LIB.TIMECARD(SCH_1):PAGE3
     2 CPU_RX_PCIE_MGT0_TXP @TIMECARD_LIB.TIMECARD(SCH_1):CPU_RX_PCIE_MGT0_TXP    I35 @TIMECARD_LIB.TIMECARD(SCH_1):PAGE3

 C25 CAPACITOR-G105-0B104-CK,0.1UF,A
     1 C_CPU_RX_PCIE_MGT0_TXN @TIMECARD_LIB.TIMECARD(SCH_1):C_CPU_RX_PCIE_MGT0_TXN   I115 @TIMECARD_LIB.TIMECARD(SCH_1):PAGE3
     2 CPU_RX_PCIE_MGT0_TXN @TIMECARD_LIB.TIMECARD(SCH_1):CPU_RX_PCIE_MGT0_TXN   I115 @TIMECARD_LIB.TIMECARD(SCH_1):PAGE3

 C26 CAPACITOR-G105-0B104-CK,0.1UF,A
     1 C_CPU_RX_PCIE_MGT1_TXP @TIMECARD_LIB.TIMECARD(SCH_1):C_CPU_RX_PCIE_MGT1_TXP   I116 @TIMECARD_LIB.TIMECARD(SCH_1):PAGE3
     2 CPU_RX_PCIE_MGT1_TXP @TIMECARD_LIB.TIMECARD(SCH_1):CPU_RX_PCIE_MGT1_TXP   I116 @TIMECARD_LIB.TIMECARD(SCH_1):PAGE3

 C27 CAPACITOR-G105-0B104-CK,0.1UF,A
     1 C_CPU_RX_PCIE_MGT1_TXN @TIMECARD_LIB.TIMECARD(SCH_1):C_CPU_RX_PCIE_MGT1_TXN   I117 @TIMECARD_LIB.TIMECARD(SCH_1):PAGE3
     2 CPU_RX_PCIE_MGT1_TXN @TIMECARD_LIB.TIMECARD(SCH_1):CPU_RX_PCIE_MGT1_TXN   I117 @TIMECARD_LIB.TIMECARD(SCH_1):PAGE3

 C28 CAPACITOR-G105-0B104-CK,0.1UF,A
     1 C_CPU_RX_PCIE_MGT2_TXP @TIMECARD_LIB.TIMECARD(SCH_1):C_CPU_RX_PCIE_MGT2_TXP   I118 @TIMECARD_LIB.TIMECARD(SCH_1):PAGE3
     2 CPU_RX_PCIE_MGT2_TXP @TIMECARD_LIB.TIMECARD(SCH_1):CPU_RX_PCIE_MGT2_TXP   I118 @TIMECARD_LIB.TIMECARD(SCH_1):PAGE3

 C29 CAPACITOR-G105-0B104-CK,0.1UF,A
     1 R_XP5R0V_EN @TIMECARD_LIB.TIMECARD(SCH_1):R_XP5R0V_EN    I10 @TIMECARD_LIB.TIMECARD(SCH_1):PAGE516
     2     SG @TIMECARD_LIB.TIMECARD(SCH_1):SG    I10 @TIMECARD_LIB.TIMECARD(SCH_1):PAGE516

 C30 CAPACITOR-G107-0F106-EM,10UF,2A
     1 VIN_XP5R0V @TIMECARD_LIB.TIMECARD(SCH_1):VIN_XP5R0V    I18 @TIMECARD_LIB.TIMECARD(SCH_1):PAGE516
     2     SG @TIMECARD_LIB.TIMECARD(SCH_1):SG    I18 @TIMECARD_LIB.TIMECARD(SCH_1):PAGE516

 C31 CAPACITOR-G105-0B223-EK,0.022UA
     1 XP5R0V_SS @TIMECARD_LIB.TIMECARD(SCH_1):XP5R0V_SS    I11 @TIMECARD_LIB.TIMECARD(SCH_1):PAGE516
     2 XP5R0V_AGND @TIMECARD_LIB.TIMECARD(SCH_1):XP5R0V_AGND    I11 @TIMECARD_LIB.TIMECARD(SCH_1):PAGE516

 C32 CAPACITOR-G107-0F106-EM,10UF,2A
     1 VIN_XP5R0V @TIMECARD_LIB.TIMECARD(SCH_1):VIN_XP5R0V    I19 @TIMECARD_LIB.TIMECARD(SCH_1):PAGE516
     2     SG @TIMECARD_LIB.TIMECARD(SCH_1):SG    I19 @TIMECARD_LIB.TIMECARD(SCH_1):PAGE516

 C33 CAPACITOR-G105-0B104-EK,0.1UF,A
     1 VIN_XP5R0V @TIMECARD_LIB.TIMECARD(SCH_1):VIN_XP5R0V    I20 @TIMECARD_LIB.TIMECARD(SCH_1):PAGE516
     2     SG @TIMECARD_LIB.TIMECARD(SCH_1):SG    I20 @TIMECARD_LIB.TIMECARD(SCH_1):PAGE516

 C34 CAPACITOR-G105-0B104-CK,0.1UF,A
     1 C_CPU_RX_PCIE_MGT2_TXN @TIMECARD_LIB.TIMECARD(SCH_1):C_CPU_RX_PCIE_MGT2_TXN   I119 @TIMECARD_LIB.TIMECARD(SCH_1):PAGE3
     2 CPU_RX_PCIE_MGT2_TXN @TIMECARD_LIB.TIMECARD(SCH_1):CPU_RX_PCIE_MGT2_TXN   I119 @TIMECARD_LIB.TIMECARD(SCH_1):PAGE3

 C35 CAPACITOR-G105-0B104-CK,0.1UF,A
     1 C_CPU_RX_PCIE_MGT3_TXP @TIMECARD_LIB.TIMECARD(SCH_1):C_CPU_RX_PCIE_MGT3_TXP   I120 @TIMECARD_LIB.TIMECARD(SCH_1):PAGE3
     2 CPU_RX_PCIE_MGT3_TXP @TIMECARD_LIB.TIMECARD(SCH_1):CPU_RX_PCIE_MGT3_TXP   I120 @TIMECARD_LIB.TIMECARD(SCH_1):PAGE3

 C36 CAPACITOR-G105-0B104-CK,0.1UF,A
     1 C_CPU_RX_PCIE_MGT3_TXN @TIMECARD_LIB.TIMECARD(SCH_1):C_CPU_RX_PCIE_MGT3_TXN   I121 @TIMECARD_LIB.TIMECARD(SCH_1):PAGE3
     2 CPU_RX_PCIE_MGT3_TXN @TIMECARD_LIB.TIMECARD(SCH_1):CPU_RX_PCIE_MGT3_TXN   I121 @TIMECARD_LIB.TIMECARD(SCH_1):PAGE3

 C37 CAPACITOR-G105-0B104-CK,0.1UF,A
     1 XP3R3V_FPGA @TIMECARD_LIB.TIMECARD(SCH_1):XP3R3V_FPGA     I4 @TIMECARD_LIB.TIMECARD(SCH_1):PAGE3
     2     SG @TIMECARD_LIB.TIMECARD(SCH_1):SG     I4 @TIMECARD_LIB.TIMECARD(SCH_1):PAGE3

 C38 CAPACITOR-G105-0B104-CK,0.1UF,A
     1 VDD_PCA9546A @TIMECARD_LIB.TIMECARD(SCH_1):VDD_PCA9546A    I45 @TIMECARD_LIB.TIMECARD(SCH_1):PAGE5
     2     SG @TIMECARD_LIB.TIMECARD(SCH_1):SG    I45 @TIMECARD_LIB.TIMECARD(SCH_1):PAGE5

 C39 CAPACITOR-G105-0B104-EK,0.1UF,A
     1     SG @TIMECARD_LIB.TIMECARD(SCH_1):SG    I37 @TIMECARD_LIB.TIMECARD(SCH_1):PAGE6
     2 XP3R3V_FPGA @TIMECARD_LIB.TIMECARD(SCH_1):XP3R3V_FPGA    I37 @TIMECARD_LIB.TIMECARD(SCH_1):PAGE6

 C40 CAPACITOR-G105-0B104-EK,0.1UF,A
     1 XP3R3V_FPGA @TIMECARD_LIB.TIMECARD(SCH_1):XP3R3V_FPGA    I18 @TIMECARD_LIB.TIMECARD(SCH_1):PAGE7
     2     SG @TIMECARD_LIB.TIMECARD(SCH_1):SG    I18 @TIMECARD_LIB.TIMECARD(SCH_1):PAGE7

 C41 CAPACITOR-G105-0B104-EK,0.1UF,A
     1 VIN_XP5R0V @TIMECARD_LIB.TIMECARD(SCH_1):VIN_XP5R0V    I22 @TIMECARD_LIB.TIMECARD(SCH_1):PAGE516
     2     SG @TIMECARD_LIB.TIMECARD(SCH_1):SG    I22 @TIMECARD_LIB.TIMECARD(SCH_1):PAGE516

 C42 CAPACITOR-G105-0B222-FK,2200PFA
     1 UNNAMED_516_CAPACITOR_I13_1 @TIMECARD_LIB.TIMECARD(SCH_1):UNNAMED_516_CAPACITOR_I13_1    I13 @TIMECARD_LIB.TIMECARD(SCH_1):PAGE516
     2 XP5R0V_AGND @TIMECARD_LIB.TIMECARD(SCH_1):XP5R0V_AGND    I13 @TIMECARD_LIB.TIMECARD(SCH_1):PAGE516

 C43 CAPACITOR-G104-0A180-FJ,18PF,5%
     1 XP5R0V_COMP @TIMECARD_LIB.TIMECARD(SCH_1):XP5R0V_COMP    I15 @TIMECARD_LIB.TIMECARD(SCH_1):PAGE516
     2 XP5R0V_AGND @TIMECARD_LIB.TIMECARD(SCH_1):XP5R0V_AGND    I15 @TIMECARD_LIB.TIMECARD(SCH_1):PAGE516

 C44 CAPACITOR-G105-0B104-EK,0.1UF,A
     1 UNNAMED_516_CAPACITOR_I27_1 @TIMECARD_LIB.TIMECARD(SCH_1):UNNAMED_516_CAPACITOR_I27_1    I27 @TIMECARD_LIB.TIMECARD(SCH_1):PAGE516
     2 XP5R0V_SW @TIMECARD_LIB.TIMECARD(SCH_1):XP5R0V_SW    I27 @TIMECARD_LIB.TIMECARD(SCH_1):PAGE516

 C45 CAPACITOR-G105-0A102-FJ,1000PFA
     1 XP5R0V_SW @TIMECARD_LIB.TIMECARD(SCH_1):XP5R0V_SW    I37 @TIMECARD_LIB.TIMECARD(SCH_1):PAGE516
     2 UNNAMED_516_CAPACITOR_I37_2 @TIMECARD_LIB.TIMECARD(SCH_1):UNNAMED_516_CAPACITOR_I37_2    I37 @TIMECARD_LIB.TIMECARD(SCH_1):PAGE516

 C46 CAPACITOR-G105-0B104-CK,0.1UF,A
     1 XP3R3V_EN @TIMECARD_LIB.TIMECARD(SCH_1):XP3R3V_EN    I12 @TIMECARD_LIB.TIMECARD(SCH_1):PAGE517
     2     SG @TIMECARD_LIB.TIMECARD(SCH_1):SG    I12 @TIMECARD_LIB.TIMECARD(SCH_1):PAGE517

 C47 CAPACITOR-G104-0A120-FJ,12PF,5%
     1 UNNAMED_9_BNO080LGA28_I29_XOUT3 @TIMECARD_LIB.TIMECARD(SCH_1):UNNAMED_9_BNO080LGA28_I29_XOUT32    I54 @TIMECARD_LIB.TIMECARD(SCH_1):PAGE9
     2     SG @TIMECARD_LIB.TIMECARD(SCH_1):SG    I54 @TIMECARD_LIB.TIMECARD(SCH_1):PAGE9

 C48 CAPACITOR-G107-0F106-EM,10UF,2A
     1 VIN_XP3R3 @TIMECARD_LIB.TIMECARD(SCH_1):VIN_XP3R3    I14 @TIMECARD_LIB.TIMECARD(SCH_1):PAGE517
     2     SG @TIMECARD_LIB.TIMECARD(SCH_1):SG    I14 @TIMECARD_LIB.TIMECARD(SCH_1):PAGE517

 C49 CAPACITOR-G105-0B223-EK,0.022UA
     1 XP3R3V_SS @TIMECARD_LIB.TIMECARD(SCH_1):XP3R3V_SS     I9 @TIMECARD_LIB.TIMECARD(SCH_1):PAGE517
     2 XP3R3V_AGND @TIMECARD_LIB.TIMECARD(SCH_1):XP3R3V_AGND     I9 @TIMECARD_LIB.TIMECARD(SCH_1):PAGE517

 C50 CAPACITOR-G107-0F106-EM,10UF,2A
     1 VIN_XP3R3 @TIMECARD_LIB.TIMECARD(SCH_1):VIN_XP3R3    I15 @TIMECARD_LIB.TIMECARD(SCH_1):PAGE517
     2     SG @TIMECARD_LIB.TIMECARD(SCH_1):SG    I15 @TIMECARD_LIB.TIMECARD(SCH_1):PAGE517

 C51 CAPACITOR-G104-0A120-FJ,12PF,5%
     1 UNNAMED_9_CAPACITOR_I17_1 @TIMECARD_LIB.TIMECARD(SCH_1):UNNAMED_9_CAPACITOR_I17_1    I17 @TIMECARD_LIB.TIMECARD(SCH_1):PAGE9
     2     SG @TIMECARD_LIB.TIMECARD(SCH_1):SG    I17 @TIMECARD_LIB.TIMECARD(SCH_1):PAGE9

 C52 CAPACITOR-G105-0B104-EK,0.1UF,A
     1 VIN_XP3R3 @TIMECARD_LIB.TIMECARD(SCH_1):VIN_XP3R3    I16 @TIMECARD_LIB.TIMECARD(SCH_1):PAGE517
     2     SG @TIMECARD_LIB.TIMECARD(SCH_1):SG    I16 @TIMECARD_LIB.TIMECARD(SCH_1):PAGE517

 C53 CAPACITOR-G105-0B104-EK,0.1UF,A
     1 VIN_XP3R3 @TIMECARD_LIB.TIMECARD(SCH_1):VIN_XP3R3    I21 @TIMECARD_LIB.TIMECARD(SCH_1):PAGE517
     2     SG @TIMECARD_LIB.TIMECARD(SCH_1):SG    I21 @TIMECARD_LIB.TIMECARD(SCH_1):PAGE517

 C54 CAPACITOR-G105-0B222-FK,2200PFA
     1 UNNAMED_517_CAPACITOR_I17_1 @TIMECARD_LIB.TIMECARD(SCH_1):UNNAMED_517_CAPACITOR_I17_1    I17 @TIMECARD_LIB.TIMECARD(SCH_1):PAGE517
     2 XP3R3V_AGND @TIMECARD_LIB.TIMECARD(SCH_1):XP3R3V_AGND    I17 @TIMECARD_LIB.TIMECARD(SCH_1):PAGE517

 C55 CAPACITOR-G104-0A180-FJ,18PF,5%
     1 XP3R3V_COMP @TIMECARD_LIB.TIMECARD(SCH_1):XP3R3V_COMP    I19 @TIMECARD_LIB.TIMECARD(SCH_1):PAGE517
     2 XP3R3V_AGND @TIMECARD_LIB.TIMECARD(SCH_1):XP3R3V_AGND    I19 @TIMECARD_LIB.TIMECARD(SCH_1):PAGE517

 C56 CAPACITOR-G105-0B104-EK,0.1UF,A
     1 UNNAMED_517_CAPACITOR_I27_1 @TIMECARD_LIB.TIMECARD(SCH_1):UNNAMED_517_CAPACITOR_I27_1    I27 @TIMECARD_LIB.TIMECARD(SCH_1):PAGE517
     2 XP3R3V_SW @TIMECARD_LIB.TIMECARD(SCH_1):XP3R3V_SW    I27 @TIMECARD_LIB.TIMECARD(SCH_1):PAGE517

 C57 CAPACITOR-G105-0A102-FJ,1000PFA
     1 XP3R3V_SW @TIMECARD_LIB.TIMECARD(SCH_1):XP3R3V_SW    I29 @TIMECARD_LIB.TIMECARD(SCH_1):PAGE517
     2 UNNAMED_517_CAPACITOR_I29_2 @TIMECARD_LIB.TIMECARD(SCH_1):UNNAMED_517_CAPACITOR_I29_2    I29 @TIMECARD_LIB.TIMECARD(SCH_1):PAGE517

 C58 CAPACITOR-G107-0F106-EM,10UF,2A
     1 XP5R0V_MAC @TIMECARD_LIB.TIMECARD(SCH_1):XP5R0V_MAC    I47 @TIMECARD_LIB.TIMECARD(SCH_1):PAGE527
     2     SG @TIMECARD_LIB.TIMECARD(SCH_1):SG    I47 @TIMECARD_LIB.TIMECARD(SCH_1):PAGE527

 C59 CAPACITOR-G105-0B104-EK,0.1UF,A
     1 XP5R0V_MAC @TIMECARD_LIB.TIMECARD(SCH_1):XP5R0V_MAC    I48 @TIMECARD_LIB.TIMECARD(SCH_1):PAGE527
     2     SG @TIMECARD_LIB.TIMECARD(SCH_1):SG    I48 @TIMECARD_LIB.TIMECARD(SCH_1):PAGE527

 C60 CAPACITOR-G105-0B104-EK,0.1UF,A
     1 XP5R0V_MAC @TIMECARD_LIB.TIMECARD(SCH_1):XP5R0V_MAC    I66 @TIMECARD_LIB.TIMECARD(SCH_1):PAGE527
     2     SG @TIMECARD_LIB.TIMECARD(SCH_1):SG    I66 @TIMECARD_LIB.TIMECARD(SCH_1):PAGE527

 C61 CAPACITOR-G107-0F106-EM,10UF,2A
     1 XP5R0V_USB_CONN @TIMECARD_LIB.TIMECARD(SCH_1):XP5R0V_USB_CONN    I16 @TIMECARD_LIB.TIMECARD(SCH_1):PAGE527
     2     SG @TIMECARD_LIB.TIMECARD(SCH_1):SG    I16 @TIMECARD_LIB.TIMECARD(SCH_1):PAGE527

 C62 CAPACITOR-G105-0B104-EK,0.1UF,A
     1 XP5R0V @TIMECARD_LIB.TIMECARD(SCH_1):XP5R0V    I93 @TIMECARD_LIB.TIMECARD(SCH_1):PAGE527
     2     SG @TIMECARD_LIB.TIMECARD(SCH_1):SG    I93 @TIMECARD_LIB.TIMECARD(SCH_1):PAGE527

 C63 CAPACITOR-G105-0B104-EK,0.1UF,A
     1 XP5R0V_USB_CONN @TIMECARD_LIB.TIMECARD(SCH_1):XP5R0V_USB_CONN    I15 @TIMECARD_LIB.TIMECARD(SCH_1):PAGE527
     2     SG @TIMECARD_LIB.TIMECARD(SCH_1):SG    I15 @TIMECARD_LIB.TIMECARD(SCH_1):PAGE527

 C64 CAPACITOR-G107-0F106-EM,10UF,2A
     1 XP5R0V_MAC_USB @TIMECARD_LIB.TIMECARD(SCH_1):XP5R0V_MAC_USB    I51 @TIMECARD_LIB.TIMECARD(SCH_1):PAGE527
     2     SG @TIMECARD_LIB.TIMECARD(SCH_1):SG    I51 @TIMECARD_LIB.TIMECARD(SCH_1):PAGE527

 C65 CAPACITOR-G105-0B104-EK,0.1UF,A
     1 XP5R0V_MAC_USB @TIMECARD_LIB.TIMECARD(SCH_1):XP5R0V_MAC_USB    I56 @TIMECARD_LIB.TIMECARD(SCH_1):PAGE527
     2     SG @TIMECARD_LIB.TIMECARD(SCH_1):SG    I56 @TIMECARD_LIB.TIMECARD(SCH_1):PAGE527

 C66 CAPACITOR-G105-0B104-EK,0.1UF,A
     1 XP5R0V_MAC_USB @TIMECARD_LIB.TIMECARD(SCH_1):XP5R0V_MAC_USB    I57 @TIMECARD_LIB.TIMECARD(SCH_1):PAGE527
     2     SG @TIMECARD_LIB.TIMECARD(SCH_1):SG    I57 @TIMECARD_LIB.TIMECARD(SCH_1):PAGE527

 C67 CAPACITOR-G105-0B104-CK,0.1UF,A
     1 XP3R3V_FPGA @TIMECARD_LIB.TIMECARD(SCH_1):XP3R3V_FPGA   I103 @TIMECARD_LIB.TIMECARD(SCH_1):PAGE527
     2     SG @TIMECARD_LIB.TIMECARD(SCH_1):SG   I103 @TIMECARD_LIB.TIMECARD(SCH_1):PAGE527

 C68 CAPACITOR-G105-0B104-EK,0.1UF,A
     1 XP3R3V_FPGA @TIMECARD_LIB.TIMECARD(SCH_1):XP3R3V_FPGA   I144 @TIMECARD_LIB.TIMECARD(SCH_1):PAGE527
     2     SG @TIMECARD_LIB.TIMECARD(SCH_1):SG   I144 @TIMECARD_LIB.TIMECARD(SCH_1):PAGE527

 C69 CAPACITOR-G105-0B104-EK,0.1UF,A
     1 USB_PWR_EN @TIMECARD_LIB.TIMECARD(SCH_1):USB_PWR_EN    I74 @TIMECARD_LIB.TIMECARD(SCH_1):PAGE527
     2     SG @TIMECARD_LIB.TIMECARD(SCH_1):SG    I74 @TIMECARD_LIB.TIMECARD(SCH_1):PAGE527

 C70 CAPACITOR-G105-0B104-EK,0.1UF,A
     1 XP5R0V_MAC @TIMECARD_LIB.TIMECARD(SCH_1):XP5R0V_MAC    I77 @TIMECARD_LIB.TIMECARD(SCH_1):PAGE527
     2     SG @TIMECARD_LIB.TIMECARD(SCH_1):SG    I77 @TIMECARD_LIB.TIMECARD(SCH_1):PAGE527

 C71 CAPACITOR-G105-0B104-EK,0.1UF,A
     1 XP5R0V_MAC_USB @TIMECARD_LIB.TIMECARD(SCH_1):XP5R0V_MAC_USB    I85 @TIMECARD_LIB.TIMECARD(SCH_1):PAGE527
     2     SG @TIMECARD_LIB.TIMECARD(SCH_1):SG    I85 @TIMECARD_LIB.TIMECARD(SCH_1):PAGE527

 C72 CAPACITOR-G107-0F106-EM,10UF,2A
     1 XP5R0V_VCC_ANT @TIMECARD_LIB.TIMECARD(SCH_1):XP5R0V_VCC_ANT    I12 @TIMECARD_LIB.TIMECARD(SCH_1):PAGE11
     2     SG @TIMECARD_LIB.TIMECARD(SCH_1):SG    I12 @TIMECARD_LIB.TIMECARD(SCH_1):PAGE11

 C73 CAPACITOR-G105-0B104-EK,0.1UF,A
     1 XP5R0V_VCC_ANT @TIMECARD_LIB.TIMECARD(SCH_1):XP5R0V_VCC_ANT    I13 @TIMECARD_LIB.TIMECARD(SCH_1):PAGE11
     2     SG @TIMECARD_LIB.TIMECARD(SCH_1):SG    I13 @TIMECARD_LIB.TIMECARD(SCH_1):PAGE11

 C74 CAPACITOR-G105-0B104-EK,0.1UF,A
     1 XP12R0V @TIMECARD_LIB.TIMECARD(SCH_1):XP12R0V     I4 @TIMECARD_LIB.TIMECARD(SCH_1):PAGE516
     2     SG @TIMECARD_LIB.TIMECARD(SCH_1):SG     I4 @TIMECARD_LIB.TIMECARD(SCH_1):PAGE516

 C75 CAPACITOR-G104-0B103-EK,0.01UFA
     1     SG @TIMECARD_LIB.TIMECARD(SCH_1):SG     I7 @TIMECARD_LIB.TIMECARD(SCH_1):PAGE516
     2 XP5R0V_PG @TIMECARD_LIB.TIMECARD(SCH_1):XP5R0V_PG     I7 @TIMECARD_LIB.TIMECARD(SCH_1):PAGE516

 C76 CAPACITOR-G105-0B104-EK,0.1UF,A
     1 XP12R0V @TIMECARD_LIB.TIMECARD(SCH_1):XP12R0V     I6 @TIMECARD_LIB.TIMECARD(SCH_1):PAGE517
     2     SG @TIMECARD_LIB.TIMECARD(SCH_1):SG     I6 @TIMECARD_LIB.TIMECARD(SCH_1):PAGE517

 C77 CAPACITOR-G104-0B103-EK,0.01UFA
     1     SG @TIMECARD_LIB.TIMECARD(SCH_1):SG     I2 @TIMECARD_LIB.TIMECARD(SCH_1):PAGE517
     2 R_XP3R3V_PG @TIMECARD_LIB.TIMECARD(SCH_1):R_XP3R3V_PG     I2 @TIMECARD_LIB.TIMECARD(SCH_1):PAGE517

 C78 CAPACITOR-G105-0B104-EK,0.1UF,A
     1 XP5R0V_VCC_ANT @TIMECARD_LIB.TIMECARD(SCH_1):XP5R0V_VCC_ANT    I15 @TIMECARD_LIB.TIMECARD(SCH_1):PAGE11
     2     SG @TIMECARD_LIB.TIMECARD(SCH_1):SG    I15 @TIMECARD_LIB.TIMECARD(SCH_1):PAGE11

 C79 CAPACITOR-G107-0F106-EM,10UF,2A
     1 XP3R3V_GPS @TIMECARD_LIB.TIMECARD(SCH_1):XP3R3V_GPS    I24 @TIMECARD_LIB.TIMECARD(SCH_1):PAGE11
     2     SG @TIMECARD_LIB.TIMECARD(SCH_1):SG    I24 @TIMECARD_LIB.TIMECARD(SCH_1):PAGE11

 C80 CAPACITOR-G105-0B104-CK,0.1UF,A
     1 XP3R3V_GPS @TIMECARD_LIB.TIMECARD(SCH_1):XP3R3V_GPS    I26 @TIMECARD_LIB.TIMECARD(SCH_1):PAGE11
     2     SG @TIMECARD_LIB.TIMECARD(SCH_1):SG    I26 @TIMECARD_LIB.TIMECARD(SCH_1):PAGE11

 C81 CAPACITOR-G105-0B104-CK,0.1UF,A
     1 XP3R3V_FPGA @TIMECARD_LIB.TIMECARD(SCH_1):XP3R3V_FPGA    I43 @TIMECARD_LIB.TIMECARD(SCH_1):PAGE11
     2     SG @TIMECARD_LIB.TIMECARD(SCH_1):SG    I43 @TIMECARD_LIB.TIMECARD(SCH_1):PAGE11

 C82 CAPACITOR-G105-0B104-CK,0.1UF,A
     1 XP3R3V_FPGA @TIMECARD_LIB.TIMECARD(SCH_1):XP3R3V_FPGA   I231 @TIMECARD_LIB.TIMECARD(SCH_1):PAGE12
     2     SG @TIMECARD_LIB.TIMECARD(SCH_1):SG   I231 @TIMECARD_LIB.TIMECARD(SCH_1):PAGE12

 C83 CAPACITOR-G105-0B104-CK,0.1UF,A
     1 XP3R3V_FPGA @TIMECARD_LIB.TIMECARD(SCH_1):XP3R3V_FPGA   I207 @TIMECARD_LIB.TIMECARD(SCH_1):PAGE12
     2     SG @TIMECARD_LIB.TIMECARD(SCH_1):SG   I207 @TIMECARD_LIB.TIMECARD(SCH_1):PAGE12

 C84 CAPACITOR-G105-0B104-CK,0.1UF,A
     1 XP3R3V_FPGA @TIMECARD_LIB.TIMECARD(SCH_1):XP3R3V_FPGA   I289 @TIMECARD_LIB.TIMECARD(SCH_1):PAGE12
     2     SG @TIMECARD_LIB.TIMECARD(SCH_1):SG   I289 @TIMECARD_LIB.TIMECARD(SCH_1):PAGE12

 C85 CAPACITOR-G105-0B104-CK,0.1UF,A
     1 XP3R3V_FPGA @TIMECARD_LIB.TIMECARD(SCH_1):XP3R3V_FPGA   I272 @TIMECARD_LIB.TIMECARD(SCH_1):PAGE12
     2     SG @TIMECARD_LIB.TIMECARD(SCH_1):SG   I272 @TIMECARD_LIB.TIMECARD(SCH_1):PAGE12

 C86 CAPACITOR-G104-0A180-FJ,18PF,5%
     1     SG @TIMECARD_LIB.TIMECARD(SCH_1):SG     I7 @TIMECARD_LIB.TIMECARD(SCH_1):PAGE524
     2 UNNAMED_524_CAPACITOR_I7_2 @TIMECARD_LIB.TIMECARD(SCH_1):UNNAMED_524_CAPACITOR_I7_2     I7 @TIMECARD_LIB.TIMECARD(SCH_1):PAGE524

 C87 CAPACITOR-G104-0A180-FJ,18PF,5%
     1     SG @TIMECARD_LIB.TIMECARD(SCH_1):SG    I10 @TIMECARD_LIB.TIMECARD(SCH_1):PAGE524
     2 UNNAMED_524_CAPACITOR_I10_2 @TIMECARD_LIB.TIMECARD(SCH_1):UNNAMED_524_CAPACITOR_I10_2    I10 @TIMECARD_LIB.TIMECARD(SCH_1):PAGE524

 C88 CAPACITOR-G105-0B104-EK,0.1UF,A
     1 XP3R3V_FT4232 @TIMECARD_LIB.TIMECARD(SCH_1):XP3R3V_FT4232   I378 @TIMECARD_LIB.TIMECARD(SCH_1):PAGE524
     2     SG @TIMECARD_LIB.TIMECARD(SCH_1):SG   I378 @TIMECARD_LIB.TIMECARD(SCH_1):PAGE524

 C89 CAPACITOR-G105-0B104-EK,0.1UF,A
     1 XP3R3V_FPGA @TIMECARD_LIB.TIMECARD(SCH_1):XP3R3V_FPGA   I474 @TIMECARD_LIB.TIMECARD(SCH_1):PAGE524
     2     SG @TIMECARD_LIB.TIMECARD(SCH_1):SG   I474 @TIMECARD_LIB.TIMECARD(SCH_1):PAGE524

 C90 CAPACITOR-G105-0F475-BM,4.7UF,A
     1 FT4232_VREGOUT @TIMECARD_LIB.TIMECARD(SCH_1):FT4232_VREGOUT   I123 @TIMECARD_LIB.TIMECARD(SCH_1):PAGE524
     2     SG @TIMECARD_LIB.TIMECARD(SCH_1):SG   I123 @TIMECARD_LIB.TIMECARD(SCH_1):PAGE524

 C91 CAPACITOR-G105-0F475-BM,4.7UF,A
     1 XP3R3V_FT4232 @TIMECARD_LIB.TIMECARD(SCH_1):XP3R3V_FT4232   I128 @TIMECARD_LIB.TIMECARD(SCH_1):PAGE524
     2     SG @TIMECARD_LIB.TIMECARD(SCH_1):SG   I128 @TIMECARD_LIB.TIMECARD(SCH_1):PAGE524

 C92 CAPACITOR-G105-0B104-EK,0.1UF,A
     1 XP3R3V_FPGA @TIMECARD_LIB.TIMECARD(SCH_1):XP3R3V_FPGA   I476 @TIMECARD_LIB.TIMECARD(SCH_1):PAGE524
     2     SG @TIMECARD_LIB.TIMECARD(SCH_1):SG   I476 @TIMECARD_LIB.TIMECARD(SCH_1):PAGE524

 C93 CAPACITOR-G105-0F475-BM,4.7UF,A
     1 XP2R5V_FPGA @TIMECARD_LIB.TIMECARD(SCH_1):XP2R5V_FPGA   I292 @TIMECARD_LIB.TIMECARD(SCH_1):PAGE164
     2     SG @TIMECARD_LIB.TIMECARD(SCH_1):SG   I292 @TIMECARD_LIB.TIMECARD(SCH_1):PAGE164

 C94 CAPACITOR-G105-0B104-EK,0.1UF,A
     1 XP5R0V_FT4232 @TIMECARD_LIB.TIMECARD(SCH_1):XP5R0V_FT4232   I377 @TIMECARD_LIB.TIMECARD(SCH_1):PAGE524
     2     SG @TIMECARD_LIB.TIMECARD(SCH_1):SG   I377 @TIMECARD_LIB.TIMECARD(SCH_1):PAGE524

 C95 CAPACITOR-G105-0B104-EK,0.1UF,A
     1 XP3R3V_FT4232 @TIMECARD_LIB.TIMECARD(SCH_1):XP3R3V_FT4232   I375 @TIMECARD_LIB.TIMECARD(SCH_1):PAGE524
     2     SG @TIMECARD_LIB.TIMECARD(SCH_1):SG   I375 @TIMECARD_LIB.TIMECARD(SCH_1):PAGE524

 C96 CAPACITOR-G105-0B104-EK,0.1UF,A
     1 FT4232_VREGOUT @TIMECARD_LIB.TIMECARD(SCH_1):FT4232_VREGOUT   I376 @TIMECARD_LIB.TIMECARD(SCH_1):PAGE524
     2     SG @TIMECARD_LIB.TIMECARD(SCH_1):SG   I376 @TIMECARD_LIB.TIMECARD(SCH_1):PAGE524

 C97 CAPACITOR-G105-0B104-EK,0.1UF,A
     1 XP3R3V_FPGA @TIMECARD_LIB.TIMECARD(SCH_1):XP3R3V_FPGA   I482 @TIMECARD_LIB.TIMECARD(SCH_1):PAGE524
     2     SG @TIMECARD_LIB.TIMECARD(SCH_1):SG   I482 @TIMECARD_LIB.TIMECARD(SCH_1):PAGE524

 C98 CAPACITOR-G105-0F475-BM,4.7UF,A
     1 XP3R3V_VPLL @TIMECARD_LIB.TIMECARD(SCH_1):XP3R3V_VPLL   I379 @TIMECARD_LIB.TIMECARD(SCH_1):PAGE524
     2     SG @TIMECARD_LIB.TIMECARD(SCH_1):SG   I379 @TIMECARD_LIB.TIMECARD(SCH_1):PAGE524

 C99 CAPACITOR-G105-0F475-BM,4.7UF,A
     1 XP3R3V_VPHY @TIMECARD_LIB.TIMECARD(SCH_1):XP3R3V_VPHY   I380 @TIMECARD_LIB.TIMECARD(SCH_1):PAGE524
     2     SG @TIMECARD_LIB.TIMECARD(SCH_1):SG   I380 @TIMECARD_LIB.TIMECARD(SCH_1):PAGE524

C100 CAPACITOR-G105-0B104-EK,0.1UF,A
     1 XP3R3V_VPLL @TIMECARD_LIB.TIMECARD(SCH_1):XP3R3V_VPLL   I374 @TIMECARD_LIB.TIMECARD(SCH_1):PAGE524
     2     SG @TIMECARD_LIB.TIMECARD(SCH_1):SG   I374 @TIMECARD_LIB.TIMECARD(SCH_1):PAGE524

C101 CAPACITOR-G105-0B104-EK,0.1UF,A
     1 XP3R3V_VPHY @TIMECARD_LIB.TIMECARD(SCH_1):XP3R3V_VPHY   I373 @TIMECARD_LIB.TIMECARD(SCH_1):PAGE524
     2     SG @TIMECARD_LIB.TIMECARD(SCH_1):SG   I373 @TIMECARD_LIB.TIMECARD(SCH_1):PAGE524

C102 CAPACITOR-G105-0B104-EK,0.1UF,A
     1 XP3R3V_FPGA @TIMECARD_LIB.TIMECARD(SCH_1):XP3R3V_FPGA   I490 @TIMECARD_LIB.TIMECARD(SCH_1):PAGE524
     2     SG @TIMECARD_LIB.TIMECARD(SCH_1):SG   I490 @TIMECARD_LIB.TIMECARD(SCH_1):PAGE524

C103 CAPACITOR-G105-0B104-CK,0.1UF,A
     1 XP3R3V_FPGA @TIMECARD_LIB.TIMECARD(SCH_1):XP3R3V_FPGA   I208 @TIMECARD_LIB.TIMECARD(SCH_1):PAGE164
     2     SG @TIMECARD_LIB.TIMECARD(SCH_1):SG   I208 @TIMECARD_LIB.TIMECARD(SCH_1):PAGE164

C104 CAPACITOR-G105-0B104-CK,0.1UF,A
     1 FPGA_MGTAVTT @TIMECARD_LIB.TIMECARD(SCH_1):FPGA_MGTAVTT   I257 @TIMECARD_LIB.TIMECARD(SCH_1):PAGE164
     2     SG @TIMECARD_LIB.TIMECARD(SCH_1):SG   I257 @TIMECARD_LIB.TIMECARD(SCH_1):PAGE164

C105 CAPACITOR-G105-0B104-CK,0.1UF,A
     1 XP1R0V_FPGA_MGTAVCC @TIMECARD_LIB.TIMECARD(SCH_1):XP1R0V_FPGA_MGTAVCC   I252 @TIMECARD_LIB.TIMECARD(SCH_1):PAGE164
     2     SG @TIMECARD_LIB.TIMECARD(SCH_1):SG   I252 @TIMECARD_LIB.TIMECARD(SCH_1):PAGE164

C106 CAPACITOR-G105-0B104-CK,0.1UF,A
     1 XP1R8V_FPGA_VCCAUX @TIMECARD_LIB.TIMECARD(SCH_1):XP1R8V_FPGA_VCCAUX   I203 @TIMECARD_LIB.TIMECARD(SCH_1):PAGE164
     2     SG @TIMECARD_LIB.TIMECARD(SCH_1):SG   I203 @TIMECARD_LIB.TIMECARD(SCH_1):PAGE164

C107 CAPACITOR-G105-0B104-CK,0.1UF,A
     1 XP3R3V_FPGA @TIMECARD_LIB.TIMECARD(SCH_1):XP3R3V_FPGA   I220 @TIMECARD_LIB.TIMECARD(SCH_1):PAGE164
     2     SG @TIMECARD_LIB.TIMECARD(SCH_1):SG   I220 @TIMECARD_LIB.TIMECARD(SCH_1):PAGE164

C108 CAPACITOR-G105-0B104-CK,0.1UF,A
     1 XP2R5V_FPGA @TIMECARD_LIB.TIMECARD(SCH_1):XP2R5V_FPGA   I235 @TIMECARD_LIB.TIMECARD(SCH_1):PAGE164
     2     SG @TIMECARD_LIB.TIMECARD(SCH_1):SG   I235 @TIMECARD_LIB.TIMECARD(SCH_1):PAGE164

C109 CAPACITOR-G105-0B104-CK,0.1UF,A
     1 XP1R0V_FPGA_VCCINT @TIMECARD_LIB.TIMECARD(SCH_1):XP1R0V_FPGA_VCCINT   I186 @TIMECARD_LIB.TIMECARD(SCH_1):PAGE164
     2     SG @TIMECARD_LIB.TIMECARD(SCH_1):SG   I186 @TIMECARD_LIB.TIMECARD(SCH_1):PAGE164

C110 CAPACITOR-G105-0B104-CK,0.1UF,A
     1 FPGA_MGTAVTT @TIMECARD_LIB.TIMECARD(SCH_1):FPGA_MGTAVTT   I256 @TIMECARD_LIB.TIMECARD(SCH_1):PAGE164
     2     SG @TIMECARD_LIB.TIMECARD(SCH_1):SG   I256 @TIMECARD_LIB.TIMECARD(SCH_1):PAGE164

C111 CAPACITOR-G105-0B104-CK,0.1UF,A
     1 XP1R0V_FPGA_MGTAVCC @TIMECARD_LIB.TIMECARD(SCH_1):XP1R0V_FPGA_MGTAVCC   I253 @TIMECARD_LIB.TIMECARD(SCH_1):PAGE164
     2     SG @TIMECARD_LIB.TIMECARD(SCH_1):SG   I253 @TIMECARD_LIB.TIMECARD(SCH_1):PAGE164

C112 CAPACITOR-G105-0B104-CK,0.1UF,A
     1 XP3R3V_FPGA @TIMECARD_LIB.TIMECARD(SCH_1):XP3R3V_FPGA   I209 @TIMECARD_LIB.TIMECARD(SCH_1):PAGE164
     2     SG @TIMECARD_LIB.TIMECARD(SCH_1):SG   I209 @TIMECARD_LIB.TIMECARD(SCH_1):PAGE164

C113 CAPACITOR-G105-0B104-CK,0.1UF,A
     1 XP1R8V_FPGA_VCCAUX @TIMECARD_LIB.TIMECARD(SCH_1):XP1R8V_FPGA_VCCAUX   I204 @TIMECARD_LIB.TIMECARD(SCH_1):PAGE164
     2     SG @TIMECARD_LIB.TIMECARD(SCH_1):SG   I204 @TIMECARD_LIB.TIMECARD(SCH_1):PAGE164

C114 CAPACITOR-G105-0B104-CK,0.1UF,A
     1 XP1R0V_FPGA_VCCINT @TIMECARD_LIB.TIMECARD(SCH_1):XP1R0V_FPGA_VCCINT   I187 @TIMECARD_LIB.TIMECARD(SCH_1):PAGE164
     2     SG @TIMECARD_LIB.TIMECARD(SCH_1):SG   I187 @TIMECARD_LIB.TIMECARD(SCH_1):PAGE164

C115 CAPACITOR-G105-0B104-CK,0.1UF,A
     1 XP3R3V_FPGA @TIMECARD_LIB.TIMECARD(SCH_1):XP3R3V_FPGA   I221 @TIMECARD_LIB.TIMECARD(SCH_1):PAGE164
     2     SG @TIMECARD_LIB.TIMECARD(SCH_1):SG   I221 @TIMECARD_LIB.TIMECARD(SCH_1):PAGE164

C116 CAPACITOR-G105-0B104-CK,0.1UF,A
     1 XP2R5V_FPGA @TIMECARD_LIB.TIMECARD(SCH_1):XP2R5V_FPGA   I236 @TIMECARD_LIB.TIMECARD(SCH_1):PAGE164
     2     SG @TIMECARD_LIB.TIMECARD(SCH_1):SG   I236 @TIMECARD_LIB.TIMECARD(SCH_1):PAGE164

C117 CAPACITOR-G105-0F475-BM,4.7UF,A
     1 FPGA_MGTAVTT @TIMECARD_LIB.TIMECARD(SCH_1):FPGA_MGTAVTT   I246 @TIMECARD_LIB.TIMECARD(SCH_1):PAGE164
     2     SG @TIMECARD_LIB.TIMECARD(SCH_1):SG   I246 @TIMECARD_LIB.TIMECARD(SCH_1):PAGE164

C118 CAPACITOR-G105-0B104-CK,0.1UF,A
     1 XP1R0V_FPGA_MGTAVCC @TIMECARD_LIB.TIMECARD(SCH_1):XP1R0V_FPGA_MGTAVCC   I254 @TIMECARD_LIB.TIMECARD(SCH_1):PAGE164
     2     SG @TIMECARD_LIB.TIMECARD(SCH_1):SG   I254 @TIMECARD_LIB.TIMECARD(SCH_1):PAGE164

C119 CAPACITOR-G105-0B104-CK,0.1UF,A
     1 XP3R3V_FPGA @TIMECARD_LIB.TIMECARD(SCH_1):XP3R3V_FPGA   I210 @TIMECARD_LIB.TIMECARD(SCH_1):PAGE164
     2     SG @TIMECARD_LIB.TIMECARD(SCH_1):SG   I210 @TIMECARD_LIB.TIMECARD(SCH_1):PAGE164

C120 CAPACITOR-G105-0F475-BM,4.7UF,A
     1 XP1R8V_FPGA_VCCAUX @TIMECARD_LIB.TIMECARD(SCH_1):XP1R8V_FPGA_VCCAUX   I177 @TIMECARD_LIB.TIMECARD(SCH_1):PAGE164
     2     SG @TIMECARD_LIB.TIMECARD(SCH_1):SG   I177 @TIMECARD_LIB.TIMECARD(SCH_1):PAGE164

C121 CAPACITOR-G105-0B104-CK,0.1UF,A
     1 XP1R0V_FPGA_VCCINT @TIMECARD_LIB.TIMECARD(SCH_1):XP1R0V_FPGA_VCCINT   I188 @TIMECARD_LIB.TIMECARD(SCH_1):PAGE164
     2     SG @TIMECARD_LIB.TIMECARD(SCH_1):SG   I188 @TIMECARD_LIB.TIMECARD(SCH_1):PAGE164

C122 CAPACITOR-G105-0B104-CK,0.1UF,A
     1 XP2R5V_FPGA @TIMECARD_LIB.TIMECARD(SCH_1):XP2R5V_FPGA   I237 @TIMECARD_LIB.TIMECARD(SCH_1):PAGE164
     2     SG @TIMECARD_LIB.TIMECARD(SCH_1):SG   I237 @TIMECARD_LIB.TIMECARD(SCH_1):PAGE164

C123 CAPACITOR-G105-0B104-EK,0.1UF,A
     1 XP3R3V_FPGA @TIMECARD_LIB.TIMECARD(SCH_1):XP3R3V_FPGA   I486 @TIMECARD_LIB.TIMECARD(SCH_1):PAGE524
     2     SG @TIMECARD_LIB.TIMECARD(SCH_1):SG   I486 @TIMECARD_LIB.TIMECARD(SCH_1):PAGE524

C124 CAPACITOR-G105-0B104-CK,0.1UF,A
     1 XP1R0V_FPGA_MGTAVCC @TIMECARD_LIB.TIMECARD(SCH_1):XP1R0V_FPGA_MGTAVCC   I255 @TIMECARD_LIB.TIMECARD(SCH_1):PAGE164
     2     SG @TIMECARD_LIB.TIMECARD(SCH_1):SG   I255 @TIMECARD_LIB.TIMECARD(SCH_1):PAGE164

C125 CAPACITOR-G107-0F476-AM,47UF,2A
     1 FPGA_MGTAVTT @TIMECARD_LIB.TIMECARD(SCH_1):FPGA_MGTAVTT   I264 @TIMECARD_LIB.TIMECARD(SCH_1):PAGE164
     2     SG @TIMECARD_LIB.TIMECARD(SCH_1):SG   I264 @TIMECARD_LIB.TIMECARD(SCH_1):PAGE164

C126 CAPACITOR-G105-0B104-CK,0.1UF,A
     1 XP3R3V_FPGA @TIMECARD_LIB.TIMECARD(SCH_1):XP3R3V_FPGA   I211 @TIMECARD_LIB.TIMECARD(SCH_1):PAGE164
     2     SG @TIMECARD_LIB.TIMECARD(SCH_1):SG   I211 @TIMECARD_LIB.TIMECARD(SCH_1):PAGE164

C127 CAPACITOR-G105-0B104-CK,0.1UF,A
     1 XP2R5V_FPGA @TIMECARD_LIB.TIMECARD(SCH_1):XP2R5V_FPGA   I238 @TIMECARD_LIB.TIMECARD(SCH_1):PAGE164
     2     SG @TIMECARD_LIB.TIMECARD(SCH_1):SG   I238 @TIMECARD_LIB.TIMECARD(SCH_1):PAGE164

C128 CAPACITOR-G105-0F475-BM,4.7UF,A
     1 XP1R8V_FPGA_VCCAUX @TIMECARD_LIB.TIMECARD(SCH_1):XP1R8V_FPGA_VCCAUX   I243 @TIMECARD_LIB.TIMECARD(SCH_1):PAGE164
     2     SG @TIMECARD_LIB.TIMECARD(SCH_1):SG   I243 @TIMECARD_LIB.TIMECARD(SCH_1):PAGE164

C129 CAPACITOR-G105-0B104-CK,0.1UF,A
     1 XP1R0V_FPGA_VCCINT @TIMECARD_LIB.TIMECARD(SCH_1):XP1R0V_FPGA_VCCINT   I189 @TIMECARD_LIB.TIMECARD(SCH_1):PAGE164
     2     SG @TIMECARD_LIB.TIMECARD(SCH_1):SG   I189 @TIMECARD_LIB.TIMECARD(SCH_1):PAGE164

C130 CAPACITOR-G105-0B104-CK,0.1UF,A
     1 XP3R3V_FPGA @TIMECARD_LIB.TIMECARD(SCH_1):XP3R3V_FPGA   I223 @TIMECARD_LIB.TIMECARD(SCH_1):PAGE164
     2     SG @TIMECARD_LIB.TIMECARD(SCH_1):SG   I223 @TIMECARD_LIB.TIMECARD(SCH_1):PAGE164

C131 CAPACITOR-G105-0F475-BM,4.7UF,A
     1 XP1R0V_FPGA_MGTAVCC @TIMECARD_LIB.TIMECARD(SCH_1):XP1R0V_FPGA_MGTAVCC   I248 @TIMECARD_LIB.TIMECARD(SCH_1):PAGE164
     2     SG @TIMECARD_LIB.TIMECARD(SCH_1):SG   I248 @TIMECARD_LIB.TIMECARD(SCH_1):PAGE164

C132 CAPACITOR-G105-0B104-CK,0.1UF,A
     1 XP3R3V_FPGA @TIMECARD_LIB.TIMECARD(SCH_1):XP3R3V_FPGA   I212 @TIMECARD_LIB.TIMECARD(SCH_1):PAGE164
     2     SG @TIMECARD_LIB.TIMECARD(SCH_1):SG   I212 @TIMECARD_LIB.TIMECARD(SCH_1):PAGE164

C133 CAPACITOR-G105-0B104-CK,0.1UF,A
     1 XP1R0V_FPGA_VCCINT @TIMECARD_LIB.TIMECARD(SCH_1):XP1R0V_FPGA_VCCINT   I190 @TIMECARD_LIB.TIMECARD(SCH_1):PAGE164
     2     SG @TIMECARD_LIB.TIMECARD(SCH_1):SG   I190 @TIMECARD_LIB.TIMECARD(SCH_1):PAGE164

C134 CAPACITOR-G105-0B104-CK,0.1UF,A
     1 XP3R3V_FPGA @TIMECARD_LIB.TIMECARD(SCH_1):XP3R3V_FPGA   I224 @TIMECARD_LIB.TIMECARD(SCH_1):PAGE164
     2     SG @TIMECARD_LIB.TIMECARD(SCH_1):SG   I224 @TIMECARD_LIB.TIMECARD(SCH_1):PAGE164

C135 CAPACITOR-G105-0B104-CK,0.1UF,A
     1 XP2R5V_FPGA @TIMECARD_LIB.TIMECARD(SCH_1):XP2R5V_FPGA   I239 @TIMECARD_LIB.TIMECARD(SCH_1):PAGE164
     2     SG @TIMECARD_LIB.TIMECARD(SCH_1):SG   I239 @TIMECARD_LIB.TIMECARD(SCH_1):PAGE164

C136 CAPACITOR-G105-0B104-CK,0.1UF,A
     1 XP1R2V_FPGA @TIMECARD_LIB.TIMECARD(SCH_1):XP1R2V_FPGA   I249 @TIMECARD_LIB.TIMECARD(SCH_1):PAGE164
     2     SG @TIMECARD_LIB.TIMECARD(SCH_1):SG   I249 @TIMECARD_LIB.TIMECARD(SCH_1):PAGE164

C137 CAPACITOR-G107-0F476-AM,47UF,2A
     1 XP1R0V_FPGA_MGTAVCC @TIMECARD_LIB.TIMECARD(SCH_1):XP1R0V_FPGA_MGTAVCC   I281 @TIMECARD_LIB.TIMECARD(SCH_1):PAGE164
     2     SG @TIMECARD_LIB.TIMECARD(SCH_1):SG   I281 @TIMECARD_LIB.TIMECARD(SCH_1):PAGE164

C138 CAPACITOR-G105-0F475-BM,4.7UF,A
     1 XP1R8V_FPGA_VCCAUX @TIMECARD_LIB.TIMECARD(SCH_1):XP1R8V_FPGA_VCCAUX   I275 @TIMECARD_LIB.TIMECARD(SCH_1):PAGE164
     2     SG @TIMECARD_LIB.TIMECARD(SCH_1):SG   I275 @TIMECARD_LIB.TIMECARD(SCH_1):PAGE164

C139 CAPACITOR-G105-0B104-CK,0.1UF,A
     1 XP3R3V_FPGA @TIMECARD_LIB.TIMECARD(SCH_1):XP3R3V_FPGA   I213 @TIMECARD_LIB.TIMECARD(SCH_1):PAGE164
     2     SG @TIMECARD_LIB.TIMECARD(SCH_1):SG   I213 @TIMECARD_LIB.TIMECARD(SCH_1):PAGE164

C140 CAPACITOR-G105-0B104-CK,0.1UF,A
     1 XP3R3V_FPGA @TIMECARD_LIB.TIMECARD(SCH_1):XP3R3V_FPGA   I225 @TIMECARD_LIB.TIMECARD(SCH_1):PAGE164
     2     SG @TIMECARD_LIB.TIMECARD(SCH_1):SG   I225 @TIMECARD_LIB.TIMECARD(SCH_1):PAGE164

C141 CAPACITOR-G105-0B104-CK,0.1UF,A
     1 XP1R0V_FPGA_VCCINT @TIMECARD_LIB.TIMECARD(SCH_1):XP1R0V_FPGA_VCCINT   I191 @TIMECARD_LIB.TIMECARD(SCH_1):PAGE164
     2     SG @TIMECARD_LIB.TIMECARD(SCH_1):SG   I191 @TIMECARD_LIB.TIMECARD(SCH_1):PAGE164

C142 CAPACITOR-G105-0B104-CK,0.1UF,A
     1 XP2R5V_FPGA @TIMECARD_LIB.TIMECARD(SCH_1):XP2R5V_FPGA   I240 @TIMECARD_LIB.TIMECARD(SCH_1):PAGE164
     2     SG @TIMECARD_LIB.TIMECARD(SCH_1):SG   I240 @TIMECARD_LIB.TIMECARD(SCH_1):PAGE164

C143 CAPACITOR-G107-0F476-AM,47UF,2A
     1 XP1R2V_FPGA @TIMECARD_LIB.TIMECARD(SCH_1):XP1R2V_FPGA   I265 @TIMECARD_LIB.TIMECARD(SCH_1):PAGE164
     2     SG @TIMECARD_LIB.TIMECARD(SCH_1):SG   I265 @TIMECARD_LIB.TIMECARD(SCH_1):PAGE164

C144 CAPACITOR-G105-0B104-CK,0.1UF,A
     1 XP3R3V_FPGA @TIMECARD_LIB.TIMECARD(SCH_1):XP3R3V_FPGA   I214 @TIMECARD_LIB.TIMECARD(SCH_1):PAGE164
     2     SG @TIMECARD_LIB.TIMECARD(SCH_1):SG   I214 @TIMECARD_LIB.TIMECARD(SCH_1):PAGE164

C145 CAPACITOR-G105-0B104-CK,0.1UF,A
     1 XP3R3V_FPGA @TIMECARD_LIB.TIMECARD(SCH_1):XP3R3V_FPGA   I226 @TIMECARD_LIB.TIMECARD(SCH_1):PAGE164
     2     SG @TIMECARD_LIB.TIMECARD(SCH_1):SG   I226 @TIMECARD_LIB.TIMECARD(SCH_1):PAGE164

C146 CAPACITOR-G105-0B104-CK,0.1UF,A
     1 XP2R5V_FPGA @TIMECARD_LIB.TIMECARD(SCH_1):XP2R5V_FPGA   I241 @TIMECARD_LIB.TIMECARD(SCH_1):PAGE164
     2     SG @TIMECARD_LIB.TIMECARD(SCH_1):SG   I241 @TIMECARD_LIB.TIMECARD(SCH_1):PAGE164

C147 CAPACITOR-G105-0B104-CK,0.1UF,A
     1 XP1R0V_FPGA_VCCINT @TIMECARD_LIB.TIMECARD(SCH_1):XP1R0V_FPGA_VCCINT   I192 @TIMECARD_LIB.TIMECARD(SCH_1):PAGE164
     2     SG @TIMECARD_LIB.TIMECARD(SCH_1):SG   I192 @TIMECARD_LIB.TIMECARD(SCH_1):PAGE164

C148 CAPACITOR-G105-0B104-CK,0.1UF,A
     1 XP1R0V_FPGA @TIMECARD_LIB.TIMECARD(SCH_1):XP1R0V_FPGA   I250 @TIMECARD_LIB.TIMECARD(SCH_1):PAGE164
     2     SG @TIMECARD_LIB.TIMECARD(SCH_1):SG   I250 @TIMECARD_LIB.TIMECARD(SCH_1):PAGE164

C149 CAPACITOR-G105-0B104-CK,0.1UF,A
     1 XP3R3V_FPGA @TIMECARD_LIB.TIMECARD(SCH_1):XP3R3V_FPGA   I215 @TIMECARD_LIB.TIMECARD(SCH_1):PAGE164
     2     SG @TIMECARD_LIB.TIMECARD(SCH_1):SG   I215 @TIMECARD_LIB.TIMECARD(SCH_1):PAGE164

C150 CAPACITOR-G105-0B104-CK,0.1UF,A
     1 XP1R8V_FPGA @TIMECARD_LIB.TIMECARD(SCH_1):XP1R8V_FPGA   I276 @TIMECARD_LIB.TIMECARD(SCH_1):PAGE164
     2     SG @TIMECARD_LIB.TIMECARD(SCH_1):SG   I276 @TIMECARD_LIB.TIMECARD(SCH_1):PAGE164

C151 CAPACITOR-G105-0B104-CK,0.1UF,A
     1 XP2R5V_FPGA @TIMECARD_LIB.TIMECARD(SCH_1):XP2R5V_FPGA   I242 @TIMECARD_LIB.TIMECARD(SCH_1):PAGE164
     2     SG @TIMECARD_LIB.TIMECARD(SCH_1):SG   I242 @TIMECARD_LIB.TIMECARD(SCH_1):PAGE164

C152 CAPACITOR-G105-0B104-CK,0.1UF,A
     1 XP1R0V_FPGA_VCCINT @TIMECARD_LIB.TIMECARD(SCH_1):XP1R0V_FPGA_VCCINT   I193 @TIMECARD_LIB.TIMECARD(SCH_1):PAGE164
     2     SG @TIMECARD_LIB.TIMECARD(SCH_1):SG   I193 @TIMECARD_LIB.TIMECARD(SCH_1):PAGE164

C153 CAPACITOR-G105-0B104-CK,0.1UF,A
     1 XP3R3V_FPGA @TIMECARD_LIB.TIMECARD(SCH_1):XP3R3V_FPGA   I227 @TIMECARD_LIB.TIMECARD(SCH_1):PAGE164
     2     SG @TIMECARD_LIB.TIMECARD(SCH_1):SG   I227 @TIMECARD_LIB.TIMECARD(SCH_1):PAGE164

C154 CAPACITOR-G105-0F475-BM,4.7UF,A
     1 XP3R3V_FPGA @TIMECARD_LIB.TIMECARD(SCH_1):XP3R3V_FPGA   I270 @TIMECARD_LIB.TIMECARD(SCH_1):PAGE164
     2     SG @TIMECARD_LIB.TIMECARD(SCH_1):SG   I270 @TIMECARD_LIB.TIMECARD(SCH_1):PAGE164

C155 CAPACITOR-G107-0F476-AM,47UF,2A
     1 XP1R0V_FPGA @TIMECARD_LIB.TIMECARD(SCH_1):XP1R0V_FPGA   I266 @TIMECARD_LIB.TIMECARD(SCH_1):PAGE164
     2     SG @TIMECARD_LIB.TIMECARD(SCH_1):SG   I266 @TIMECARD_LIB.TIMECARD(SCH_1):PAGE164

C156 CAPACITOR-G105-0B104-CK,0.1UF,A
     1 XP1R0V_FPGA_VCCINT @TIMECARD_LIB.TIMECARD(SCH_1):XP1R0V_FPGA_VCCINT   I194 @TIMECARD_LIB.TIMECARD(SCH_1):PAGE164
     2     SG @TIMECARD_LIB.TIMECARD(SCH_1):SG   I194 @TIMECARD_LIB.TIMECARD(SCH_1):PAGE164

C157 CAPACITOR-G105-0B104-CK,0.1UF,A
     1 XP3R3V_FPGA @TIMECARD_LIB.TIMECARD(SCH_1):XP3R3V_FPGA   I228 @TIMECARD_LIB.TIMECARD(SCH_1):PAGE164
     2     SG @TIMECARD_LIB.TIMECARD(SCH_1):SG   I228 @TIMECARD_LIB.TIMECARD(SCH_1):PAGE164

C158 CAPACITOR-G107-0F226-CM,22UF,2A
     1 XP1R8V_FPGA @TIMECARD_LIB.TIMECARD(SCH_1):XP1R8V_FPGA   I176 @TIMECARD_LIB.TIMECARD(SCH_1):PAGE164
     2     SG @TIMECARD_LIB.TIMECARD(SCH_1):SG   I176 @TIMECARD_LIB.TIMECARD(SCH_1):PAGE164

C159 CAPACITOR-G105-0F475-BM,4.7UF,A
     1 XP3R3V_FPGA @TIMECARD_LIB.TIMECARD(SCH_1):XP3R3V_FPGA   I271 @TIMECARD_LIB.TIMECARD(SCH_1):PAGE164
     2     SG @TIMECARD_LIB.TIMECARD(SCH_1):SG   I271 @TIMECARD_LIB.TIMECARD(SCH_1):PAGE164

C160 CAPACITOR-G105-0F475-BM,4.7UF,A
     1 XP2R5V_FPGA @TIMECARD_LIB.TIMECARD(SCH_1):XP2R5V_FPGA   I245 @TIMECARD_LIB.TIMECARD(SCH_1):PAGE164
     2     SG @TIMECARD_LIB.TIMECARD(SCH_1):SG   I245 @TIMECARD_LIB.TIMECARD(SCH_1):PAGE164

C161 CAPACITOR-G105-0B104-CK,0.1UF,A
     1 XP1R0V_FPGA_VCCINT @TIMECARD_LIB.TIMECARD(SCH_1):XP1R0V_FPGA_VCCINT   I195 @TIMECARD_LIB.TIMECARD(SCH_1):PAGE164
     2     SG @TIMECARD_LIB.TIMECARD(SCH_1):SG   I195 @TIMECARD_LIB.TIMECARD(SCH_1):PAGE164

C162 CAPACITOR-G105-0B104-CK,0.1UF,A
     1 XP3R3V_FPGA @TIMECARD_LIB.TIMECARD(SCH_1):XP3R3V_FPGA   I229 @TIMECARD_LIB.TIMECARD(SCH_1):PAGE164
     2     SG @TIMECARD_LIB.TIMECARD(SCH_1):SG   I229 @TIMECARD_LIB.TIMECARD(SCH_1):PAGE164

C163 CAPACITOR-G105-0F475-BM,4.7UF,A
     1 XP3R3V_FPGA @TIMECARD_LIB.TIMECARD(SCH_1):XP3R3V_FPGA   I272 @TIMECARD_LIB.TIMECARD(SCH_1):PAGE164
     2     SG @TIMECARD_LIB.TIMECARD(SCH_1):SG   I272 @TIMECARD_LIB.TIMECARD(SCH_1):PAGE164

C164 CAPACITOR-G107-0F226-CM,22UF,2A
     1 XP2R5V_FPGA @TIMECARD_LIB.TIMECARD(SCH_1):XP2R5V_FPGA   I268 @TIMECARD_LIB.TIMECARD(SCH_1):PAGE164
     2     SG @TIMECARD_LIB.TIMECARD(SCH_1):SG   I268 @TIMECARD_LIB.TIMECARD(SCH_1):PAGE164

C165 CAPACITOR-G105-0B104-CK,0.1UF,A
     1 XP3R3V_FPGA @TIMECARD_LIB.TIMECARD(SCH_1):XP3R3V_FPGA   I230 @TIMECARD_LIB.TIMECARD(SCH_1):PAGE164
     2     SG @TIMECARD_LIB.TIMECARD(SCH_1):SG   I230 @TIMECARD_LIB.TIMECARD(SCH_1):PAGE164

C166 CAPACITOR-G105-0B104-CK,0.1UF,A
     1 XP1R0V_FPGA_VCCINT @TIMECARD_LIB.TIMECARD(SCH_1):XP1R0V_FPGA_VCCINT   I196 @TIMECARD_LIB.TIMECARD(SCH_1):PAGE164
     2     SG @TIMECARD_LIB.TIMECARD(SCH_1):SG   I196 @TIMECARD_LIB.TIMECARD(SCH_1):PAGE164

C167 CAPACITOR-G105-0F475-BM,4.7UF,A
     1 XP3R3V_FPGA @TIMECARD_LIB.TIMECARD(SCH_1):XP3R3V_FPGA   I273 @TIMECARD_LIB.TIMECARD(SCH_1):PAGE164
     2     SG @TIMECARD_LIB.TIMECARD(SCH_1):SG   I273 @TIMECARD_LIB.TIMECARD(SCH_1):PAGE164

C168 CAPACITOR-G107-0F226-CM,22UF,2A
     1 XP2R5V_FPGA @TIMECARD_LIB.TIMECARD(SCH_1):XP2R5V_FPGA   I267 @TIMECARD_LIB.TIMECARD(SCH_1):PAGE164
     2     SG @TIMECARD_LIB.TIMECARD(SCH_1):SG   I267 @TIMECARD_LIB.TIMECARD(SCH_1):PAGE164

C169 CAPACITOR-G105-0B104-CK,0.1UF,A
     1 XP1R0V_FPGA_VCCINT @TIMECARD_LIB.TIMECARD(SCH_1):XP1R0V_FPGA_VCCINT   I197 @TIMECARD_LIB.TIMECARD(SCH_1):PAGE164
     2     SG @TIMECARD_LIB.TIMECARD(SCH_1):SG   I197 @TIMECARD_LIB.TIMECARD(SCH_1):PAGE164

C170 CAPACITOR-G105-0F475-BM,4.7UF,A
     1 XP3R3V_FPGA @TIMECARD_LIB.TIMECARD(SCH_1):XP3R3V_FPGA   I282 @TIMECARD_LIB.TIMECARD(SCH_1):PAGE164
     2     SG @TIMECARD_LIB.TIMECARD(SCH_1):SG   I282 @TIMECARD_LIB.TIMECARD(SCH_1):PAGE164

C171 CAPACITOR-G105-0B104-CK,0.1UF,A
     1 XP1R0V_FPGA_VCCINT @TIMECARD_LIB.TIMECARD(SCH_1):XP1R0V_FPGA_VCCINT   I198 @TIMECARD_LIB.TIMECARD(SCH_1):PAGE164
     2     SG @TIMECARD_LIB.TIMECARD(SCH_1):SG   I198 @TIMECARD_LIB.TIMECARD(SCH_1):PAGE164

C172 CAPACITOR-G109-0G107-BM,100UF,A
     1 XP3R3V_FPGA @TIMECARD_LIB.TIMECARD(SCH_1):XP3R3V_FPGA   I174 @TIMECARD_LIB.TIMECARD(SCH_1):PAGE164
     2     SG @TIMECARD_LIB.TIMECARD(SCH_1):SG   I174 @TIMECARD_LIB.TIMECARD(SCH_1):PAGE164

C173 CAPACITOR-G107-0F476-AM,47UF,2A
     1 XP1R0V_FPGA_VCCINT @TIMECARD_LIB.TIMECARD(SCH_1):XP1R0V_FPGA_VCCINT   I280 @TIMECARD_LIB.TIMECARD(SCH_1):PAGE164
     2     SG @TIMECARD_LIB.TIMECARD(SCH_1):SG   I280 @TIMECARD_LIB.TIMECARD(SCH_1):PAGE164

C174 CAPACITOR-G109-0G107-BM,100UF,A
     1 XP3R3V_FPGA @TIMECARD_LIB.TIMECARD(SCH_1):XP3R3V_FPGA   I178 @TIMECARD_LIB.TIMECARD(SCH_1):PAGE164
     2     SG @TIMECARD_LIB.TIMECARD(SCH_1):SG   I178 @TIMECARD_LIB.TIMECARD(SCH_1):PAGE164

C175 CAPACITOR-G109-0G107-BM,100UF,A
     1 XP1R0V_FPGA_VCCINT @TIMECARD_LIB.TIMECARD(SCH_1):XP1R0V_FPGA_VCCINT   I173 @TIMECARD_LIB.TIMECARD(SCH_1):PAGE164
     2     SG @TIMECARD_LIB.TIMECARD(SCH_1):SG   I173 @TIMECARD_LIB.TIMECARD(SCH_1):PAGE164

C176 CAPACITOR-G109-0G107-BM,100UF,A
     1 XP1R0V_FPGA_VCCINT @TIMECARD_LIB.TIMECARD(SCH_1):XP1R0V_FPGA_VCCINT   I172 @TIMECARD_LIB.TIMECARD(SCH_1):PAGE164
     2     SG @TIMECARD_LIB.TIMECARD(SCH_1):SG   I172 @TIMECARD_LIB.TIMECARD(SCH_1):PAGE164

C177 CAPACITOR-G109-0G107-BM,100UF,A
     1 XP1R0V_FPGA_VCCINT @TIMECARD_LIB.TIMECARD(SCH_1):XP1R0V_FPGA_VCCINT   I277 @TIMECARD_LIB.TIMECARD(SCH_1):PAGE164
     2     SG @TIMECARD_LIB.TIMECARD(SCH_1):SG   I277 @TIMECARD_LIB.TIMECARD(SCH_1):PAGE164

C178 CAPACITOR-G105-0B104-CK,0.1UF,A
     1 XP1R0V_FPGA @TIMECARD_LIB.TIMECARD(SCH_1):XP1R0V_FPGA   I283 @TIMECARD_LIB.TIMECARD(SCH_1):PAGE164
     2     SG @TIMECARD_LIB.TIMECARD(SCH_1):SG   I283 @TIMECARD_LIB.TIMECARD(SCH_1):PAGE164

C179 CAPACITOR-G107-0F476-AM,47UF,2A
     1 XP1R0V_FPGA @TIMECARD_LIB.TIMECARD(SCH_1):XP1R0V_FPGA   I274 @TIMECARD_LIB.TIMECARD(SCH_1):PAGE164
     2     SG @TIMECARD_LIB.TIMECARD(SCH_1):SG   I274 @TIMECARD_LIB.TIMECARD(SCH_1):PAGE164

C180 CAPACITOR-G107-0F226-CM,22UF,2A
     1 XP3R3V @TIMECARD_LIB.TIMECARD(SCH_1):XP3R3V    I93 @TIMECARD_LIB.TIMECARD(SCH_1):PAGE68
     2     SG @TIMECARD_LIB.TIMECARD(SCH_1):SG    I93 @TIMECARD_LIB.TIMECARD(SCH_1):PAGE68

C181 CAPACITOR-G107-0F226-CM,22UF,2A
     1 XP3R3V @TIMECARD_LIB.TIMECARD(SCH_1):XP3R3V    I97 @TIMECARD_LIB.TIMECARD(SCH_1):PAGE68
     2     SG @TIMECARD_LIB.TIMECARD(SCH_1):SG    I97 @TIMECARD_LIB.TIMECARD(SCH_1):PAGE68

C182 CAPACITOR-G105-0B104-EK,0.1UF,A
     1 XP3R3V @TIMECARD_LIB.TIMECARD(SCH_1):XP3R3V    I94 @TIMECARD_LIB.TIMECARD(SCH_1):PAGE68
     2     SG @TIMECARD_LIB.TIMECARD(SCH_1):SG    I94 @TIMECARD_LIB.TIMECARD(SCH_1):PAGE68

C183 CAPACITOR-G105-0B104-EK,0.1UF,A
     1 XP3R3V @TIMECARD_LIB.TIMECARD(SCH_1):XP3R3V    I98 @TIMECARD_LIB.TIMECARD(SCH_1):PAGE68
     2     SG @TIMECARD_LIB.TIMECARD(SCH_1):SG    I98 @TIMECARD_LIB.TIMECARD(SCH_1):PAGE68

C184 CAPACITOR-G105-0B104-EK,0.1UF,A
     1 XP1R2V_EN_R @TIMECARD_LIB.TIMECARD(SCH_1):XP1R2V_EN_R     I3 @TIMECARD_LIB.TIMECARD(SCH_1):PAGE68
     2     SG @TIMECARD_LIB.TIMECARD(SCH_1):SG     I3 @TIMECARD_LIB.TIMECARD(SCH_1):PAGE68

C185 CAPACITOR-G107-0F106-EM,10UF,2A
     1 XP1R2V_VIN @TIMECARD_LIB.TIMECARD(SCH_1):XP1R2V_VIN    I27 @TIMECARD_LIB.TIMECARD(SCH_1):PAGE68
     2     SG @TIMECARD_LIB.TIMECARD(SCH_1):SG    I27 @TIMECARD_LIB.TIMECARD(SCH_1):PAGE68

C186 CAPACITOR-G107-0F106-EM,10UF,2A
     1 XP1R8V_VIN @TIMECARD_LIB.TIMECARD(SCH_1):XP1R8V_VIN    I47 @TIMECARD_LIB.TIMECARD(SCH_1):PAGE68
     2     SG @TIMECARD_LIB.TIMECARD(SCH_1):SG    I47 @TIMECARD_LIB.TIMECARD(SCH_1):PAGE68

C187 CAPACITOR-G105-0B104-EK,0.1UF,A
     1 XP1R8V_EN_R @TIMECARD_LIB.TIMECARD(SCH_1):XP1R8V_EN_R    I46 @TIMECARD_LIB.TIMECARD(SCH_1):PAGE68
     2     SG @TIMECARD_LIB.TIMECARD(SCH_1):SG    I46 @TIMECARD_LIB.TIMECARD(SCH_1):PAGE68

C188 CAPACITOR-G105-0B104-EK,0.1UF,A
     1 XP1R2V_VIN @TIMECARD_LIB.TIMECARD(SCH_1):XP1R2V_VIN    I35 @TIMECARD_LIB.TIMECARD(SCH_1):PAGE68
     2     SG @TIMECARD_LIB.TIMECARD(SCH_1):SG    I35 @TIMECARD_LIB.TIMECARD(SCH_1):PAGE68

C189 CAPACITOR-G105-0B104-EK,0.1UF,A
     1 XP1R8V_VIN @TIMECARD_LIB.TIMECARD(SCH_1):XP1R8V_VIN    I51 @TIMECARD_LIB.TIMECARD(SCH_1):PAGE68
     2     SG @TIMECARD_LIB.TIMECARD(SCH_1):SG    I51 @TIMECARD_LIB.TIMECARD(SCH_1):PAGE68

C190 CAPACITOR-G104-0B103-EK,0.01UFA
     1 XP1R2V_SS @TIMECARD_LIB.TIMECARD(SCH_1):XP1R2V_SS     I5 @TIMECARD_LIB.TIMECARD(SCH_1):PAGE68
     2     SG @TIMECARD_LIB.TIMECARD(SCH_1):SG     I5 @TIMECARD_LIB.TIMECARD(SCH_1):PAGE68

C191 CAPACITOR-G104-0B103-EK,0.01UFA
     1 XP1R8V_SS @TIMECARD_LIB.TIMECARD(SCH_1):XP1R8V_SS    I49 @TIMECARD_LIB.TIMECARD(SCH_1):PAGE68
     2     SG @TIMECARD_LIB.TIMECARD(SCH_1):SG    I49 @TIMECARD_LIB.TIMECARD(SCH_1):PAGE68

C192 CAPACITOR-G104-0B103-EK,0.01UFA
     1 XP1R2V_PG_R @TIMECARD_LIB.TIMECARD(SCH_1):XP1R2V_PG_R     I9 @TIMECARD_LIB.TIMECARD(SCH_1):PAGE68
     2     SG @TIMECARD_LIB.TIMECARD(SCH_1):SG     I9 @TIMECARD_LIB.TIMECARD(SCH_1):PAGE68

C193 CAPACITOR-G104-0B103-EK,0.01UFA
     1 XP1R8V_PG_R @TIMECARD_LIB.TIMECARD(SCH_1):XP1R8V_PG_R    I71 @TIMECARD_LIB.TIMECARD(SCH_1):PAGE68
     2     SG @TIMECARD_LIB.TIMECARD(SCH_1):SG    I71 @TIMECARD_LIB.TIMECARD(SCH_1):PAGE68

C194 CAPACITOR-G107-0F106-EM,10UF,2A
     1 XP1R2V_FPGA @TIMECARD_LIB.TIMECARD(SCH_1):XP1R2V_FPGA    I60 @TIMECARD_LIB.TIMECARD(SCH_1):PAGE68
     2     SG @TIMECARD_LIB.TIMECARD(SCH_1):SG    I60 @TIMECARD_LIB.TIMECARD(SCH_1):PAGE68

C195 CAPACITOR-G107-0F106-EM,10UF,2A
     1 XP1R8V_FPGA @TIMECARD_LIB.TIMECARD(SCH_1):XP1R8V_FPGA    I81 @TIMECARD_LIB.TIMECARD(SCH_1):PAGE68
     2     SG @TIMECARD_LIB.TIMECARD(SCH_1):SG    I81 @TIMECARD_LIB.TIMECARD(SCH_1):PAGE68

C196 CAPACITOR-G105-0B104-EK,0.1UF,A
     1 XP1R2V_FPGA @TIMECARD_LIB.TIMECARD(SCH_1):XP1R2V_FPGA    I61 @TIMECARD_LIB.TIMECARD(SCH_1):PAGE68
     2     SG @TIMECARD_LIB.TIMECARD(SCH_1):SG    I61 @TIMECARD_LIB.TIMECARD(SCH_1):PAGE68

C197 CAPACITOR-G105-0B104-EK,0.1UF,A
     1 XP1R8V_FPGA @TIMECARD_LIB.TIMECARD(SCH_1):XP1R8V_FPGA    I83 @TIMECARD_LIB.TIMECARD(SCH_1):PAGE68
     2     SG @TIMECARD_LIB.TIMECARD(SCH_1):SG    I83 @TIMECARD_LIB.TIMECARD(SCH_1):PAGE68

C198 CAPACITOR-G105-0F475-BM,4.7UF,A
     1 XP3R3V_FPGA @TIMECARD_LIB.TIMECARD(SCH_1):XP3R3V_FPGA   I473 @TIMECARD_LIB.TIMECARD(SCH_1):PAGE127
     2     SG @TIMECARD_LIB.TIMECARD(SCH_1):SG   I473 @TIMECARD_LIB.TIMECARD(SCH_1):PAGE127

C199 CAPACITOR-G105-0B104-CK,0.1UF,A
     1 XP3R3V_FPGA @TIMECARD_LIB.TIMECARD(SCH_1):XP3R3V_FPGA   I472 @TIMECARD_LIB.TIMECARD(SCH_1):PAGE127
     2     SG @TIMECARD_LIB.TIMECARD(SCH_1):SG   I472 @TIMECARD_LIB.TIMECARD(SCH_1):PAGE127

C200 CAPACITOR-G105-0B104-CK,0.1UF,A
     1 XP1R8V_FPGA_VCCAUX @TIMECARD_LIB.TIMECARD(SCH_1):XP1R8V_FPGA_VCCAUX   I199 @TIMECARD_LIB.TIMECARD(SCH_1):PAGE164
     2     SG @TIMECARD_LIB.TIMECARD(SCH_1):SG   I199 @TIMECARD_LIB.TIMECARD(SCH_1):PAGE164

C201 CAPACITOR-G105-0B104-CK,0.1UF,A
     1 XP1R0V_FPGA_VCCINT @TIMECARD_LIB.TIMECARD(SCH_1):XP1R0V_FPGA_VCCINT   I182 @TIMECARD_LIB.TIMECARD(SCH_1):PAGE164
     2     SG @TIMECARD_LIB.TIMECARD(SCH_1):SG   I182 @TIMECARD_LIB.TIMECARD(SCH_1):PAGE164

C202 CAPACITOR-G105-0B104-CK,0.1UF,A
     1 XP3R3V_FPGA @TIMECARD_LIB.TIMECARD(SCH_1):XP3R3V_FPGA   I205 @TIMECARD_LIB.TIMECARD(SCH_1):PAGE164
     2     SG @TIMECARD_LIB.TIMECARD(SCH_1):SG   I205 @TIMECARD_LIB.TIMECARD(SCH_1):PAGE164

C203 CAPACITOR-G105-0B104-CK,0.1UF,A
     1 XP3R3V_FPGA @TIMECARD_LIB.TIMECARD(SCH_1):XP3R3V_FPGA   I216 @TIMECARD_LIB.TIMECARD(SCH_1):PAGE164
     2     SG @TIMECARD_LIB.TIMECARD(SCH_1):SG   I216 @TIMECARD_LIB.TIMECARD(SCH_1):PAGE164

C204 CAPACITOR-G105-0B104-CK,0.1UF,A
     1 XP2R5V_FPGA @TIMECARD_LIB.TIMECARD(SCH_1):XP2R5V_FPGA   I231 @TIMECARD_LIB.TIMECARD(SCH_1):PAGE164
     2     SG @TIMECARD_LIB.TIMECARD(SCH_1):SG   I231 @TIMECARD_LIB.TIMECARD(SCH_1):PAGE164

C205 CAPACITOR-G105-0B104-CK,0.1UF,A
     1 FPGA_MGTAVTT @TIMECARD_LIB.TIMECARD(SCH_1):FPGA_MGTAVTT   I260 @TIMECARD_LIB.TIMECARD(SCH_1):PAGE164
     2     SG @TIMECARD_LIB.TIMECARD(SCH_1):SG   I260 @TIMECARD_LIB.TIMECARD(SCH_1):PAGE164

C206 CAPACITOR-G105-0B104-CK,0.1UF,A
     1 XP1R8V_FPGA_VCCAUX @TIMECARD_LIB.TIMECARD(SCH_1):XP1R8V_FPGA_VCCAUX   I200 @TIMECARD_LIB.TIMECARD(SCH_1):PAGE164
     2     SG @TIMECARD_LIB.TIMECARD(SCH_1):SG   I200 @TIMECARD_LIB.TIMECARD(SCH_1):PAGE164

C207 CAPACITOR-G105-0B104-CK,0.1UF,A
     1 XP1R0V_FPGA_VCCINT @TIMECARD_LIB.TIMECARD(SCH_1):XP1R0V_FPGA_VCCINT   I183 @TIMECARD_LIB.TIMECARD(SCH_1):PAGE164
     2     SG @TIMECARD_LIB.TIMECARD(SCH_1):SG   I183 @TIMECARD_LIB.TIMECARD(SCH_1):PAGE164

C208 CAPACITOR-G105-0B104-CK,0.1UF,A
     1 XP2R5V_FPGA @TIMECARD_LIB.TIMECARD(SCH_1):XP2R5V_FPGA   I232 @TIMECARD_LIB.TIMECARD(SCH_1):PAGE164
     2     SG @TIMECARD_LIB.TIMECARD(SCH_1):SG   I232 @TIMECARD_LIB.TIMECARD(SCH_1):PAGE164

C209 CAPACITOR-G105-0B104-CK,0.1UF,A
     1 FPGA_MGTAVTT @TIMECARD_LIB.TIMECARD(SCH_1):FPGA_MGTAVTT   I259 @TIMECARD_LIB.TIMECARD(SCH_1):PAGE164
     2     SG @TIMECARD_LIB.TIMECARD(SCH_1):SG   I259 @TIMECARD_LIB.TIMECARD(SCH_1):PAGE164

C210 CAPACITOR-G105-0B104-CK,0.1UF,A
     1 XP3R3V_FPGA @TIMECARD_LIB.TIMECARD(SCH_1):XP3R3V_FPGA   I206 @TIMECARD_LIB.TIMECARD(SCH_1):PAGE164
     2     SG @TIMECARD_LIB.TIMECARD(SCH_1):SG   I206 @TIMECARD_LIB.TIMECARD(SCH_1):PAGE164

C211 CAPACITOR-G105-0B104-CK,0.1UF,A
     1 XP3R3V_FPGA @TIMECARD_LIB.TIMECARD(SCH_1):XP3R3V_FPGA   I217 @TIMECARD_LIB.TIMECARD(SCH_1):PAGE164
     2     SG @TIMECARD_LIB.TIMECARD(SCH_1):SG   I217 @TIMECARD_LIB.TIMECARD(SCH_1):PAGE164

C212 CAPACITOR-G105-0B104-CK,0.1UF,A
     1 XP1R8V_FPGA_VCCAUX @TIMECARD_LIB.TIMECARD(SCH_1):XP1R8V_FPGA_VCCAUX   I201 @TIMECARD_LIB.TIMECARD(SCH_1):PAGE164
     2     SG @TIMECARD_LIB.TIMECARD(SCH_1):SG   I201 @TIMECARD_LIB.TIMECARD(SCH_1):PAGE164

C213 CAPACITOR-G105-0B104-CK,0.1UF,A
     1 XP2R5V_FPGA @TIMECARD_LIB.TIMECARD(SCH_1):XP2R5V_FPGA   I233 @TIMECARD_LIB.TIMECARD(SCH_1):PAGE164
     2     SG @TIMECARD_LIB.TIMECARD(SCH_1):SG   I233 @TIMECARD_LIB.TIMECARD(SCH_1):PAGE164

C214 CAPACITOR-G105-0B104-CK,0.1UF,A
     1 XP1R0V_FPGA_VCCINT @TIMECARD_LIB.TIMECARD(SCH_1):XP1R0V_FPGA_VCCINT   I184 @TIMECARD_LIB.TIMECARD(SCH_1):PAGE164
     2     SG @TIMECARD_LIB.TIMECARD(SCH_1):SG   I184 @TIMECARD_LIB.TIMECARD(SCH_1):PAGE164

C215 CAPACITOR-G105-0B104-CK,0.1UF,A
     1 XP3R3V_FPGA @TIMECARD_LIB.TIMECARD(SCH_1):XP3R3V_FPGA   I207 @TIMECARD_LIB.TIMECARD(SCH_1):PAGE164
     2     SG @TIMECARD_LIB.TIMECARD(SCH_1):SG   I207 @TIMECARD_LIB.TIMECARD(SCH_1):PAGE164

C216 CAPACITOR-G105-0B104-CK,0.1UF,A
     1 XP3R3V_FPGA @TIMECARD_LIB.TIMECARD(SCH_1):XP3R3V_FPGA   I218 @TIMECARD_LIB.TIMECARD(SCH_1):PAGE164
     2     SG @TIMECARD_LIB.TIMECARD(SCH_1):SG   I218 @TIMECARD_LIB.TIMECARD(SCH_1):PAGE164

C217 CAPACITOR-G105-0B104-CK,0.1UF,A
     1 FPGA_MGTAVTT @TIMECARD_LIB.TIMECARD(SCH_1):FPGA_MGTAVTT   I258 @TIMECARD_LIB.TIMECARD(SCH_1):PAGE164
     2     SG @TIMECARD_LIB.TIMECARD(SCH_1):SG   I258 @TIMECARD_LIB.TIMECARD(SCH_1):PAGE164

C218 CAPACITOR-G105-0B104-CK,0.1UF,A
     1 XP1R0V_FPGA_MGTAVCC @TIMECARD_LIB.TIMECARD(SCH_1):XP1R0V_FPGA_MGTAVCC   I251 @TIMECARD_LIB.TIMECARD(SCH_1):PAGE164
     2     SG @TIMECARD_LIB.TIMECARD(SCH_1):SG   I251 @TIMECARD_LIB.TIMECARD(SCH_1):PAGE164

C219 CAPACITOR-G105-0B104-CK,0.1UF,A
     1 XP1R8V_FPGA_VCCAUX @TIMECARD_LIB.TIMECARD(SCH_1):XP1R8V_FPGA_VCCAUX   I202 @TIMECARD_LIB.TIMECARD(SCH_1):PAGE164
     2     SG @TIMECARD_LIB.TIMECARD(SCH_1):SG   I202 @TIMECARD_LIB.TIMECARD(SCH_1):PAGE164

C220 CAPACITOR-G105-0B104-CK,0.1UF,A
     1 XP2R5V_FPGA @TIMECARD_LIB.TIMECARD(SCH_1):XP2R5V_FPGA   I234 @TIMECARD_LIB.TIMECARD(SCH_1):PAGE164
     2     SG @TIMECARD_LIB.TIMECARD(SCH_1):SG   I234 @TIMECARD_LIB.TIMECARD(SCH_1):PAGE164

C221 CAPACITOR-G105-0B104-CK,0.1UF,A
     1 XP3R3V_FPGA @TIMECARD_LIB.TIMECARD(SCH_1):XP3R3V_FPGA   I219 @TIMECARD_LIB.TIMECARD(SCH_1):PAGE164
     2     SG @TIMECARD_LIB.TIMECARD(SCH_1):SG   I219 @TIMECARD_LIB.TIMECARD(SCH_1):PAGE164

C222 CAPACITOR-G105-0B104-CK,0.1UF,A
     1 XP1R0V_FPGA_VCCINT @TIMECARD_LIB.TIMECARD(SCH_1):XP1R0V_FPGA_VCCINT   I185 @TIMECARD_LIB.TIMECARD(SCH_1):PAGE164
     2     SG @TIMECARD_LIB.TIMECARD(SCH_1):SG   I185 @TIMECARD_LIB.TIMECARD(SCH_1):PAGE164

C223 CAPACITOR-G105-0B104-CK,0.1UF,A
     1 XP3R3V_FPGA @TIMECARD_LIB.TIMECARD(SCH_1):XP3R3V_FPGA   I222 @TIMECARD_LIB.TIMECARD(SCH_1):PAGE164
     2     SG @TIMECARD_LIB.TIMECARD(SCH_1):SG   I222 @TIMECARD_LIB.TIMECARD(SCH_1):PAGE164

C224 CAPACITOR-G107-0F226-CM,22UF,2A
     1 XP3R3V @TIMECARD_LIB.TIMECARD(SCH_1):XP3R3V   I154 @TIMECARD_LIB.TIMECARD(SCH_1):PAGE515
     2     SG @TIMECARD_LIB.TIMECARD(SCH_1):SG   I154 @TIMECARD_LIB.TIMECARD(SCH_1):PAGE515

C225 CAPACITOR-G105-0B104-EK,0.1UF,A
     1 XP3R3V_FPGA @TIMECARD_LIB.TIMECARD(SCH_1):XP3R3V_FPGA    I92 @TIMECARD_LIB.TIMECARD(SCH_1):PAGE5
     2     SG @TIMECARD_LIB.TIMECARD(SCH_1):SG    I92 @TIMECARD_LIB.TIMECARD(SCH_1):PAGE5

C226 CAPACITOR-G105-0B104-EK,0.1UF,A
     1 XP3R3V @TIMECARD_LIB.TIMECARD(SCH_1):XP3R3V   I155 @TIMECARD_LIB.TIMECARD(SCH_1):PAGE515
     2     SG @TIMECARD_LIB.TIMECARD(SCH_1):SG   I155 @TIMECARD_LIB.TIMECARD(SCH_1):PAGE515

C227 CAPACITOR-G105-0B104-EK,0.1UF,A
     1 UNNAMED_515_CAPACITOR_I128_1 @TIMECARD_LIB.TIMECARD(SCH_1):UNNAMED_515_CAPACITOR_I128_1   I128 @TIMECARD_LIB.TIMECARD(SCH_1):PAGE515
     2     SG @TIMECARD_LIB.TIMECARD(SCH_1):SG   I128 @TIMECARD_LIB.TIMECARD(SCH_1):PAGE515

C228 CAPACITOR-G107-0F106-EM,10UF,2A
     1 UNNAMED_515_CAPACITOR_I130_1 @TIMECARD_LIB.TIMECARD(SCH_1):UNNAMED_515_CAPACITOR_I130_1   I130 @TIMECARD_LIB.TIMECARD(SCH_1):PAGE515
     2     SG @TIMECARD_LIB.TIMECARD(SCH_1):SG   I130 @TIMECARD_LIB.TIMECARD(SCH_1):PAGE515

C229 CAPACITOR-G105-0B104-CK,0.1UF,A
     1 XP3R3V_FPGA_EN_R @TIMECARD_LIB.TIMECARD(SCH_1):XP3R3V_FPGA_EN_R    I87 @TIMECARD_LIB.TIMECARD(SCH_1):PAGE515
     2     SG @TIMECARD_LIB.TIMECARD(SCH_1):SG    I87 @TIMECARD_LIB.TIMECARD(SCH_1):PAGE515

C230 CAPACITOR-G105-0B104-EK,0.1UF,A
     1 UNNAMED_515_CAPACITOR_I130_1 @TIMECARD_LIB.TIMECARD(SCH_1):UNNAMED_515_CAPACITOR_I130_1   I134 @TIMECARD_LIB.TIMECARD(SCH_1):PAGE515
     2     SG @TIMECARD_LIB.TIMECARD(SCH_1):SG   I134 @TIMECARD_LIB.TIMECARD(SCH_1):PAGE515

C231 CAPACITOR-G104-0B103-EK,0.01UFA
     1 UNNAMED_515_CAPACITOR_I132_1 @TIMECARD_LIB.TIMECARD(SCH_1):UNNAMED_515_CAPACITOR_I132_1   I132 @TIMECARD_LIB.TIMECARD(SCH_1):PAGE515
     2     SG @TIMECARD_LIB.TIMECARD(SCH_1):SG   I132 @TIMECARD_LIB.TIMECARD(SCH_1):PAGE515

C232 CAPACITOR-G107-0F226-CM,22UF,2A
     1 XP3R3V @TIMECARD_LIB.TIMECARD(SCH_1):XP3R3V    I61 @TIMECARD_LIB.TIMECARD(SCH_1):PAGE515
     2     SG @TIMECARD_LIB.TIMECARD(SCH_1):SG    I61 @TIMECARD_LIB.TIMECARD(SCH_1):PAGE515

C233 CAPACITOR-G105-0B104-CK,0.1UF,A
     1 XP3R3V @TIMECARD_LIB.TIMECARD(SCH_1):XP3R3V    I63 @TIMECARD_LIB.TIMECARD(SCH_1):PAGE515
     2     SG @TIMECARD_LIB.TIMECARD(SCH_1):SG    I63 @TIMECARD_LIB.TIMECARD(SCH_1):PAGE515

C234 CAPACITOR-G104-0B103-EK,0.01UFA
     1 UNNAMED_515_CAPACITOR_I138_1 @TIMECARD_LIB.TIMECARD(SCH_1):UNNAMED_515_CAPACITOR_I138_1   I138 @TIMECARD_LIB.TIMECARD(SCH_1):PAGE515
     2     SG @TIMECARD_LIB.TIMECARD(SCH_1):SG   I138 @TIMECARD_LIB.TIMECARD(SCH_1):PAGE515

C235 CAPACITOR-G105-0B104-CK,0.1UF,A
     1 XP3R3V @TIMECARD_LIB.TIMECARD(SCH_1):XP3R3V    I80 @TIMECARD_LIB.TIMECARD(SCH_1):PAGE515
     2     SG @TIMECARD_LIB.TIMECARD(SCH_1):SG    I80 @TIMECARD_LIB.TIMECARD(SCH_1):PAGE515

C236 CAPACITOR-G105-0B104-EK,0.1UF,A
     1 XP3R3V_FPGA_SR @TIMECARD_LIB.TIMECARD(SCH_1):XP3R3V_FPGA_SR    I66 @TIMECARD_LIB.TIMECARD(SCH_1):PAGE515
     2     SG @TIMECARD_LIB.TIMECARD(SCH_1):SG    I66 @TIMECARD_LIB.TIMECARD(SCH_1):PAGE515

C237 CAPACITOR-G105-0B104-CK,0.1UF,A
     1 XP3R3V_FPGA @TIMECARD_LIB.TIMECARD(SCH_1):XP3R3V_FPGA    I64 @TIMECARD_LIB.TIMECARD(SCH_1):PAGE515
     2     SG @TIMECARD_LIB.TIMECARD(SCH_1):SG    I64 @TIMECARD_LIB.TIMECARD(SCH_1):PAGE515

C238 CAPACITOR-G107-0F226-CM,22UF,2A
     1 XP3R3V_FPGA @TIMECARD_LIB.TIMECARD(SCH_1):XP3R3V_FPGA    I81 @TIMECARD_LIB.TIMECARD(SCH_1):PAGE515
     2     SG @TIMECARD_LIB.TIMECARD(SCH_1):SG    I81 @TIMECARD_LIB.TIMECARD(SCH_1):PAGE515

C239 CAPACITOR-G107-0F106-EM,10UF,2A
     1 XP2R5V_FPGA @TIMECARD_LIB.TIMECARD(SCH_1):XP2R5V_FPGA   I147 @TIMECARD_LIB.TIMECARD(SCH_1):PAGE515
     2     SG @TIMECARD_LIB.TIMECARD(SCH_1):SG   I147 @TIMECARD_LIB.TIMECARD(SCH_1):PAGE515

C240 CAPACITOR-G107-0F226-CM,22UF,2A
     1 XP3R3V_FPGA @TIMECARD_LIB.TIMECARD(SCH_1):XP3R3V_FPGA    I71 @TIMECARD_LIB.TIMECARD(SCH_1):PAGE515
     2     SG @TIMECARD_LIB.TIMECARD(SCH_1):SG    I71 @TIMECARD_LIB.TIMECARD(SCH_1):PAGE515

C241 CAPACITOR-G107-0F226-CM,22UF,2A
     1 XP3R3V_FPGA @TIMECARD_LIB.TIMECARD(SCH_1):XP3R3V_FPGA    I72 @TIMECARD_LIB.TIMECARD(SCH_1):PAGE515
     2     SG @TIMECARD_LIB.TIMECARD(SCH_1):SG    I72 @TIMECARD_LIB.TIMECARD(SCH_1):PAGE515

C242 CAPACITOR-G105-0B104-EK,0.1UF,A
     1 XP2R5V_FPGA @TIMECARD_LIB.TIMECARD(SCH_1):XP2R5V_FPGA   I149 @TIMECARD_LIB.TIMECARD(SCH_1):PAGE515
     2     SG @TIMECARD_LIB.TIMECARD(SCH_1):SG   I149 @TIMECARD_LIB.TIMECARD(SCH_1):PAGE515

C243 CAPACITOR-G107-0F226-CM,22UF,2A
     1 XP3R3V_FPGA @TIMECARD_LIB.TIMECARD(SCH_1):XP3R3V_FPGA    I74 @TIMECARD_LIB.TIMECARD(SCH_1):PAGE515
     2     SG @TIMECARD_LIB.TIMECARD(SCH_1):SG    I74 @TIMECARD_LIB.TIMECARD(SCH_1):PAGE515

C244 CAPACITOR-G105-0B104-EK,0.1UF,A
     1 XP3R3V @TIMECARD_LIB.TIMECARD(SCH_1):XP3R3V   I152 @TIMECARD_LIB.TIMECARD(SCH_1):PAGE522
     2     SG @TIMECARD_LIB.TIMECARD(SCH_1):SG   I152 @TIMECARD_LIB.TIMECARD(SCH_1):PAGE522

C245 CAPACITOR-G105-0B104-EK,0.1UF,A
     1 XP3R3V @TIMECARD_LIB.TIMECARD(SCH_1):XP3R3V   I153 @TIMECARD_LIB.TIMECARD(SCH_1):PAGE522
     2     SG @TIMECARD_LIB.TIMECARD(SCH_1):SG   I153 @TIMECARD_LIB.TIMECARD(SCH_1):PAGE522

C246 CAPACITOR-G105-0C106-BM,10UF,2A
     1 VDD3V3_OSC_200M @TIMECARD_LIB.TIMECARD(SCH_1):VDD3V3_OSC_200M   I151 @TIMECARD_LIB.TIMECARD(SCH_1):PAGE522
     2     SG @TIMECARD_LIB.TIMECARD(SCH_1):SG   I151 @TIMECARD_LIB.TIMECARD(SCH_1):PAGE522

C247 CAPACITOR-G105-0C106-BM,10UF,2A
     1 VDD3V3_OSC_125M @TIMECARD_LIB.TIMECARD(SCH_1):VDD3V3_OSC_125M   I154 @TIMECARD_LIB.TIMECARD(SCH_1):PAGE522
     2     SG @TIMECARD_LIB.TIMECARD(SCH_1):SG   I154 @TIMECARD_LIB.TIMECARD(SCH_1):PAGE522

C248 CAPACITOR-G105-0B104-EK,0.1UF,A
     1 VDD3V3_OSC_200M @TIMECARD_LIB.TIMECARD(SCH_1):VDD3V3_OSC_200M   I147 @TIMECARD_LIB.TIMECARD(SCH_1):PAGE522
     2     SG @TIMECARD_LIB.TIMECARD(SCH_1):SG   I147 @TIMECARD_LIB.TIMECARD(SCH_1):PAGE522

C249 CAPACITOR-G105-0B104-EK,0.1UF,A
     1 VDD3V3_OSC_125M @TIMECARD_LIB.TIMECARD(SCH_1):VDD3V3_OSC_125M   I158 @TIMECARD_LIB.TIMECARD(SCH_1):PAGE522
     2     SG @TIMECARD_LIB.TIMECARD(SCH_1):SG   I158 @TIMECARD_LIB.TIMECARD(SCH_1):PAGE522

C250 CAPACITOR-G105-0B104-EK,0.1UF,A
     1 UNNAMED_3_RESISTOR_I151_2 @TIMECARD_LIB.TIMECARD(SCH_1):UNNAMED_3_RESISTOR_I151_2   I152 @TIMECARD_LIB.TIMECARD(SCH_1):PAGE3
     2     SG @TIMECARD_LIB.TIMECARD(SCH_1):SG   I152 @TIMECARD_LIB.TIMECARD(SCH_1):PAGE3

C251 CAPACITOR-G105-0B104-CK,0.1UF,A
     1 OSC_200M_CLKP @TIMECARD_LIB.TIMECARD(SCH_1):OSC_200M_CLKP   I161 @TIMECARD_LIB.TIMECARD(SCH_1):PAGE522
     2 MHZ200CLKP_CLKIN @TIMECARD_LIB.TIMECARD(SCH_1):MHZ200CLKP_CLKIN   I161 @TIMECARD_LIB.TIMECARD(SCH_1):PAGE522

C252 CAPACITOR-G105-0B104-CK,0.1UF,A
     1 OSC_200M_CLKN @TIMECARD_LIB.TIMECARD(SCH_1):OSC_200M_CLKN   I160 @TIMECARD_LIB.TIMECARD(SCH_1):PAGE522
     2 MHZ200CLKN_CLKIN @TIMECARD_LIB.TIMECARD(SCH_1):MHZ200CLKN_CLKIN   I160 @TIMECARD_LIB.TIMECARD(SCH_1):PAGE522

C253 CAPACITOR-G105-0B104-CK,0.1UF,A
     1 OSC_125M_CLKP @TIMECARD_LIB.TIMECARD(SCH_1):OSC_125M_CLKP   I143 @TIMECARD_LIB.TIMECARD(SCH_1):PAGE522
     2 MHZ125CLKP_CLKIN @TIMECARD_LIB.TIMECARD(SCH_1):MHZ125CLKP_CLKIN   I143 @TIMECARD_LIB.TIMECARD(SCH_1):PAGE522

C254 CAPACITOR-G105-0B104-CK,0.1UF,A
     1 OSC_125M_CLKN @TIMECARD_LIB.TIMECARD(SCH_1):OSC_125M_CLKN   I142 @TIMECARD_LIB.TIMECARD(SCH_1):PAGE522
     2 MHZ125CLKN_CLKIN @TIMECARD_LIB.TIMECARD(SCH_1):MHZ125CLKN_CLKIN   I142 @TIMECARD_LIB.TIMECARD(SCH_1):PAGE522

C255 CAPACITOR-G105-0B104-EK,0.1UF,A
     1 XP12R0V @TIMECARD_LIB.TIMECARD(SCH_1):XP12R0V    I46 @TIMECARD_LIB.TIMECARD(SCH_1):PAGE523
     2     SG @TIMECARD_LIB.TIMECARD(SCH_1):SG    I46 @TIMECARD_LIB.TIMECARD(SCH_1):PAGE523

C256 CAPACITOR-G105-0B104-CK,0.1UF,A
     1 UNNAMED_523_CAPACITOR_I7_1 @TIMECARD_LIB.TIMECARD(SCH_1):UNNAMED_523_CAPACITOR_I7_1     I7 @TIMECARD_LIB.TIMECARD(SCH_1):PAGE523
     2     SG @TIMECARD_LIB.TIMECARD(SCH_1):SG     I7 @TIMECARD_LIB.TIMECARD(SCH_1):PAGE523

C257 CAPACITOR-G107-0F106-EM,10UF,2A
     1 VIN_XP1R0V @TIMECARD_LIB.TIMECARD(SCH_1):VIN_XP1R0V    I13 @TIMECARD_LIB.TIMECARD(SCH_1):PAGE523
     2     SG @TIMECARD_LIB.TIMECARD(SCH_1):SG    I13 @TIMECARD_LIB.TIMECARD(SCH_1):PAGE523

C258 CAPACITOR-G104-0B103-EK,0.01UFA
     1     SG @TIMECARD_LIB.TIMECARD(SCH_1):SG    I50 @TIMECARD_LIB.TIMECARD(SCH_1):PAGE523
     2 XP1R0V_PG @TIMECARD_LIB.TIMECARD(SCH_1):XP1R0V_PG    I50 @TIMECARD_LIB.TIMECARD(SCH_1):PAGE523

C259 CAPACITOR-G105-0B223-EK,0.022UA
     1 XP1R0V_SS @TIMECARD_LIB.TIMECARD(SCH_1):XP1R0V_SS    I12 @TIMECARD_LIB.TIMECARD(SCH_1):PAGE523
     2 XP1R0V_AGND @TIMECARD_LIB.TIMECARD(SCH_1):XP1R0V_AGND    I12 @TIMECARD_LIB.TIMECARD(SCH_1):PAGE523

C260 CAPACITOR-G107-0F106-EM,10UF,2A
     1 VIN_XP1R0V @TIMECARD_LIB.TIMECARD(SCH_1):VIN_XP1R0V    I14 @TIMECARD_LIB.TIMECARD(SCH_1):PAGE523
     2     SG @TIMECARD_LIB.TIMECARD(SCH_1):SG    I14 @TIMECARD_LIB.TIMECARD(SCH_1):PAGE523

C261 CAPACITOR-G105-0B104-EK,0.1UF,A
     1 VIN_XP1R0V @TIMECARD_LIB.TIMECARD(SCH_1):VIN_XP1R0V    I17 @TIMECARD_LIB.TIMECARD(SCH_1):PAGE523
     2     SG @TIMECARD_LIB.TIMECARD(SCH_1):SG    I17 @TIMECARD_LIB.TIMECARD(SCH_1):PAGE523

C262 CAPACITOR-G105-0B104-EK,0.1UF,A
     1 VIN_XP1R0V @TIMECARD_LIB.TIMECARD(SCH_1):VIN_XP1R0V    I19 @TIMECARD_LIB.TIMECARD(SCH_1):PAGE523
     2     SG @TIMECARD_LIB.TIMECARD(SCH_1):SG    I19 @TIMECARD_LIB.TIMECARD(SCH_1):PAGE523

C263 CAPACITOR-G104-0B472-EK,4700PFA
     1 UNNAMED_523_CAPACITOR_I9_1 @TIMECARD_LIB.TIMECARD(SCH_1):UNNAMED_523_CAPACITOR_I9_1     I9 @TIMECARD_LIB.TIMECARD(SCH_1):PAGE523
     2 XP1R0V_AGND @TIMECARD_LIB.TIMECARD(SCH_1):XP1R0V_AGND     I9 @TIMECARD_LIB.TIMECARD(SCH_1):PAGE523

C264 CAPACITOR-G104-0A180-FJ,18PF,5%
     1 XP1R0V_COMP @TIMECARD_LIB.TIMECARD(SCH_1):XP1R0V_COMP    I10 @TIMECARD_LIB.TIMECARD(SCH_1):PAGE523
     2 XP1R0V_AGND @TIMECARD_LIB.TIMECARD(SCH_1):XP1R0V_AGND    I10 @TIMECARD_LIB.TIMECARD(SCH_1):PAGE523

C265 CAPACITOR-G105-0B104-EK,0.1UF,A
     1 UNNAMED_523_CAPACITOR_I24_1 @TIMECARD_LIB.TIMECARD(SCH_1):UNNAMED_523_CAPACITOR_I24_1    I24 @TIMECARD_LIB.TIMECARD(SCH_1):PAGE523
     2 XP1R0V_SW @TIMECARD_LIB.TIMECARD(SCH_1):XP1R0V_SW    I24 @TIMECARD_LIB.TIMECARD(SCH_1):PAGE523

C266 CAPACITOR-G105-0A102-FJ,1000PFA
     1 XP1R0V_SW @TIMECARD_LIB.TIMECARD(SCH_1):XP1R0V_SW    I31 @TIMECARD_LIB.TIMECARD(SCH_1):PAGE523
     2 UNNAMED_523_CAPACITOR_I31_2 @TIMECARD_LIB.TIMECARD(SCH_1):UNNAMED_523_CAPACITOR_I31_2    I31 @TIMECARD_LIB.TIMECARD(SCH_1):PAGE523

C267 CAPACITOR-G104-0B101-FK,100PF,A
     1 UNNAMED_523_CAPACITOR_I28_1 @TIMECARD_LIB.TIMECARD(SCH_1):UNNAMED_523_CAPACITOR_I28_1    I28 @TIMECARD_LIB.TIMECARD(SCH_1):PAGE523
     2 XP1R0V_FB_R_TO_AGND @TIMECARD_LIB.TIMECARD(SCH_1):XP1R0V_FB_R_TO_AGND    I28 @TIMECARD_LIB.TIMECARD(SCH_1):PAGE523

C268 CAPACITOR-G105-0B104-CK,0.1UF,A
     1 XP1R0V_FPGA @TIMECARD_LIB.TIMECARD(SCH_1):XP1R0V_FPGA    I33 @TIMECARD_LIB.TIMECARD(SCH_1):PAGE523
     2     SG @TIMECARD_LIB.TIMECARD(SCH_1):SG    I33 @TIMECARD_LIB.TIMECARD(SCH_1):PAGE523

C269 CAPACITOR-G107-0F476-AM,47UF,2A
     1 XP1R0V_FPGA @TIMECARD_LIB.TIMECARD(SCH_1):XP1R0V_FPGA    I34 @TIMECARD_LIB.TIMECARD(SCH_1):PAGE523
     2     SG @TIMECARD_LIB.TIMECARD(SCH_1):SG    I34 @TIMECARD_LIB.TIMECARD(SCH_1):PAGE523

C270 CAPACITOR-G107-0F476-AM,47UF,2A
     1 XP1R0V_FPGA @TIMECARD_LIB.TIMECARD(SCH_1):XP1R0V_FPGA    I35 @TIMECARD_LIB.TIMECARD(SCH_1):PAGE523
     2     SG @TIMECARD_LIB.TIMECARD(SCH_1):SG    I35 @TIMECARD_LIB.TIMECARD(SCH_1):PAGE523

C271 CAPACITOR-G107-0F476-AM,47UF,2A
     1 XP1R0V_FPGA @TIMECARD_LIB.TIMECARD(SCH_1):XP1R0V_FPGA    I37 @TIMECARD_LIB.TIMECARD(SCH_1):PAGE523
     2     SG @TIMECARD_LIB.TIMECARD(SCH_1):SG    I37 @TIMECARD_LIB.TIMECARD(SCH_1):PAGE523

C272 CAPACITOR-G105-0B104-EK,0.1UF,A
     1 XP5R0V @TIMECARD_LIB.TIMECARD(SCH_1):XP5R0V    I44 @TIMECARD_LIB.TIMECARD(SCH_1):PAGE11
     2     SG @TIMECARD_LIB.TIMECARD(SCH_1):SG    I44 @TIMECARD_LIB.TIMECARD(SCH_1):PAGE11

C273 CAPACITOR-G105-0B104-CK,0.1UF,A
     1 XP3R3V_GPS @TIMECARD_LIB.TIMECARD(SCH_1):XP3R3V_GPS    I45 @TIMECARD_LIB.TIMECARD(SCH_1):PAGE11
     2     SG @TIMECARD_LIB.TIMECARD(SCH_1):SG    I45 @TIMECARD_LIB.TIMECARD(SCH_1):PAGE11

C274 CAPACITOR-G105-0C106-BM,10UF,2A
     1 VDD3V3_SHT31A @TIMECARD_LIB.TIMECARD(SCH_1):VDD3V3_SHT31A    I23 @TIMECARD_LIB.TIMECARD(SCH_1):PAGE7
     2     SG @TIMECARD_LIB.TIMECARD(SCH_1):SG    I23 @TIMECARD_LIB.TIMECARD(SCH_1):PAGE7

C275 CAPACITOR-G105-0B104-EK,0.1UF,A
     1 VDD3V3_SHT31A @TIMECARD_LIB.TIMECARD(SCH_1):VDD3V3_SHT31A    I19 @TIMECARD_LIB.TIMECARD(SCH_1):PAGE7
     2     SG @TIMECARD_LIB.TIMECARD(SCH_1):SG    I19 @TIMECARD_LIB.TIMECARD(SCH_1):PAGE7

C276 CAPACITOR-G105-0B104-EK,0.1UF,A
     1 XP1R8V_FPGA @TIMECARD_LIB.TIMECARD(SCH_1):XP1R8V_FPGA    I16 @TIMECARD_LIB.TIMECARD(SCH_1):PAGE8
     2     SG @TIMECARD_LIB.TIMECARD(SCH_1):SG    I16 @TIMECARD_LIB.TIMECARD(SCH_1):PAGE8

C277 CAPACITOR-G105-0C106-BM,10UF,2A
     1 XP1R8V_ICP10100 @TIMECARD_LIB.TIMECARD(SCH_1):XP1R8V_ICP10100    I21 @TIMECARD_LIB.TIMECARD(SCH_1):PAGE8
     2     SG @TIMECARD_LIB.TIMECARD(SCH_1):SG    I21 @TIMECARD_LIB.TIMECARD(SCH_1):PAGE8

C278 CAPACITOR-G105-0B104-EK,0.1UF,A
     1 XP1R8V_ICP10100 @TIMECARD_LIB.TIMECARD(SCH_1):XP1R8V_ICP10100    I19 @TIMECARD_LIB.TIMECARD(SCH_1):PAGE8
     2     SG @TIMECARD_LIB.TIMECARD(SCH_1):SG    I19 @TIMECARD_LIB.TIMECARD(SCH_1):PAGE8

C279 CAPACITOR-G105-0B104-EK,0.1UF,A
     1 XP3R3V_FPGA @TIMECARD_LIB.TIMECARD(SCH_1):XP3R3V_FPGA    I21 @TIMECARD_LIB.TIMECARD(SCH_1):PAGE9
     2     SG @TIMECARD_LIB.TIMECARD(SCH_1):SG    I21 @TIMECARD_LIB.TIMECARD(SCH_1):PAGE9

C280 CAPACITOR-G105-0C106-BM,10UF,2A
     1 VDD_BNO085 @TIMECARD_LIB.TIMECARD(SCH_1):VDD_BNO085    I23 @TIMECARD_LIB.TIMECARD(SCH_1):PAGE9
     2     SG @TIMECARD_LIB.TIMECARD(SCH_1):SG    I23 @TIMECARD_LIB.TIMECARD(SCH_1):PAGE9

C281 CAPACITOR-G105-0B104-EK,0.1UF,A
     1 VDD_BNO085 @TIMECARD_LIB.TIMECARD(SCH_1):VDD_BNO085    I24 @TIMECARD_LIB.TIMECARD(SCH_1):PAGE9
     2     SG @TIMECARD_LIB.TIMECARD(SCH_1):SG    I24 @TIMECARD_LIB.TIMECARD(SCH_1):PAGE9

C282 CAPACITOR-G107-0F106-EM,10UF,2A
     1 XP5R0V_MAC @TIMECARD_LIB.TIMECARD(SCH_1):XP5R0V_MAC   I208 @TIMECARD_LIB.TIMECARD(SCH_1):PAGE527
     2     SG @TIMECARD_LIB.TIMECARD(SCH_1):SG   I208 @TIMECARD_LIB.TIMECARD(SCH_1):PAGE527

C283 CAPACITOR-G107-0F106-EM,10UF,2A
     1 XP5R0V_MAC @TIMECARD_LIB.TIMECARD(SCH_1):XP5R0V_MAC   I209 @TIMECARD_LIB.TIMECARD(SCH_1):PAGE527
     2     SG @TIMECARD_LIB.TIMECARD(SCH_1):SG   I209 @TIMECARD_LIB.TIMECARD(SCH_1):PAGE527

C284 CAPACITOR-G107-0F226-CM,22UF,2A
     1 UNNAMED_525_CAPACITOR_I7_1 @TIMECARD_LIB.TIMECARD(SCH_1):UNNAMED_525_CAPACITOR_I7_1     I7 @TIMECARD_LIB.TIMECARD(SCH_1):PAGE525
     2     SG @TIMECARD_LIB.TIMECARD(SCH_1):SG     I7 @TIMECARD_LIB.TIMECARD(SCH_1):PAGE525

C285 CAPACITOR-G105-0B104-CK,0.1UF,A
     1 UNNAMED_9_BNO080LGA28_I29_CAP @TIMECARD_LIB.TIMECARD(SCH_1):UNNAMED_9_BNO080LGA28_I29_CAP    I53 @TIMECARD_LIB.TIMECARD(SCH_1):PAGE9
     2     SG @TIMECARD_LIB.TIMECARD(SCH_1):SG    I53 @TIMECARD_LIB.TIMECARD(SCH_1):PAGE9

C286 CAPACITOR-G105-0B224-DK,0.22UFA
     1 XP3R3V_EN @TIMECARD_LIB.TIMECARD(SCH_1):XP3R3V_EN    I51 @TIMECARD_LIB.TIMECARD(SCH_1):PAGE517
     2     SG @TIMECARD_LIB.TIMECARD(SCH_1):SG    I51 @TIMECARD_LIB.TIMECARD(SCH_1):PAGE517

C287 CAPACITOR-G105-0C106-BM,10UF,2A
     1 XP3R3V_AUX_PCIE @TIMECARD_LIB.TIMECARD(SCH_1):XP3R3V_AUX_PCIE   I129 @TIMECARD_LIB.TIMECARD(SCH_1):PAGE3
     2     SG @TIMECARD_LIB.TIMECARD(SCH_1):SG   I129 @TIMECARD_LIB.TIMECARD(SCH_1):PAGE3

C288 CAPACITOR-G105-0B104-EK,0.1UF,A
     1 XP3R3V_AUX_PCIE @TIMECARD_LIB.TIMECARD(SCH_1):XP3R3V_AUX_PCIE   I127 @TIMECARD_LIB.TIMECARD(SCH_1):PAGE3
     2     SG @TIMECARD_LIB.TIMECARD(SCH_1):SG   I127 @TIMECARD_LIB.TIMECARD(SCH_1):PAGE3

C289 CAPACITOR-G105-0C106-BM,10UF,2A
     1 XP3R3V_PCIE @TIMECARD_LIB.TIMECARD(SCH_1):XP3R3V_PCIE   I124 @TIMECARD_LIB.TIMECARD(SCH_1):PAGE3
     2     SG @TIMECARD_LIB.TIMECARD(SCH_1):SG   I124 @TIMECARD_LIB.TIMECARD(SCH_1):PAGE3

C290 CAPACITOR-G105-0B104-EK,0.1UF,A
     1 XP3R3V_PCIE @TIMECARD_LIB.TIMECARD(SCH_1):XP3R3V_PCIE   I126 @TIMECARD_LIB.TIMECARD(SCH_1):PAGE3
     2     SG @TIMECARD_LIB.TIMECARD(SCH_1):SG   I126 @TIMECARD_LIB.TIMECARD(SCH_1):PAGE3

C291 CAPACITOR-G107-0F226-CM,22UF,2A
     1 XP2R5V_FPGA @TIMECARD_LIB.TIMECARD(SCH_1):XP2R5V_FPGA   I290 @TIMECARD_LIB.TIMECARD(SCH_1):PAGE164
     2     SG @TIMECARD_LIB.TIMECARD(SCH_1):SG   I290 @TIMECARD_LIB.TIMECARD(SCH_1):PAGE164

C292 CAPACITOR-G107-0F226-CM,22UF,2A
     1 XP2R5V_FPGA @TIMECARD_LIB.TIMECARD(SCH_1):XP2R5V_FPGA   I291 @TIMECARD_LIB.TIMECARD(SCH_1):PAGE164
     2     SG @TIMECARD_LIB.TIMECARD(SCH_1):SG   I291 @TIMECARD_LIB.TIMECARD(SCH_1):PAGE164

C293 CAPACITOR-G105-0B224-DK,0.22UFA
     1 UNNAMED_515_CAPACITOR_I128_1 @TIMECARD_LIB.TIMECARD(SCH_1):UNNAMED_515_CAPACITOR_I128_1   I168 @TIMECARD_LIB.TIMECARD(SCH_1):PAGE515
     2     SG @TIMECARD_LIB.TIMECARD(SCH_1):SG   I168 @TIMECARD_LIB.TIMECARD(SCH_1):PAGE515

C294 CAPACITOR-G105-0B224-DK,0.22UFA
     1 XP3R3V_FPGA_EN_R @TIMECARD_LIB.TIMECARD(SCH_1):XP3R3V_FPGA_EN_R   I169 @TIMECARD_LIB.TIMECARD(SCH_1):PAGE515
     2     SG @TIMECARD_LIB.TIMECARD(SCH_1):SG   I169 @TIMECARD_LIB.TIMECARD(SCH_1):PAGE515

C297 CAPACITOR-G107-0F106-EM,10UF,2A
     1 XP12R0V_IN @TIMECARD_LIB.TIMECARD(SCH_1):XP12R0V_IN   I229 @TIMECARD_LIB.TIMECARD(SCH_1):PAGE15
     2     SG @TIMECARD_LIB.TIMECARD(SCH_1):SG   I229 @TIMECARD_LIB.TIMECARD(SCH_1):PAGE15

C298 CAPACITOR-G105-0B104-EK,0.1UF,A
     1 UNNAMED_525_CAPACITOR_I7_1 @TIMECARD_LIB.TIMECARD(SCH_1):UNNAMED_525_CAPACITOR_I7_1     I8 @TIMECARD_LIB.TIMECARD(SCH_1):PAGE525
     2     SG @TIMECARD_LIB.TIMECARD(SCH_1):SG     I8 @TIMECARD_LIB.TIMECARD(SCH_1):PAGE525

C299 CAPACITOR-G107-0F106-EM,10UF,2A
     1 XP12R0V_IN @TIMECARD_LIB.TIMECARD(SCH_1):XP12R0V_IN   I230 @TIMECARD_LIB.TIMECARD(SCH_1):PAGE15
     2     SG @TIMECARD_LIB.TIMECARD(SCH_1):SG   I230 @TIMECARD_LIB.TIMECARD(SCH_1):PAGE15

C300 CAPACITOR-G107-0F106-EM,10UF,2A
     1 UNNAMED_525_CAPACITOR_I16_1 @TIMECARD_LIB.TIMECARD(SCH_1):UNNAMED_525_CAPACITOR_I16_1    I16 @TIMECARD_LIB.TIMECARD(SCH_1):PAGE525
     2     SG @TIMECARD_LIB.TIMECARD(SCH_1):SG    I16 @TIMECARD_LIB.TIMECARD(SCH_1):PAGE525

C301 CAPACITOR-G107-0F106-EM,10UF,2A
     1 XP12R0V_IN @TIMECARD_LIB.TIMECARD(SCH_1):XP12R0V_IN   I232 @TIMECARD_LIB.TIMECARD(SCH_1):PAGE15
     2     SG @TIMECARD_LIB.TIMECARD(SCH_1):SG   I232 @TIMECARD_LIB.TIMECARD(SCH_1):PAGE15

C302 CAPACITOR-G105-0B104-EK,0.1UF,A
     1 UNNAMED_525_CAPACITOR_I14_1 @TIMECARD_LIB.TIMECARD(SCH_1):UNNAMED_525_CAPACITOR_I14_1    I14 @TIMECARD_LIB.TIMECARD(SCH_1):PAGE525
     2     SG @TIMECARD_LIB.TIMECARD(SCH_1):SG    I14 @TIMECARD_LIB.TIMECARD(SCH_1):PAGE525

C303 CAPACITOR-G107-0F106-EM,10UF,2A
     1 XP12R0V_IN @TIMECARD_LIB.TIMECARD(SCH_1):XP12R0V_IN   I231 @TIMECARD_LIB.TIMECARD(SCH_1):PAGE15
     2     SG @TIMECARD_LIB.TIMECARD(SCH_1):SG   I231 @TIMECARD_LIB.TIMECARD(SCH_1):PAGE15

C304 CAPACITOR-G105-0B104-EK,0.1UF,A
     1 UNNAMED_525_CAPACITOR_I16_1 @TIMECARD_LIB.TIMECARD(SCH_1):UNNAMED_525_CAPACITOR_I16_1    I20 @TIMECARD_LIB.TIMECARD(SCH_1):PAGE525
     2     SG @TIMECARD_LIB.TIMECARD(SCH_1):SG    I20 @TIMECARD_LIB.TIMECARD(SCH_1):PAGE525

C305 CAPACITOR-G105-0B104-EK,0.1UF,A
     1     SG @TIMECARD_LIB.TIMECARD(SCH_1):SG    I67 @TIMECARD_LIB.TIMECARD(SCH_1):PAGE6
     2 XP3R3V_FPGA @TIMECARD_LIB.TIMECARD(SCH_1):XP3R3V_FPGA    I67 @TIMECARD_LIB.TIMECARD(SCH_1):PAGE6

C306 CAPACITOR-G105-0B104-EK,0.1UF,A
     1     SG @TIMECARD_LIB.TIMECARD(SCH_1):SG    I91 @TIMECARD_LIB.TIMECARD(SCH_1):PAGE6
     2 XP3R3V_FPGA @TIMECARD_LIB.TIMECARD(SCH_1):XP3R3V_FPGA    I91 @TIMECARD_LIB.TIMECARD(SCH_1):PAGE6

C307 CAPACITOR-G104-0B103-EK,0.01UFA
     1 UNNAMED_525_CAPACITOR_I18_1 @TIMECARD_LIB.TIMECARD(SCH_1):UNNAMED_525_CAPACITOR_I18_1    I18 @TIMECARD_LIB.TIMECARD(SCH_1):PAGE525
     2     SG @TIMECARD_LIB.TIMECARD(SCH_1):SG    I18 @TIMECARD_LIB.TIMECARD(SCH_1):PAGE525

C308 CAPACITOR-G107-0F106-EM,10UF,2A
     1 XP3R3V_FT4232 @TIMECARD_LIB.TIMECARD(SCH_1):XP3R3V_FT4232    I64 @TIMECARD_LIB.TIMECARD(SCH_1):PAGE525
     2     SG @TIMECARD_LIB.TIMECARD(SCH_1):SG    I64 @TIMECARD_LIB.TIMECARD(SCH_1):PAGE525

C309 CAPACITOR-G105-0B104-EK,0.1UF,A
     1 XP3R3V_FT4232 @TIMECARD_LIB.TIMECARD(SCH_1):XP3R3V_FT4232    I56 @TIMECARD_LIB.TIMECARD(SCH_1):PAGE525
     2     SG @TIMECARD_LIB.TIMECARD(SCH_1):SG    I56 @TIMECARD_LIB.TIMECARD(SCH_1):PAGE525

C310 CAPACITOR-G104-0A180-FJ,18PF,5%
     1     SG @TIMECARD_LIB.TIMECARD(SCH_1):SG   I318 @TIMECARD_LIB.TIMECARD(SCH_1):PAGE12
     2 UNNAMED_12_CAPACITOR_I318_2 @TIMECARD_LIB.TIMECARD(SCH_1):UNNAMED_12_CAPACITOR_I318_2   I318 @TIMECARD_LIB.TIMECARD(SCH_1):PAGE12

C311 CAPACITOR-G104-0A180-FJ,18PF,5%
     1     SG @TIMECARD_LIB.TIMECARD(SCH_1):SG   I321 @TIMECARD_LIB.TIMECARD(SCH_1):PAGE12
     2 UNNAMED_12_CAPACITOR_I321_2 @TIMECARD_LIB.TIMECARD(SCH_1):UNNAMED_12_CAPACITOR_I321_2   I321 @TIMECARD_LIB.TIMECARD(SCH_1):PAGE12

C312 CAPACITOR-G105-0B104-CK,0.1UF,A
     1 XP3R3V @TIMECARD_LIB.TIMECARD(SCH_1):XP3R3V    I39 @TIMECARD_LIB.TIMECARD(SCH_1):PAGE8
     2     SG @TIMECARD_LIB.TIMECARD(SCH_1):SG    I39 @TIMECARD_LIB.TIMECARD(SCH_1):PAGE8

C313 CAPACITOR-G105-0B104-CK,0.1UF,A
     1 XP1R8V_ICP10100 @TIMECARD_LIB.TIMECARD(SCH_1):XP1R8V_ICP10100    I41 @TIMECARD_LIB.TIMECARD(SCH_1):PAGE8
     2     SG @TIMECARD_LIB.TIMECARD(SCH_1):SG    I41 @TIMECARD_LIB.TIMECARD(SCH_1):PAGE8

C314 CAPACITOR-G105-0C106-BM,10UF,2A
     1 XP3R3V_FPGA @TIMECARD_LIB.TIMECARD(SCH_1):XP3R3V_FPGA   I238 @TIMECARD_LIB.TIMECARD(SCH_1):PAGE14
     2     SG @TIMECARD_LIB.TIMECARD(SCH_1):SG   I238 @TIMECARD_LIB.TIMECARD(SCH_1):PAGE14

C315 CAPACITOR-G105-0B104-EK,0.1UF,A
     1 XP3R3V_FPGA @TIMECARD_LIB.TIMECARD(SCH_1):XP3R3V_FPGA   I237 @TIMECARD_LIB.TIMECARD(SCH_1):PAGE14
     2     SG @TIMECARD_LIB.TIMECARD(SCH_1):SG   I237 @TIMECARD_LIB.TIMECARD(SCH_1):PAGE14

C316 CAPACITOR-G105-0B104-EK,0.1UF,A
     1 RGB_LED_SHUTDOWN_N @TIMECARD_LIB.TIMECARD(SCH_1):RGB_LED_SHUTDOWN_N   I250 @TIMECARD_LIB.TIMECARD(SCH_1):PAGE14
     2     SG @TIMECARD_LIB.TIMECARD(SCH_1):SG   I250 @TIMECARD_LIB.TIMECARD(SCH_1):PAGE14

C317 CAPACITOR-G104-0A180-FJ,18PF,5%
     1     SG @TIMECARD_LIB.TIMECARD(SCH_1):SG   I328 @TIMECARD_LIB.TIMECARD(SCH_1):PAGE12
     2 UNNAMED_12_CAPACITOR_I328_2 @TIMECARD_LIB.TIMECARD(SCH_1):UNNAMED_12_CAPACITOR_I328_2   I328 @TIMECARD_LIB.TIMECARD(SCH_1):PAGE12

C318 CAPACITOR-G104-0A180-FJ,18PF,5%
     1     SG @TIMECARD_LIB.TIMECARD(SCH_1):SG   I332 @TIMECARD_LIB.TIMECARD(SCH_1):PAGE12
     2 UNNAMED_12_CAPACITOR_I332_2 @TIMECARD_LIB.TIMECARD(SCH_1):UNNAMED_12_CAPACITOR_I332_2   I332 @TIMECARD_LIB.TIMECARD(SCH_1):PAGE12

 CR1 DIODE_2F-G122-10186-01
     C UNNAMED_525_CAPACITOR_I7_1 @TIMECARD_LIB.TIMECARD(SCH_1):UNNAMED_525_CAPACITOR_I7_1   I102 @TIMECARD_LIB.TIMECARD(SCH_1):PAGE525
     A XP5R0V @TIMECARD_LIB.TIMECARD(SCH_1):XP5R0V   I102 @TIMECARD_LIB.TIMECARD(SCH_1):PAGE525

 CR2 DIODE_2F-G122-10186-01
     C UNNAMED_525_CAPACITOR_I7_1 @TIMECARD_LIB.TIMECARD(SCH_1):UNNAMED_525_CAPACITOR_I7_1   I104 @TIMECARD_LIB.TIMECARD(SCH_1):PAGE525
     A XP5R0V_FT4232 @TIMECARD_LIB.TIMECARD(SCH_1):XP5R0V_FT4232   I104 @TIMECARD_LIB.TIMECARD(SCH_1):PAGE525

 CR3 DIODE_2-G122-00005-01
     C XP12R0V @TIMECARD_LIB.TIMECARD(SCH_1):XP12R0V   I204 @TIMECARD_LIB.TIMECARD(SCH_1):PAGE15
     A     SG @TIMECARD_LIB.TIMECARD(SCH_1):SG   I204 @TIMECARD_LIB.TIMECARD(SCH_1):PAGE15

 CR4 DIODE_4_V1-G122-10123-01
     1     SG @TIMECARD_LIB.TIMECARD(SCH_1):SG   I179 @TIMECARD_LIB.TIMECARD(SCH_1):PAGE12
     2 SMA2_SIG_IO_CONN @TIMECARD_LIB.TIMECARD(SCH_1):SMA2_SIG_IO_CONN   I179 @TIMECARD_LIB.TIMECARD(SCH_1):PAGE12
     3 SMA1_SIG_IO_CONN @TIMECARD_LIB.TIMECARD(SCH_1):SMA1_SIG_IO_CONN   I179 @TIMECARD_LIB.TIMECARD(SCH_1):PAGE12
     4     NC     NC   I179 @TIMECARD_LIB.TIMECARD(SCH_1):PAGE12

 CR5 DIODE_4_V1-G122-10123-01
     1     SG @TIMECARD_LIB.TIMECARD(SCH_1):SG    I42 @TIMECARD_LIB.TIMECARD(SCH_1):PAGE12
     2 SMA4_SIG_IO_CONN @TIMECARD_LIB.TIMECARD(SCH_1):SMA4_SIG_IO_CONN    I42 @TIMECARD_LIB.TIMECARD(SCH_1):PAGE12
     3 SMA3_SIG_IO_CONN @TIMECARD_LIB.TIMECARD(SCH_1):SMA3_SIG_IO_CONN    I42 @TIMECARD_LIB.TIMECARD(SCH_1):PAGE12
     4     NC     NC    I42 @TIMECARD_LIB.TIMECARD(SCH_1):PAGE12

 CR6 DIODE_4_V1-G122-10123-01
     1     SG @TIMECARD_LIB.TIMECARD(SCH_1):SG   I443 @TIMECARD_LIB.TIMECARD(SCH_1):PAGE127
     2 FT4232_FPGA_TMS @TIMECARD_LIB.TIMECARD(SCH_1):FT4232_FPGA_TMS   I443 @TIMECARD_LIB.TIMECARD(SCH_1):PAGE127
     3 FT4232_FPGA_TDI @TIMECARD_LIB.TIMECARD(SCH_1):FT4232_FPGA_TDI   I443 @TIMECARD_LIB.TIMECARD(SCH_1):PAGE127
     4     NC     NC   I443 @TIMECARD_LIB.TIMECARD(SCH_1):PAGE127

 CR7 DIODE_4_V1-G122-10123-01
     1     SG @TIMECARD_LIB.TIMECARD(SCH_1):SG   I442 @TIMECARD_LIB.TIMECARD(SCH_1):PAGE127
     2 FT4232_FPGA_TCK @TIMECARD_LIB.TIMECARD(SCH_1):FT4232_FPGA_TCK   I442 @TIMECARD_LIB.TIMECARD(SCH_1):PAGE127
     3 FT4232_FPGA_TDO @TIMECARD_LIB.TIMECARD(SCH_1):FT4232_FPGA_TDO   I442 @TIMECARD_LIB.TIMECARD(SCH_1):PAGE127
     4     NC     NC   I442 @TIMECARD_LIB.TIMECARD(SCH_1):PAGE127

CR10 DIODE_2E-G122-10190-01
     C XP12R0V_IN @TIMECARD_LIB.TIMECARD(SCH_1):XP12R0V_IN   I159 @TIMECARD_LIB.TIMECARD(SCH_1):PAGE15
     A     SG @TIMECARD_LIB.TIMECARD(SCH_1):SG   I159 @TIMECARD_LIB.TIMECARD(SCH_1):PAGE15

CR12 DIODE_3F-G122-10080-01
     1 XP12R0V_PCIE @TIMECARD_LIB.TIMECARD(SCH_1):XP12R0V_PCIE   I239 @TIMECARD_LIB.TIMECARD(SCH_1):PAGE15
     2 XP12R0V_EXT @TIMECARD_LIB.TIMECARD(SCH_1):XP12R0V_EXT   I239 @TIMECARD_LIB.TIMECARD(SCH_1):PAGE15
     3 XP12R0V_IN @TIMECARD_LIB.TIMECARD(SCH_1):XP12R0V_IN   I239 @TIMECARD_LIB.TIMECARD(SCH_1):PAGE15

 DS1 OPTICAL-G170-10143-01
     A UNNAMED_14_OPTICAL_I12_A @TIMECARD_LIB.TIMECARD(SCH_1):UNNAMED_14_OPTICAL_I12_A    I12 @TIMECARD_LIB.TIMECARD(SCH_1):PAGE14
     C LED_DATOUT3 @TIMECARD_LIB.TIMECARD(SCH_1):LED_DATOUT3    I12 @TIMECARD_LIB.TIMECARD(SCH_1):PAGE14

 DS2 OPTICAL-G170-10143-01
     A UNNAMED_14_OPTICAL_I11_A @TIMECARD_LIB.TIMECARD(SCH_1):UNNAMED_14_OPTICAL_I11_A    I11 @TIMECARD_LIB.TIMECARD(SCH_1):PAGE14
     C LED_DATOUT2 @TIMECARD_LIB.TIMECARD(SCH_1):LED_DATOUT2    I11 @TIMECARD_LIB.TIMECARD(SCH_1):PAGE14

 DS3 OPTICAL-G170-10143-01
     A UNNAMED_14_OPTICAL_I136_A @TIMECARD_LIB.TIMECARD(SCH_1):UNNAMED_14_OPTICAL_I136_A   I136 @TIMECARD_LIB.TIMECARD(SCH_1):PAGE14
     C LED_DATOUT1 @TIMECARD_LIB.TIMECARD(SCH_1):LED_DATOUT1   I136 @TIMECARD_LIB.TIMECARD(SCH_1):PAGE14

 DS4 OPTICAL-G170-10143-01
     A UNNAMED_14_OPTICAL_I137_A @TIMECARD_LIB.TIMECARD(SCH_1):UNNAMED_14_OPTICAL_I137_A   I137 @TIMECARD_LIB.TIMECARD(SCH_1):PAGE14
     C LED_DATOUT0 @TIMECARD_LIB.TIMECARD(SCH_1):LED_DATOUT0   I137 @TIMECARD_LIB.TIMECARD(SCH_1):PAGE14

 DS5 OPTICAL-G170-10143-01
     A UNNAMED_14_OPTICAL_I143_A @TIMECARD_LIB.TIMECARD(SCH_1):UNNAMED_14_OPTICAL_I143_A   I143 @TIMECARD_LIB.TIMECARD(SCH_1):PAGE14
     C     SG @TIMECARD_LIB.TIMECARD(SCH_1):SG   I143 @TIMECARD_LIB.TIMECARD(SCH_1):PAGE14

 DS6 OPTICAL-G170-10143-01
     A UNNAMED_14_OPTICAL_I140_A @TIMECARD_LIB.TIMECARD(SCH_1):UNNAMED_14_OPTICAL_I140_A   I140 @TIMECARD_LIB.TIMECARD(SCH_1):PAGE14
     C     SG @TIMECARD_LIB.TIMECARD(SCH_1):SG   I140 @TIMECARD_LIB.TIMECARD(SCH_1):PAGE14

 DS7 OPTICAL-G170-10143-01
     A UNNAMED_14_OPTICAL_I141_A @TIMECARD_LIB.TIMECARD(SCH_1):UNNAMED_14_OPTICAL_I141_A   I141 @TIMECARD_LIB.TIMECARD(SCH_1):PAGE14
     C     SG @TIMECARD_LIB.TIMECARD(SCH_1):SG   I141 @TIMECARD_LIB.TIMECARD(SCH_1):PAGE14

 DS8 OPTICAL-G170-10143-01
     A UNNAMED_14_OPTICAL_I142_A @TIMECARD_LIB.TIMECARD(SCH_1):UNNAMED_14_OPTICAL_I142_A   I142 @TIMECARD_LIB.TIMECARD(SCH_1):PAGE14
     C     SG @TIMECARD_LIB.TIMECARD(SCH_1):SG   I142 @TIMECARD_LIB.TIMECARD(SCH_1):PAGE14

 DS9 OPTICAL-G170-10143-01
     A UNNAMED_14_OPTICAL_I292_A @TIMECARD_LIB.TIMECARD(SCH_1):UNNAMED_14_OPTICAL_I292_A   I292 @TIMECARD_LIB.TIMECARD(SCH_1):PAGE14
     C     SG @TIMECARD_LIB.TIMECARD(SCH_1):SG   I292 @TIMECARD_LIB.TIMECARD(SCH_1):PAGE14

DS10 OPTICAL-G170-10143-01
     A UNNAMED_14_OPTICAL_I138_A @TIMECARD_LIB.TIMECARD(SCH_1):UNNAMED_14_OPTICAL_I138_A   I138 @TIMECARD_LIB.TIMECARD(SCH_1):PAGE14
     C FPGA_USR_LED1 @TIMECARD_LIB.TIMECARD(SCH_1):FPGA_USR_LED1   I138 @TIMECARD_LIB.TIMECARD(SCH_1):PAGE14

DS11 OPTICAL-G170-10143-01
     A UNNAMED_14_OPTICAL_I139_A @TIMECARD_LIB.TIMECARD(SCH_1):UNNAMED_14_OPTICAL_I139_A   I139 @TIMECARD_LIB.TIMECARD(SCH_1):PAGE14
     C FPGA_USR_LED0 @TIMECARD_LIB.TIMECARD(SCH_1):FPGA_USR_LED0   I139 @TIMECARD_LIB.TIMECARD(SCH_1):PAGE14

DS12 OPTICAL-G170-10143-01
     A UNNAMED_14_OPTICAL_I289_A @TIMECARD_LIB.TIMECARD(SCH_1):UNNAMED_14_OPTICAL_I289_A   I289 @TIMECARD_LIB.TIMECARD(SCH_1):PAGE14
     C     SG @TIMECARD_LIB.TIMECARD(SCH_1):SG   I289 @TIMECARD_LIB.TIMECARD(SCH_1):PAGE14

DS14 LED_4P_V14-G170-10189-01
     4 UNNAMED_14_LED4PV14_I265_4 @TIMECARD_LIB.TIMECARD(SCH_1):UNNAMED_14_LED4PV14_I265_4   I265 @TIMECARD_LIB.TIMECARD(SCH_1):PAGE14
     3 UNNAMED_14_LED4PV14_I265_3 @TIMECARD_LIB.TIMECARD(SCH_1):UNNAMED_14_LED4PV14_I265_3   I265 @TIMECARD_LIB.TIMECARD(SCH_1):PAGE14
     1 UNNAMED_14_LED4PV14_I265_1 @TIMECARD_LIB.TIMECARD(SCH_1):UNNAMED_14_LED4PV14_I265_1   I265 @TIMECARD_LIB.TIMECARD(SCH_1):PAGE14
     2 XP3R3V_FPGA @TIMECARD_LIB.TIMECARD(SCH_1):XP3R3V_FPGA   I265 @TIMECARD_LIB.TIMECARD(SCH_1):PAGE14

DS15 LED_4P_V14-G170-10189-01
     4 UNNAMED_14_LED4PV14_I266_4 @TIMECARD_LIB.TIMECARD(SCH_1):UNNAMED_14_LED4PV14_I266_4   I266 @TIMECARD_LIB.TIMECARD(SCH_1):PAGE14
     3 UNNAMED_14_LED4PV14_I266_3 @TIMECARD_LIB.TIMECARD(SCH_1):UNNAMED_14_LED4PV14_I266_3   I266 @TIMECARD_LIB.TIMECARD(SCH_1):PAGE14
     1 UNNAMED_14_LED4PV14_I266_1 @TIMECARD_LIB.TIMECARD(SCH_1):UNNAMED_14_LED4PV14_I266_1   I266 @TIMECARD_LIB.TIMECARD(SCH_1):PAGE14
     2 XP3R3V_FPGA @TIMECARD_LIB.TIMECARD(SCH_1):XP3R3V_FPGA   I266 @TIMECARD_LIB.TIMECARD(SCH_1):PAGE14

DS16 LED_4P_V14-G170-10189-01
     4 UNNAMED_14_LED4PV14_I267_4 @TIMECARD_LIB.TIMECARD(SCH_1):UNNAMED_14_LED4PV14_I267_4   I267 @TIMECARD_LIB.TIMECARD(SCH_1):PAGE14
     3 UNNAMED_14_LED4PV14_I267_3 @TIMECARD_LIB.TIMECARD(SCH_1):UNNAMED_14_LED4PV14_I267_3   I267 @TIMECARD_LIB.TIMECARD(SCH_1):PAGE14
     1 UNNAMED_14_LED4PV14_I267_1 @TIMECARD_LIB.TIMECARD(SCH_1):UNNAMED_14_LED4PV14_I267_1   I267 @TIMECARD_LIB.TIMECARD(SCH_1):PAGE14
     2 XP3R3V_FPGA @TIMECARD_LIB.TIMECARD(SCH_1):XP3R3V_FPGA   I267 @TIMECARD_LIB.TIMECARD(SCH_1):PAGE14

DS17 LED_4P_V14-G170-10189-01
     4 UNNAMED_14_LED4PV14_I268_4 @TIMECARD_LIB.TIMECARD(SCH_1):UNNAMED_14_LED4PV14_I268_4   I268 @TIMECARD_LIB.TIMECARD(SCH_1):PAGE14
     3 UNNAMED_14_LED4PV14_I268_3 @TIMECARD_LIB.TIMECARD(SCH_1):UNNAMED_14_LED4PV14_I268_3   I268 @TIMECARD_LIB.TIMECARD(SCH_1):PAGE14
     1 UNNAMED_14_LED4PV14_I268_1 @TIMECARD_LIB.TIMECARD(SCH_1):UNNAMED_14_LED4PV14_I268_1   I268 @TIMECARD_LIB.TIMECARD(SCH_1):PAGE14
     2 XP3R3V_FPGA @TIMECARD_LIB.TIMECARD(SCH_1):XP3R3V_FPGA   I268 @TIMECARD_LIB.TIMECARD(SCH_1):PAGE14

DS18 LED_4P_V14-G170-10189-01
     4 UNNAMED_14_LED4PV14_I269_4 @TIMECARD_LIB.TIMECARD(SCH_1):UNNAMED_14_LED4PV14_I269_4   I269 @TIMECARD_LIB.TIMECARD(SCH_1):PAGE14
     3 UNNAMED_14_LED4PV14_I269_3 @TIMECARD_LIB.TIMECARD(SCH_1):UNNAMED_14_LED4PV14_I269_3   I269 @TIMECARD_LIB.TIMECARD(SCH_1):PAGE14
     1 UNNAMED_14_LED4PV14_I269_1 @TIMECARD_LIB.TIMECARD(SCH_1):UNNAMED_14_LED4PV14_I269_1   I269 @TIMECARD_LIB.TIMECARD(SCH_1):PAGE14
     2 XP3R3V_FPGA @TIMECARD_LIB.TIMECARD(SCH_1):XP3R3V_FPGA   I269 @TIMECARD_LIB.TIMECARD(SCH_1):PAGE14

DS19 OPTICAL-G170-10143-01
     A UNNAMED_14_OPTICAL_I191_A @TIMECARD_LIB.TIMECARD(SCH_1):UNNAMED_14_OPTICAL_I191_A   I191 @TIMECARD_LIB.TIMECARD(SCH_1):PAGE14
     C     SG @TIMECARD_LIB.TIMECARD(SCH_1):SG   I191 @TIMECARD_LIB.TIMECARD(SCH_1):PAGE14

DS20 OPTICAL-G170-10143-01
     A UNNAMED_14_OPTICAL_I194_A @TIMECARD_LIB.TIMECARD(SCH_1):UNNAMED_14_OPTICAL_I194_A   I194 @TIMECARD_LIB.TIMECARD(SCH_1):PAGE14
     C     SG @TIMECARD_LIB.TIMECARD(SCH_1):SG   I194 @TIMECARD_LIB.TIMECARD(SCH_1):PAGE14

 FU1 FUSE-G280-10012-01,2.5A
     1 XP12R0V_IN @TIMECARD_LIB.TIMECARD(SCH_1):XP12R0V_IN   I223 @TIMECARD_LIB.TIMECARD(SCH_1):PAGE15
     2 XP12R0V @TIMECARD_LIB.TIMECARD(SCH_1):XP12R0V   I223 @TIMECARD_LIB.TIMECARD(SCH_1):PAGE15

 FU3 FUSE-G280-10049-01,1A
     1 UNNAMED_527_FUSE_I244_1 @TIMECARD_LIB.TIMECARD(SCH_1):UNNAMED_527_FUSE_I244_1   I244 @TIMECARD_LIB.TIMECARD(SCH_1):PAGE527
     2 XP5R0V_MAC_USB @TIMECARD_LIB.TIMECARD(SCH_1):XP5R0V_MAC_USB   I244 @TIMECARD_LIB.TIMECARD(SCH_1):PAGE527

 GF1 CONN_64P_GF-S_M_EF64_PCIE_P039A
    B1 XP12R0V_PCIE @TIMECARD_LIB.TIMECARD(SCH_1):XP12R0V_PCIE    I61 @TIMECARD_LIB.TIMECARD(SCH_1):PAGE3
    B2 XP12R0V_PCIE @TIMECARD_LIB.TIMECARD(SCH_1):XP12R0V_PCIE    I61 @TIMECARD_LIB.TIMECARD(SCH_1):PAGE3
    B3 XP12R0V_PCIE @TIMECARD_LIB.TIMECARD(SCH_1):XP12R0V_PCIE    I61 @TIMECARD_LIB.TIMECARD(SCH_1):PAGE3
    B4     SG @TIMECARD_LIB.TIMECARD(SCH_1):SG    I61 @TIMECARD_LIB.TIMECARD(SCH_1):PAGE3
    B5 PCIE_CONN_SMCLK @TIMECARD_LIB.TIMECARD(SCH_1):PCIE_CONN_SMCLK    I61 @TIMECARD_LIB.TIMECARD(SCH_1):PAGE3
    B6 PCIE_CONN_SMDAT @TIMECARD_LIB.TIMECARD(SCH_1):PCIE_CONN_SMDAT    I61 @TIMECARD_LIB.TIMECARD(SCH_1):PAGE3
    B7     SG @TIMECARD_LIB.TIMECARD(SCH_1):SG    I61 @TIMECARD_LIB.TIMECARD(SCH_1):PAGE3
    B8 XP3R3V_PCIE @TIMECARD_LIB.TIMECARD(SCH_1):XP3R3V_PCIE    I61 @TIMECARD_LIB.TIMECARD(SCH_1):PAGE3
    B9     NC     NC    I61 @TIMECARD_LIB.TIMECARD(SCH_1):PAGE3
   B10 XP3R3V_AUX_PCIE @TIMECARD_LIB.TIMECARD(SCH_1):XP3R3V_AUX_PCIE    I61 @TIMECARD_LIB.TIMECARD(SCH_1):PAGE3
   B11     NC     NC    I61 @TIMECARD_LIB.TIMECARD(SCH_1):PAGE3
   B12     NC     NC    I61 @TIMECARD_LIB.TIMECARD(SCH_1):PAGE3
   B13     SG @TIMECARD_LIB.TIMECARD(SCH_1):SG    I61 @TIMECARD_LIB.TIMECARD(SCH_1):PAGE3
   B14 CPU_TX_PCIE_MGT_0_RXP @TIMECARD_LIB.TIMECARD(SCH_1):CPU_TX_PCIE_MGT_0_RXP    I61 @TIMECARD_LIB.TIMECARD(SCH_1):PAGE3
   B15 CPU_TX_PCIE_MGT_0_RXN @TIMECARD_LIB.TIMECARD(SCH_1):CPU_TX_PCIE_MGT_0_RXN    I61 @TIMECARD_LIB.TIMECARD(SCH_1):PAGE3
   B16     SG @TIMECARD_LIB.TIMECARD(SCH_1):SG    I61 @TIMECARD_LIB.TIMECARD(SCH_1):PAGE3
   B17 UNNAMED_3_CONN64PGF_I61_PRSNT21 @TIMECARD_LIB.TIMECARD(SCH_1):UNNAMED_3_CONN64PGF_I61_PRSNT21    I61 @TIMECARD_LIB.TIMECARD(SCH_1):PAGE3
   B18     SG @TIMECARD_LIB.TIMECARD(SCH_1):SG    I61 @TIMECARD_LIB.TIMECARD(SCH_1):PAGE3
   B19 CPU_TX_PCIE_MGT_1_RXP @TIMECARD_LIB.TIMECARD(SCH_1):CPU_TX_PCIE_MGT_1_RXP    I61 @TIMECARD_LIB.TIMECARD(SCH_1):PAGE3
   B20 CPU_TX_PCIE_MGT_1_RXN @TIMECARD_LIB.TIMECARD(SCH_1):CPU_TX_PCIE_MGT_1_RXN    I61 @TIMECARD_LIB.TIMECARD(SCH_1):PAGE3
   B21     SG @TIMECARD_LIB.TIMECARD(SCH_1):SG    I61 @TIMECARD_LIB.TIMECARD(SCH_1):PAGE3
   B22     SG @TIMECARD_LIB.TIMECARD(SCH_1):SG    I61 @TIMECARD_LIB.TIMECARD(SCH_1):PAGE3
   B23 CPU_TX_PCIE_MGT_2_RXP @TIMECARD_LIB.TIMECARD(SCH_1):CPU_TX_PCIE_MGT_2_RXP    I61 @TIMECARD_LIB.TIMECARD(SCH_1):PAGE3
   B24 CPU_TX_PCIE_MGT_2_RXN @TIMECARD_LIB.TIMECARD(SCH_1):CPU_TX_PCIE_MGT_2_RXN    I61 @TIMECARD_LIB.TIMECARD(SCH_1):PAGE3
   B25     SG @TIMECARD_LIB.TIMECARD(SCH_1):SG    I61 @TIMECARD_LIB.TIMECARD(SCH_1):PAGE3
   B26     SG @TIMECARD_LIB.TIMECARD(SCH_1):SG    I61 @TIMECARD_LIB.TIMECARD(SCH_1):PAGE3
   B27 CPU_TX_PCIE_MGT_3_RXP @TIMECARD_LIB.TIMECARD(SCH_1):CPU_TX_PCIE_MGT_3_RXP    I61 @TIMECARD_LIB.TIMECARD(SCH_1):PAGE3
   B28 CPU_TX_PCIE_MGT_3_RXN @TIMECARD_LIB.TIMECARD(SCH_1):CPU_TX_PCIE_MGT_3_RXN    I61 @TIMECARD_LIB.TIMECARD(SCH_1):PAGE3
   B29     SG @TIMECARD_LIB.TIMECARD(SCH_1):SG    I61 @TIMECARD_LIB.TIMECARD(SCH_1):PAGE3
   B30     NC     NC    I61 @TIMECARD_LIB.TIMECARD(SCH_1):PAGE3
   B31 UNNAMED_3_CONN64PGF_I61_PRSNT22 @TIMECARD_LIB.TIMECARD(SCH_1):UNNAMED_3_CONN64PGF_I61_PRSNT22    I61 @TIMECARD_LIB.TIMECARD(SCH_1):PAGE3
   B32     SG @TIMECARD_LIB.TIMECARD(SCH_1):SG    I61 @TIMECARD_LIB.TIMECARD(SCH_1):PAGE3
    A1 CARD_PRESENT @TIMECARD_LIB.TIMECARD(SCH_1):CARD_PRESENT    I61 @TIMECARD_LIB.TIMECARD(SCH_1):PAGE3
    A2 XP12R0V_PCIE @TIMECARD_LIB.TIMECARD(SCH_1):XP12R0V_PCIE    I61 @TIMECARD_LIB.TIMECARD(SCH_1):PAGE3
    A3 XP12R0V_PCIE @TIMECARD_LIB.TIMECARD(SCH_1):XP12R0V_PCIE    I61 @TIMECARD_LIB.TIMECARD(SCH_1):PAGE3
    A4     SG @TIMECARD_LIB.TIMECARD(SCH_1):SG    I61 @TIMECARD_LIB.TIMECARD(SCH_1):PAGE3
    A5 PCIE_CONN_TCK @TIMECARD_LIB.TIMECARD(SCH_1):PCIE_CONN_TCK    I61 @TIMECARD_LIB.TIMECARD(SCH_1):PAGE3
    A6 PCIE_CONN_TDI @TIMECARD_LIB.TIMECARD(SCH_1):PCIE_CONN_TDI    I61 @TIMECARD_LIB.TIMECARD(SCH_1):PAGE3
    A7 PCIE_CONN_TDO @TIMECARD_LIB.TIMECARD(SCH_1):PCIE_CONN_TDO    I61 @TIMECARD_LIB.TIMECARD(SCH_1):PAGE3
    A8 PCIE_CONN_TMS @TIMECARD_LIB.TIMECARD(SCH_1):PCIE_CONN_TMS    I61 @TIMECARD_LIB.TIMECARD(SCH_1):PAGE3
    A9 XP3R3V_PCIE @TIMECARD_LIB.TIMECARD(SCH_1):XP3R3V_PCIE    I61 @TIMECARD_LIB.TIMECARD(SCH_1):PAGE3
   A10 XP3R3V_PCIE @TIMECARD_LIB.TIMECARD(SCH_1):XP3R3V_PCIE    I61 @TIMECARD_LIB.TIMECARD(SCH_1):PAGE3
   A11 PCIE_CONN_PERST_N @TIMECARD_LIB.TIMECARD(SCH_1):PCIE_CONN_PERST_N    I61 @TIMECARD_LIB.TIMECARD(SCH_1):PAGE3
   A12     SG @TIMECARD_LIB.TIMECARD(SCH_1):SG    I61 @TIMECARD_LIB.TIMECARD(SCH_1):PAGE3
   A13 C_PCIEREFCLKP @TIMECARD_LIB.TIMECARD(SCH_1):C_PCIEREFCLKP    I61 @TIMECARD_LIB.TIMECARD(SCH_1):PAGE3
   A14 C_PCIEREFCLKN @TIMECARD_LIB.TIMECARD(SCH_1):C_PCIEREFCLKN    I61 @TIMECARD_LIB.TIMECARD(SCH_1):PAGE3
   A15     SG @TIMECARD_LIB.TIMECARD(SCH_1):SG    I61 @TIMECARD_LIB.TIMECARD(SCH_1):PAGE3
   A16 C_CPU_RX_PCIE_MGT0_TXP @TIMECARD_LIB.TIMECARD(SCH_1):C_CPU_RX_PCIE_MGT0_TXP    I61 @TIMECARD_LIB.TIMECARD(SCH_1):PAGE3
   A17 C_CPU_RX_PCIE_MGT0_TXN @TIMECARD_LIB.TIMECARD(SCH_1):C_CPU_RX_PCIE_MGT0_TXN    I61 @TIMECARD_LIB.TIMECARD(SCH_1):PAGE3
   A18     SG @TIMECARD_LIB.TIMECARD(SCH_1):SG    I61 @TIMECARD_LIB.TIMECARD(SCH_1):PAGE3
   A19     NC     NC    I61 @TIMECARD_LIB.TIMECARD(SCH_1):PAGE3
   A20     SG @TIMECARD_LIB.TIMECARD(SCH_1):SG    I61 @TIMECARD_LIB.TIMECARD(SCH_1):PAGE3
   A21 C_CPU_RX_PCIE_MGT1_TXP @TIMECARD_LIB.TIMECARD(SCH_1):C_CPU_RX_PCIE_MGT1_TXP    I61 @TIMECARD_LIB.TIMECARD(SCH_1):PAGE3
   A22 C_CPU_RX_PCIE_MGT1_TXN @TIMECARD_LIB.TIMECARD(SCH_1):C_CPU_RX_PCIE_MGT1_TXN    I61 @TIMECARD_LIB.TIMECARD(SCH_1):PAGE3
   A23     SG @TIMECARD_LIB.TIMECARD(SCH_1):SG    I61 @TIMECARD_LIB.TIMECARD(SCH_1):PAGE3
   A24     SG @TIMECARD_LIB.TIMECARD(SCH_1):SG    I61 @TIMECARD_LIB.TIMECARD(SCH_1):PAGE3
   A25 C_CPU_RX_PCIE_MGT2_TXP @TIMECARD_LIB.TIMECARD(SCH_1):C_CPU_RX_PCIE_MGT2_TXP    I61 @TIMECARD_LIB.TIMECARD(SCH_1):PAGE3
   A26 C_CPU_RX_PCIE_MGT2_TXN @TIMECARD_LIB.TIMECARD(SCH_1):C_CPU_RX_PCIE_MGT2_TXN    I61 @TIMECARD_LIB.TIMECARD(SCH_1):PAGE3
   A27     SG @TIMECARD_LIB.TIMECARD(SCH_1):SG    I61 @TIMECARD_LIB.TIMECARD(SCH_1):PAGE3
   A28     SG @TIMECARD_LIB.TIMECARD(SCH_1):SG    I61 @TIMECARD_LIB.TIMECARD(SCH_1):PAGE3
   A29 C_CPU_RX_PCIE_MGT3_TXP @TIMECARD_LIB.TIMECARD(SCH_1):C_CPU_RX_PCIE_MGT3_TXP    I61 @TIMECARD_LIB.TIMECARD(SCH_1):PAGE3
   A30 C_CPU_RX_PCIE_MGT3_TXN @TIMECARD_LIB.TIMECARD(SCH_1):C_CPU_RX_PCIE_MGT3_TXN    I61 @TIMECARD_LIB.TIMECARD(SCH_1):PAGE3
   A31     SG @TIMECARD_LIB.TIMECARD(SCH_1):SG    I61 @TIMECARD_LIB.TIMECARD(SCH_1):PAGE3
   A32     NC     NC    I61 @TIMECARD_LIB.TIMECARD(SCH_1):PAGE3

  J1 CONN_JACK_1P_GH4_S_TH-G200-130A
     1 SMA3_SIG_IO_CONN @TIMECARD_LIB.TIMECARD(SCH_1):SMA3_SIG_IO_CONN   I290 @TIMECARD_LIB.TIMECARD(SCH_1):PAGE12
   GH1     SG @TIMECARD_LIB.TIMECARD(SCH_1):SG   I290 @TIMECARD_LIB.TIMECARD(SCH_1):PAGE12
   GH2     SG @TIMECARD_LIB.TIMECARD(SCH_1):SG   I290 @TIMECARD_LIB.TIMECARD(SCH_1):PAGE12
   GH3     SG @TIMECARD_LIB.TIMECARD(SCH_1):SG   I290 @TIMECARD_LIB.TIMECARD(SCH_1):PAGE12
   GH4     SG @TIMECARD_LIB.TIMECARD(SCH_1):SG   I290 @TIMECARD_LIB.TIMECARD(SCH_1):PAGE12

  J2 CONN_JACK_1P_GH4_S_TH-G200-130A
     1 SMA4_SIG_IO_CONN @TIMECARD_LIB.TIMECARD(SCH_1):SMA4_SIG_IO_CONN   I294 @TIMECARD_LIB.TIMECARD(SCH_1):PAGE12
   GH1     SG @TIMECARD_LIB.TIMECARD(SCH_1):SG   I294 @TIMECARD_LIB.TIMECARD(SCH_1):PAGE12
   GH2     SG @TIMECARD_LIB.TIMECARD(SCH_1):SG   I294 @TIMECARD_LIB.TIMECARD(SCH_1):PAGE12
   GH3     SG @TIMECARD_LIB.TIMECARD(SCH_1):SG   I294 @TIMECARD_LIB.TIMECARD(SCH_1):PAGE12
   GH4     SG @TIMECARD_LIB.TIMECARD(SCH_1):SG   I294 @TIMECARD_LIB.TIMECARD(SCH_1):PAGE12

  J3 CONN_JACK_1P_GH4_S_TH-G200-130A
     1 SMA1_SIG_IO_CONN @TIMECARD_LIB.TIMECARD(SCH_1):SMA1_SIG_IO_CONN   I297 @TIMECARD_LIB.TIMECARD(SCH_1):PAGE12
   GH1     SG @TIMECARD_LIB.TIMECARD(SCH_1):SG   I297 @TIMECARD_LIB.TIMECARD(SCH_1):PAGE12
   GH2     SG @TIMECARD_LIB.TIMECARD(SCH_1):SG   I297 @TIMECARD_LIB.TIMECARD(SCH_1):PAGE12
   GH3     SG @TIMECARD_LIB.TIMECARD(SCH_1):SG   I297 @TIMECARD_LIB.TIMECARD(SCH_1):PAGE12
   GH4     SG @TIMECARD_LIB.TIMECARD(SCH_1):SG   I297 @TIMECARD_LIB.TIMECARD(SCH_1):PAGE12

  J4 CONN_JACK_1P_GH4_S_TH-G200-130A
     1 SMA2_SIG_IO_CONN @TIMECARD_LIB.TIMECARD(SCH_1):SMA2_SIG_IO_CONN   I300 @TIMECARD_LIB.TIMECARD(SCH_1):PAGE12
   GH1     SG @TIMECARD_LIB.TIMECARD(SCH_1):SG   I300 @TIMECARD_LIB.TIMECARD(SCH_1):PAGE12
   GH2     SG @TIMECARD_LIB.TIMECARD(SCH_1):SG   I300 @TIMECARD_LIB.TIMECARD(SCH_1):PAGE12
   GH3     SG @TIMECARD_LIB.TIMECARD(SCH_1):SG   I300 @TIMECARD_LIB.TIMECARD(SCH_1):PAGE12
   GH4     SG @TIMECARD_LIB.TIMECARD(SCH_1):SG   I300 @TIMECARD_LIB.TIMECARD(SCH_1):PAGE12

  J5 CONN_HDR_2X6_F_S_SMT-G200-1313A
     1 UNNAMED_16_CONNHDR2X6FSSMT_I161 @TIMECARD_LIB.TIMECARD(SCH_1):UNNAMED_16_CONNHDR2X6FSSMT_I1614_1  I1614 @TIMECARD_LIB.TIMECARD(SCH_1):PAGE16
     3 UNNAMED_16_CONNHDR2X6FSSMT_I1_2 @TIMECARD_LIB.TIMECARD(SCH_1):UNNAMED_16_CONNHDR2X6FSSMT_I1614_3  I1614 @TIMECARD_LIB.TIMECARD(SCH_1):PAGE16
     5 UNNAMED_16_CONNHDR2X6FSSMT_I1_6 @TIMECARD_LIB.TIMECARD(SCH_1):UNNAMED_16_CONNHDR2X6FSSMT_I1614_5  I1614 @TIMECARD_LIB.TIMECARD(SCH_1):PAGE16
     7 UNNAMED_16_CONNHDR2X6FSSMT_I1_4 @TIMECARD_LIB.TIMECARD(SCH_1):UNNAMED_16_CONNHDR2X6FSSMT_I1614_7  I1614 @TIMECARD_LIB.TIMECARD(SCH_1):PAGE16
     9     SG @TIMECARD_LIB.TIMECARD(SCH_1):SG  I1614 @TIMECARD_LIB.TIMECARD(SCH_1):PAGE16
    11 XP3R3V_FPGA @TIMECARD_LIB.TIMECARD(SCH_1):XP3R3V_FPGA  I1614 @TIMECARD_LIB.TIMECARD(SCH_1):PAGE16
     2 UNNAMED_16_CONNHDR2X6FSSMT_I1_1 @TIMECARD_LIB.TIMECARD(SCH_1):UNNAMED_16_CONNHDR2X6FSSMT_I1614_2  I1614 @TIMECARD_LIB.TIMECARD(SCH_1):PAGE16
     4 UNNAMED_16_CONNHDR2X6FSSMT_I1_3 @TIMECARD_LIB.TIMECARD(SCH_1):UNNAMED_16_CONNHDR2X6FSSMT_I1614_4  I1614 @TIMECARD_LIB.TIMECARD(SCH_1):PAGE16
     6 UNNAMED_16_CONNHDR2X6FSSMT_I1_7 @TIMECARD_LIB.TIMECARD(SCH_1):UNNAMED_16_CONNHDR2X6FSSMT_I1614_6  I1614 @TIMECARD_LIB.TIMECARD(SCH_1):PAGE16
     8 UNNAMED_16_CONNHDR2X6FSSMT_I1_5 @TIMECARD_LIB.TIMECARD(SCH_1):UNNAMED_16_CONNHDR2X6FSSMT_I1614_8  I1614 @TIMECARD_LIB.TIMECARD(SCH_1):PAGE16
    10     SG @TIMECARD_LIB.TIMECARD(SCH_1):SG  I1614 @TIMECARD_LIB.TIMECARD(SCH_1):PAGE16
    12 XP3R3V_FPGA @TIMECARD_LIB.TIMECARD(SCH_1):XP3R3V_FPGA  I1614 @TIMECARD_LIB.TIMECARD(SCH_1):PAGE16

  J9 CONN_HDR_2X2_M_S_SMT-G200-1068A
     1 UNNAMED_5_CONNHDR2X2MSSMT_I126_ @TIMECARD_LIB.TIMECARD(SCH_1):UNNAMED_5_CONNHDR2X2MSSMT_I126_1   I126 @TIMECARD_LIB.TIMECARD(SCH_1):PAGE5
     2 EEPROM_SDA @TIMECARD_LIB.TIMECARD(SCH_1):EEPROM_SDA   I126 @TIMECARD_LIB.TIMECARD(SCH_1):PAGE5
     3 UNNAMED_5_CONNHDR2X2MSSMT_I12_1 @TIMECARD_LIB.TIMECARD(SCH_1):UNNAMED_5_CONNHDR2X2MSSMT_I126_3   I126 @TIMECARD_LIB.TIMECARD(SCH_1):PAGE5
     4 EEPROM_SCL @TIMECARD_LIB.TIMECARD(SCH_1):EEPROM_SCL   I126 @TIMECARD_LIB.TIMECARD(SCH_1):PAGE5

 J10 G200_10283_01-G200-10283-01
     1 FT4232_CHD_TX @TIMECARD_LIB.TIMECARD(SCH_1):FT4232_CHD_TX   I173 @TIMECARD_LIB.TIMECARD(SCH_1):PAGE524
     2 DBG_UART_MAC_RX @TIMECARD_LIB.TIMECARD(SCH_1):DBG_UART_MAC_RX   I173 @TIMECARD_LIB.TIMECARD(SCH_1):PAGE524
     3 FT4232_CHD_TX @TIMECARD_LIB.TIMECARD(SCH_1):FT4232_CHD_TX   I173 @TIMECARD_LIB.TIMECARD(SCH_1):PAGE524
     4 DBG_UART_GPS_RXD @TIMECARD_LIB.TIMECARD(SCH_1):DBG_UART_GPS_RXD   I173 @TIMECARD_LIB.TIMECARD(SCH_1):PAGE524
     5 FT4232_CHD_RX @TIMECARD_LIB.TIMECARD(SCH_1):FT4232_CHD_RX   I173 @TIMECARD_LIB.TIMECARD(SCH_1):PAGE524
     6 DBG_UART_MAC_TX @TIMECARD_LIB.TIMECARD(SCH_1):DBG_UART_MAC_TX   I173 @TIMECARD_LIB.TIMECARD(SCH_1):PAGE524
     7 FT4232_CHD_RX @TIMECARD_LIB.TIMECARD(SCH_1):FT4232_CHD_RX   I173 @TIMECARD_LIB.TIMECARD(SCH_1):PAGE524
     8 DBG_UART_GPS_TXD @TIMECARD_LIB.TIMECARD(SCH_1):DBG_UART_GPS_TXD   I173 @TIMECARD_LIB.TIMECARD(SCH_1):PAGE524
     9     SG @TIMECARD_LIB.TIMECARD(SCH_1):SG   I173 @TIMECARD_LIB.TIMECARD(SCH_1):PAGE524
    10 FPGA_CFG_INIT_N @TIMECARD_LIB.TIMECARD(SCH_1):FPGA_CFG_INIT_N   I173 @TIMECARD_LIB.TIMECARD(SCH_1):PAGE524

 J11 CONN_USB_1X5_G2_GH4_F_RA_SMT-GA
     1 XP5R0V_USB_CONN @TIMECARD_LIB.TIMECARD(SCH_1):XP5R0V_USB_CONN     I2 @TIMECARD_LIB.TIMECARD(SCH_1):PAGE527
     2 CONN_MICRO_USB_DM @TIMECARD_LIB.TIMECARD(SCH_1):CONN_MICRO_USB_DM     I2 @TIMECARD_LIB.TIMECARD(SCH_1):PAGE527
     3 CONN_MICRO_USB_DP @TIMECARD_LIB.TIMECARD(SCH_1):CONN_MICRO_USB_DP     I2 @TIMECARD_LIB.TIMECARD(SCH_1):PAGE527
     4     NC     NC     I2 @TIMECARD_LIB.TIMECARD(SCH_1):PAGE527
     5     SG @TIMECARD_LIB.TIMECARD(SCH_1):SG     I2 @TIMECARD_LIB.TIMECARD(SCH_1):PAGE527
    G1     SG @TIMECARD_LIB.TIMECARD(SCH_1):SG     I2 @TIMECARD_LIB.TIMECARD(SCH_1):PAGE527
    G2     SG @TIMECARD_LIB.TIMECARD(SCH_1):SG     I2 @TIMECARD_LIB.TIMECARD(SCH_1):PAGE527
   GH1     SG @TIMECARD_LIB.TIMECARD(SCH_1):SG     I2 @TIMECARD_LIB.TIMECARD(SCH_1):PAGE527
   GH2     SG @TIMECARD_LIB.TIMECARD(SCH_1):SG     I2 @TIMECARD_LIB.TIMECARD(SCH_1):PAGE527
   GH3     SG @TIMECARD_LIB.TIMECARD(SCH_1):SG     I2 @TIMECARD_LIB.TIMECARD(SCH_1):PAGE527
   GH4     SG @TIMECARD_LIB.TIMECARD(SCH_1):SG     I2 @TIMECARD_LIB.TIMECARD(SCH_1):PAGE527

 J13 CONN_USB_14P_GH4_F_RA_TH-G200-A
    A1     SG @TIMECARD_LIB.TIMECARD(SCH_1):SG   I495 @TIMECARD_LIB.TIMECARD(SCH_1):PAGE524
    A4 XP5R0V_FT4232 @TIMECARD_LIB.TIMECARD(SCH_1):XP5R0V_FT4232   I495 @TIMECARD_LIB.TIMECARD(SCH_1):PAGE524
    A5 UNNAMED_524_CONNUSB14PGH4FRATH_ @TIMECARD_LIB.TIMECARD(SCH_1):UNNAMED_524_CONNUSB14PGH4FRATH_I495_CC1   I495 @TIMECARD_LIB.TIMECARD(SCH_1):PAGE524
    A6 FT_USB_DP @TIMECARD_LIB.TIMECARD(SCH_1):FT_USB_DP   I495 @TIMECARD_LIB.TIMECARD(SCH_1):PAGE524
    A7 FT_USB_DM @TIMECARD_LIB.TIMECARD(SCH_1):FT_USB_DM   I495 @TIMECARD_LIB.TIMECARD(SCH_1):PAGE524
    A9 XP5R0V_FT4232 @TIMECARD_LIB.TIMECARD(SCH_1):XP5R0V_FT4232   I495 @TIMECARD_LIB.TIMECARD(SCH_1):PAGE524
   A12     SG @TIMECARD_LIB.TIMECARD(SCH_1):SG   I495 @TIMECARD_LIB.TIMECARD(SCH_1):PAGE524
    B1     SG @TIMECARD_LIB.TIMECARD(SCH_1):SG   I495 @TIMECARD_LIB.TIMECARD(SCH_1):PAGE524
    B4 XP5R0V_FT4232 @TIMECARD_LIB.TIMECARD(SCH_1):XP5R0V_FT4232   I495 @TIMECARD_LIB.TIMECARD(SCH_1):PAGE524
    B5 UNNAMED_524_CONNUSB14PGH4FRAT_1 @TIMECARD_LIB.TIMECARD(SCH_1):UNNAMED_524_CONNUSB14PGH4FRATH_I495_CC2   I495 @TIMECARD_LIB.TIMECARD(SCH_1):PAGE524
    B6 FT_USB_DP @TIMECARD_LIB.TIMECARD(SCH_1):FT_USB_DP   I495 @TIMECARD_LIB.TIMECARD(SCH_1):PAGE524
    B7 FT_USB_DM @TIMECARD_LIB.TIMECARD(SCH_1):FT_USB_DM   I495 @TIMECARD_LIB.TIMECARD(SCH_1):PAGE524
    B9 XP5R0V_FT4232 @TIMECARD_LIB.TIMECARD(SCH_1):XP5R0V_FT4232   I495 @TIMECARD_LIB.TIMECARD(SCH_1):PAGE524
   B12     SG @TIMECARD_LIB.TIMECARD(SCH_1):SG   I495 @TIMECARD_LIB.TIMECARD(SCH_1):PAGE524
   GH1     SG @TIMECARD_LIB.TIMECARD(SCH_1):SG   I495 @TIMECARD_LIB.TIMECARD(SCH_1):PAGE524
   GH2     SG @TIMECARD_LIB.TIMECARD(SCH_1):SG   I495 @TIMECARD_LIB.TIMECARD(SCH_1):PAGE524
   GH3     SG @TIMECARD_LIB.TIMECARD(SCH_1):SG   I495 @TIMECARD_LIB.TIMECARD(SCH_1):PAGE524
   GH4     SG @TIMECARD_LIB.TIMECARD(SCH_1):SG   I495 @TIMECARD_LIB.TIMECARD(SCH_1):PAGE524

 J14 G200_10283_01-G200-10283-01
     1 FT4232_FPGA_TCK @TIMECARD_LIB.TIMECARD(SCH_1):FT4232_FPGA_TCK   I427 @TIMECARD_LIB.TIMECARD(SCH_1):PAGE127
     2     SG @TIMECARD_LIB.TIMECARD(SCH_1):SG   I427 @TIMECARD_LIB.TIMECARD(SCH_1):PAGE127
     3 FT4232_FPGA_TDO @TIMECARD_LIB.TIMECARD(SCH_1):FT4232_FPGA_TDO   I427 @TIMECARD_LIB.TIMECARD(SCH_1):PAGE127
     4 UNNAMED_127_G2001028301_I427_4 @TIMECARD_LIB.TIMECARD(SCH_1):UNNAMED_127_G2001028301_I427_4   I427 @TIMECARD_LIB.TIMECARD(SCH_1):PAGE127
     5 FT4232_FPGA_TMS @TIMECARD_LIB.TIMECARD(SCH_1):FT4232_FPGA_TMS   I427 @TIMECARD_LIB.TIMECARD(SCH_1):PAGE127
     6     NC     NC   I427 @TIMECARD_LIB.TIMECARD(SCH_1):PAGE127
     7     NC     NC   I427 @TIMECARD_LIB.TIMECARD(SCH_1):PAGE127
     8     NC     NC   I427 @TIMECARD_LIB.TIMECARD(SCH_1):PAGE127
     9 FT4232_FPGA_TDI @TIMECARD_LIB.TIMECARD(SCH_1):FT4232_FPGA_TDI   I427 @TIMECARD_LIB.TIMECARD(SCH_1):PAGE127
    10     SG @TIMECARD_LIB.TIMECARD(SCH_1):SG   I427 @TIMECARD_LIB.TIMECARD(SCH_1):PAGE127

 J17 CONN_HDR_2X2_M_S_SMT-G200-1068A
     1 SN_EEPROM_WP @TIMECARD_LIB.TIMECARD(SCH_1):SN_EEPROM_WP   I127 @TIMECARD_LIB.TIMECARD(SCH_1):PAGE5
     2     SG @TIMECARD_LIB.TIMECARD(SCH_1):SG   I127 @TIMECARD_LIB.TIMECARD(SCH_1):PAGE5
     3 SEC_EEPROM_WP @TIMECARD_LIB.TIMECARD(SCH_1):SEC_EEPROM_WP   I127 @TIMECARD_LIB.TIMECARD(SCH_1):PAGE5
     4     SG @TIMECARD_LIB.TIMECARD(SCH_1):SG   I127 @TIMECARD_LIB.TIMECARD(SCH_1):PAGE5

 J18 CONN_HDR_1X3_M_S_SMT-G205-1002A
     1     SG @TIMECARD_LIB.TIMECARD(SCH_1):SG   I198 @TIMECARD_LIB.TIMECARD(SCH_1):PAGE527
     2 SMA_ANALOG_TUNING_IN @TIMECARD_LIB.TIMECARD(SCH_1):SMA_ANALOG_TUNING_IN   I198 @TIMECARD_LIB.TIMECARD(SCH_1):PAGE527
     3     SG @TIMECARD_LIB.TIMECARD(SCH_1):SG   I198 @TIMECARD_LIB.TIMECARD(SCH_1):PAGE527

  L1 INDUCTOR_2-G190-10424-01,4.7UHA
     1 XP5R0V_SW @TIMECARD_LIB.TIMECARD(SCH_1):XP5R0V_SW    I36 @TIMECARD_LIB.TIMECARD(SCH_1):PAGE516
     2 XP5R0V @TIMECARD_LIB.TIMECARD(SCH_1):XP5R0V    I36 @TIMECARD_LIB.TIMECARD(SCH_1):PAGE516

  L2 INDUCTOR_2-G190-10424-01,4.7UHA
     1 XP3R3V_SW @TIMECARD_LIB.TIMECARD(SCH_1):XP3R3V_SW    I28 @TIMECARD_LIB.TIMECARD(SCH_1):PAGE517
     2 XP3R3V @TIMECARD_LIB.TIMECARD(SCH_1):XP3R3V    I28 @TIMECARD_LIB.TIMECARD(SCH_1):PAGE517

  L3 FERRITEBEAD-G191-10101-01,26OHA
     1 XP5R0V_MAC @TIMECARD_LIB.TIMECARD(SCH_1):XP5R0V_MAC    I91 @TIMECARD_LIB.TIMECARD(SCH_1):PAGE527
     2 XP5R0V @TIMECARD_LIB.TIMECARD(SCH_1):XP5R0V    I91 @TIMECARD_LIB.TIMECARD(SCH_1):PAGE527

  L4 FERRITEBEAD-G191-10097-01,600OA
     1 XP3R3V_FT4232 @TIMECARD_LIB.TIMECARD(SCH_1):XP3R3V_FT4232   I127 @TIMECARD_LIB.TIMECARD(SCH_1):PAGE524
     2 XP3R3V_VPLL @TIMECARD_LIB.TIMECARD(SCH_1):XP3R3V_VPLL   I127 @TIMECARD_LIB.TIMECARD(SCH_1):PAGE524

  L5 INDUCTOR_2-G190-10418-01,1.0UHA
     1 XP1R0V_SW @TIMECARD_LIB.TIMECARD(SCH_1):XP1R0V_SW    I25 @TIMECARD_LIB.TIMECARD(SCH_1):PAGE523
     2 XP1R0V_FPGA @TIMECARD_LIB.TIMECARD(SCH_1):XP1R0V_FPGA    I25 @TIMECARD_LIB.TIMECARD(SCH_1):PAGE523

  L6 FERRITEBEAD-G191-10101-01,26OHA
     1 XP3R3V @TIMECARD_LIB.TIMECARD(SCH_1):XP3R3V    I43 @TIMECARD_LIB.TIMECARD(SCH_1):PAGE68
     2 XP1R8V_VIN @TIMECARD_LIB.TIMECARD(SCH_1):XP1R8V_VIN    I43 @TIMECARD_LIB.TIMECARD(SCH_1):PAGE68

  L7 FERRITEBEAD-G191-10101-01,26OHA
     1 XP12R0V @TIMECARD_LIB.TIMECARD(SCH_1):XP12R0V    I17 @TIMECARD_LIB.TIMECARD(SCH_1):PAGE516
     2 VIN_XP5R0V @TIMECARD_LIB.TIMECARD(SCH_1):VIN_XP5R0V    I17 @TIMECARD_LIB.TIMECARD(SCH_1):PAGE516

  L8 FERRITEBEAD-G191-10101-01,26OHA
     1 XP12R0V @TIMECARD_LIB.TIMECARD(SCH_1):XP12R0V     I7 @TIMECARD_LIB.TIMECARD(SCH_1):PAGE517
     2 VIN_XP3R3 @TIMECARD_LIB.TIMECARD(SCH_1):VIN_XP3R3     I7 @TIMECARD_LIB.TIMECARD(SCH_1):PAGE517

  L9 FERRITEBEAD-G191-10101-01,26OHA
     1 XP12R0V @TIMECARD_LIB.TIMECARD(SCH_1):XP12R0V    I48 @TIMECARD_LIB.TIMECARD(SCH_1):PAGE523
     2 VIN_XP1R0V @TIMECARD_LIB.TIMECARD(SCH_1):VIN_XP1R0V    I48 @TIMECARD_LIB.TIMECARD(SCH_1):PAGE523

 L10 FERRITEBEAD-G191-10097-01,600OA
     1 VDD3V3_OSC_125M @TIMECARD_LIB.TIMECARD(SCH_1):VDD3V3_OSC_125M   I159 @TIMECARD_LIB.TIMECARD(SCH_1):PAGE522
     2 XP3R3V @TIMECARD_LIB.TIMECARD(SCH_1):XP3R3V   I159 @TIMECARD_LIB.TIMECARD(SCH_1):PAGE522

 L11 FERRITEBEAD-G191-10101-01,26OHA
     1 XP3R3V @TIMECARD_LIB.TIMECARD(SCH_1):XP3R3V    I25 @TIMECARD_LIB.TIMECARD(SCH_1):PAGE68
     2 XP1R2V_VIN @TIMECARD_LIB.TIMECARD(SCH_1):XP1R2V_VIN    I25 @TIMECARD_LIB.TIMECARD(SCH_1):PAGE68

 L12 FERRITEBEAD-G191-10100-01,120OA
     1 XP1R0V_FPGA_VCCINT @TIMECARD_LIB.TIMECARD(SCH_1):XP1R0V_FPGA_VCCINT   I139 @TIMECARD_LIB.TIMECARD(SCH_1):PAGE164
     2 XP1R0V_FPGA @TIMECARD_LIB.TIMECARD(SCH_1):XP1R0V_FPGA   I139 @TIMECARD_LIB.TIMECARD(SCH_1):PAGE164

 L13 FERRITEBEAD-G191-10101-01,26OHA
     1 XP3R3V @TIMECARD_LIB.TIMECARD(SCH_1):XP3R3V   I135 @TIMECARD_LIB.TIMECARD(SCH_1):PAGE515
     2 UNNAMED_515_CAPACITOR_I130_1 @TIMECARD_LIB.TIMECARD(SCH_1):UNNAMED_515_CAPACITOR_I130_1   I135 @TIMECARD_LIB.TIMECARD(SCH_1):PAGE515

 L14 FERRITEBEAD-G191-10097-01,600OA
     1 VDD3V3_OSC_200M @TIMECARD_LIB.TIMECARD(SCH_1):VDD3V3_OSC_200M   I146 @TIMECARD_LIB.TIMECARD(SCH_1):PAGE522
     2 XP3R3V @TIMECARD_LIB.TIMECARD(SCH_1):XP3R3V   I146 @TIMECARD_LIB.TIMECARD(SCH_1):PAGE522

 L15 FERRITEBEAD-G191-10100-01,120OA
     1 XP5R0V @TIMECARD_LIB.TIMECARD(SCH_1):XP5R0V    I56 @TIMECARD_LIB.TIMECARD(SCH_1):PAGE11
     2 XP5R0V_VCC_ANT @TIMECARD_LIB.TIMECARD(SCH_1):XP5R0V_VCC_ANT    I56 @TIMECARD_LIB.TIMECARD(SCH_1):PAGE11

 L16 FERRITEBEAD-G191-10100-01,120OA
     1 XP3R3V_GPS @TIMECARD_LIB.TIMECARD(SCH_1):XP3R3V_GPS    I55 @TIMECARD_LIB.TIMECARD(SCH_1):PAGE11
     2 XP3R3V_FPGA @TIMECARD_LIB.TIMECARD(SCH_1):XP3R3V_FPGA    I55 @TIMECARD_LIB.TIMECARD(SCH_1):PAGE11

 L17 FERRITEBEAD-G191-10097-01,600OA
     1 XP3R3V_FPGA @TIMECARD_LIB.TIMECARD(SCH_1):XP3R3V_FPGA    I21 @TIMECARD_LIB.TIMECARD(SCH_1):PAGE7
     2 VDD3V3_SHT31A @TIMECARD_LIB.TIMECARD(SCH_1):VDD3V3_SHT31A    I21 @TIMECARD_LIB.TIMECARD(SCH_1):PAGE7

 L18 FERRITEBEAD-G191-10097-01,600OA
     1 XP1R8V_FPGA @TIMECARD_LIB.TIMECARD(SCH_1):XP1R8V_FPGA    I18 @TIMECARD_LIB.TIMECARD(SCH_1):PAGE8
     2 XP1R8V_ICP10100 @TIMECARD_LIB.TIMECARD(SCH_1):XP1R8V_ICP10100    I18 @TIMECARD_LIB.TIMECARD(SCH_1):PAGE8

 L19 FERRITEBEAD-G191-10097-01,600OA
     1 VDD_BNO085 @TIMECARD_LIB.TIMECARD(SCH_1):VDD_BNO085    I22 @TIMECARD_LIB.TIMECARD(SCH_1):PAGE9
     2 XP3R3V_FPGA @TIMECARD_LIB.TIMECARD(SCH_1):XP3R3V_FPGA    I22 @TIMECARD_LIB.TIMECARD(SCH_1):PAGE9

 L20 FERRITEBEAD-G191-10101-01,26OHA
     1 XP12R0V_PCIE @TIMECARD_LIB.TIMECARD(SCH_1):XP12R0V_PCIE   I240 @TIMECARD_LIB.TIMECARD(SCH_1):PAGE15
     2 XP12R0V_IN @TIMECARD_LIB.TIMECARD(SCH_1):XP12R0V_IN   I240 @TIMECARD_LIB.TIMECARD(SCH_1):PAGE15

 L21 FERRITEBEAD-G191-10101-01,26OHA
     1 XP3R3V_PCIE @TIMECARD_LIB.TIMECARD(SCH_1):XP3R3V_PCIE   I132 @TIMECARD_LIB.TIMECARD(SCH_1):PAGE3
     2 XP3R3V @TIMECARD_LIB.TIMECARD(SCH_1):XP3R3V   I132 @TIMECARD_LIB.TIMECARD(SCH_1):PAGE3

 L22 FERRITEBEAD-G191-10097-01,600OA
     1 XP3R3V_FT4232 @TIMECARD_LIB.TIMECARD(SCH_1):XP3R3V_FT4232   I118 @TIMECARD_LIB.TIMECARD(SCH_1):PAGE524
     2 XP3R3V_VPHY @TIMECARD_LIB.TIMECARD(SCH_1):XP3R3V_VPHY   I118 @TIMECARD_LIB.TIMECARD(SCH_1):PAGE524

 L23 FERRITEBEAD-G191-10101-01,26OHA
     1 UNNAMED_525_CAPACITOR_I7_1 @TIMECARD_LIB.TIMECARD(SCH_1):UNNAMED_525_CAPACITOR_I7_1    I10 @TIMECARD_LIB.TIMECARD(SCH_1):PAGE525
     2 UNNAMED_525_CAPACITOR_I16_1 @TIMECARD_LIB.TIMECARD(SCH_1):UNNAMED_525_CAPACITOR_I16_1    I10 @TIMECARD_LIB.TIMECARD(SCH_1):PAGE525

 L24 FERRITEBEAD-G191-10100-01,120OA
     1 XP3R3V_FPGA @TIMECARD_LIB.TIMECARD(SCH_1):XP3R3V_FPGA   I108 @TIMECARD_LIB.TIMECARD(SCH_1):PAGE525
     2 XP3R3V_FT4232 @TIMECARD_LIB.TIMECARD(SCH_1):XP3R3V_FT4232   I108 @TIMECARD_LIB.TIMECARD(SCH_1):PAGE525

 L33 FERRITEBEAD-G191-10100-01,120OA
     1 XP1R8V_FPGA_VCCAUX @TIMECARD_LIB.TIMECARD(SCH_1):XP1R8V_FPGA_VCCAUX   I102 @TIMECARD_LIB.TIMECARD(SCH_1):PAGE164
     2 XP1R8V_FPGA @TIMECARD_LIB.TIMECARD(SCH_1):XP1R8V_FPGA   I102 @TIMECARD_LIB.TIMECARD(SCH_1):PAGE164

 L34 FERRITEBEAD-G191-10100-01,120OA
     1 XP1R0V_FPGA_MGTAVCC @TIMECARD_LIB.TIMECARD(SCH_1):XP1R0V_FPGA_MGTAVCC    I37 @TIMECARD_LIB.TIMECARD(SCH_1):PAGE164
     2 XP1R0V_FPGA @TIMECARD_LIB.TIMECARD(SCH_1):XP1R0V_FPGA    I37 @TIMECARD_LIB.TIMECARD(SCH_1):PAGE164

 L35 FERRITEBEAD-G191-10100-01,120OA
     1 FPGA_MGTAVTT @TIMECARD_LIB.TIMECARD(SCH_1):FPGA_MGTAVTT    I36 @TIMECARD_LIB.TIMECARD(SCH_1):PAGE164
     2 XP1R2V_FPGA @TIMECARD_LIB.TIMECARD(SCH_1):XP1R2V_FPGA    I36 @TIMECARD_LIB.TIMECARD(SCH_1):PAGE164

MAC_PIN1 NUT-A200-00029-FB
     1 ANALOG_TUNING_IN @TIMECARD_LIB.TIMECARD(SCH_1):ANALOG_TUNING_IN   I227 @TIMECARD_LIB.TIMECARD(SCH_1):PAGE527

MAC_PIN2 NUT-A200-00029-FB
     1     SG @TIMECARD_LIB.TIMECARD(SCH_1):SG   I229 @TIMECARD_LIB.TIMECARD(SCH_1):PAGE527

MAC_PIN3 NUT-A200-00029-FB
     1 R_MAC_10MHZ_RF_OUT @TIMECARD_LIB.TIMECARD(SCH_1):R_MAC_10MHZ_RF_OUT   I226 @TIMECARD_LIB.TIMECARD(SCH_1):PAGE527

MAC_PIN4 NUT-A200-00029-FB
     1     SG @TIMECARD_LIB.TIMECARD(SCH_1):SG   I228 @TIMECARD_LIB.TIMECARD(SCH_1):PAGE527

MAC_PIN5 NUT-A200-00029-FB
     1 XP5R0V_MAC @TIMECARD_LIB.TIMECARD(SCH_1):XP5R0V_MAC   I230 @TIMECARD_LIB.TIMECARD(SCH_1):PAGE527

MAC_PIN6 NUT-A200-00029-FB
     1 R_MAC_BITEOUT @TIMECARD_LIB.TIMECARD(SCH_1):R_MAC_BITE OUT   I225 @TIMECARD_LIB.TIMECARD(SCH_1):PAGE527

MAC_PIN7 NUT-A200-00029-FB
     1 R_MAC_UART_TX_FPGA_RX @TIMECARD_LIB.TIMECARD(SCH_1):R_MAC_UART_TX_FPGA_RX   I224 @TIMECARD_LIB.TIMECARD(SCH_1):PAGE527

MAC_PIN8 NUT-A200-00029-FB
     1 R_MAC_UART_RX_FPGA_TX @TIMECARD_LIB.TIMECARD(SCH_1):R_MAC_UART_RX_FPGA_TX   I220 @TIMECARD_LIB.TIMECARD(SCH_1):PAGE527

 ME1 NUT-G340-10437-01
     1     SG @TIMECARD_LIB.TIMECARD(SCH_1):SG   I127 @TIMECARD_LIB.TIMECARD(SCH_1):PAGE33

 ME2 NUT-G340-10437-01
     1     SG @TIMECARD_LIB.TIMECARD(SCH_1):SG   I129 @TIMECARD_LIB.TIMECARD(SCH_1):PAGE33

 ME3 NUT-G340-10437-01
     1     SG @TIMECARD_LIB.TIMECARD(SCH_1):SG   I125 @TIMECARD_LIB.TIMECARD(SCH_1):PAGE33

 ME4 NUT-G340-10437-01
     1     SG @TIMECARD_LIB.TIMECARD(SCH_1):SG   I126 @TIMECARD_LIB.TIMECARD(SCH_1):PAGE33

 ME5 MEC_NPTH-MTH100C240N-MTH100C24A

 ME6 MEC_NPTH-MTH100C240N-MTH100C24A

 ME7 MEC_NPTH-MTH100C240N-MTH100C24A

 ME8 MEC_NPTH-MTH100C240N-MTH100C24A

 ME9 MEC_MTH8-MTH125C236N_V8-MTH125A
     2     SG @TIMECARD_LIB.TIMECARD(SCH_1):SG     I7 @TIMECARD_LIB.TIMECARD(SCH_1):PAGE33
     3     SG @TIMECARD_LIB.TIMECARD(SCH_1):SG     I7 @TIMECARD_LIB.TIMECARD(SCH_1):PAGE33
     1     SG @TIMECARD_LIB.TIMECARD(SCH_1):SG     I7 @TIMECARD_LIB.TIMECARD(SCH_1):PAGE33
     4     SG @TIMECARD_LIB.TIMECARD(SCH_1):SG     I7 @TIMECARD_LIB.TIMECARD(SCH_1):PAGE33
     6     SG @TIMECARD_LIB.TIMECARD(SCH_1):SG     I7 @TIMECARD_LIB.TIMECARD(SCH_1):PAGE33
     5     SG @TIMECARD_LIB.TIMECARD(SCH_1):SG     I7 @TIMECARD_LIB.TIMECARD(SCH_1):PAGE33
     7     SG @TIMECARD_LIB.TIMECARD(SCH_1):SG     I7 @TIMECARD_LIB.TIMECARD(SCH_1):PAGE33
     8     SG @TIMECARD_LIB.TIMECARD(SCH_1):SG     I7 @TIMECARD_LIB.TIMECARD(SCH_1):PAGE33

ME10 MEC_MTH8-MTH125C236N_V8-MTH125A
     2     SG @TIMECARD_LIB.TIMECARD(SCH_1):SG     I5 @TIMECARD_LIB.TIMECARD(SCH_1):PAGE33
     3     SG @TIMECARD_LIB.TIMECARD(SCH_1):SG     I5 @TIMECARD_LIB.TIMECARD(SCH_1):PAGE33
     1     SG @TIMECARD_LIB.TIMECARD(SCH_1):SG     I5 @TIMECARD_LIB.TIMECARD(SCH_1):PAGE33
     4     SG @TIMECARD_LIB.TIMECARD(SCH_1):SG     I5 @TIMECARD_LIB.TIMECARD(SCH_1):PAGE33
     6     SG @TIMECARD_LIB.TIMECARD(SCH_1):SG     I5 @TIMECARD_LIB.TIMECARD(SCH_1):PAGE33
     5     SG @TIMECARD_LIB.TIMECARD(SCH_1):SG     I5 @TIMECARD_LIB.TIMECARD(SCH_1):PAGE33
     7     SG @TIMECARD_LIB.TIMECARD(SCH_1):SG     I5 @TIMECARD_LIB.TIMECARD(SCH_1):PAGE33
     8     SG @TIMECARD_LIB.TIMECARD(SCH_1):SG     I5 @TIMECARD_LIB.TIMECARD(SCH_1):PAGE33

ME11 MEC_MTH8-MTH125C236N_V8-MTH125A
     2     SG @TIMECARD_LIB.TIMECARD(SCH_1):SG     I1 @TIMECARD_LIB.TIMECARD(SCH_1):PAGE33
     3     SG @TIMECARD_LIB.TIMECARD(SCH_1):SG     I1 @TIMECARD_LIB.TIMECARD(SCH_1):PAGE33
     1     SG @TIMECARD_LIB.TIMECARD(SCH_1):SG     I1 @TIMECARD_LIB.TIMECARD(SCH_1):PAGE33
     4     SG @TIMECARD_LIB.TIMECARD(SCH_1):SG     I1 @TIMECARD_LIB.TIMECARD(SCH_1):PAGE33
     6     SG @TIMECARD_LIB.TIMECARD(SCH_1):SG     I1 @TIMECARD_LIB.TIMECARD(SCH_1):PAGE33
     5     SG @TIMECARD_LIB.TIMECARD(SCH_1):SG     I1 @TIMECARD_LIB.TIMECARD(SCH_1):PAGE33
     7     SG @TIMECARD_LIB.TIMECARD(SCH_1):SG     I1 @TIMECARD_LIB.TIMECARD(SCH_1):PAGE33
     8     SG @TIMECARD_LIB.TIMECARD(SCH_1):SG     I1 @TIMECARD_LIB.TIMECARD(SCH_1):PAGE33

ME12 MEC_MTH8-MTH125C236N_V8-MTH125A
     2     SG @TIMECARD_LIB.TIMECARD(SCH_1):SG     I2 @TIMECARD_LIB.TIMECARD(SCH_1):PAGE33
     3     SG @TIMECARD_LIB.TIMECARD(SCH_1):SG     I2 @TIMECARD_LIB.TIMECARD(SCH_1):PAGE33
     1     SG @TIMECARD_LIB.TIMECARD(SCH_1):SG     I2 @TIMECARD_LIB.TIMECARD(SCH_1):PAGE33
     4     SG @TIMECARD_LIB.TIMECARD(SCH_1):SG     I2 @TIMECARD_LIB.TIMECARD(SCH_1):PAGE33
     6     SG @TIMECARD_LIB.TIMECARD(SCH_1):SG     I2 @TIMECARD_LIB.TIMECARD(SCH_1):PAGE33
     5     SG @TIMECARD_LIB.TIMECARD(SCH_1):SG     I2 @TIMECARD_LIB.TIMECARD(SCH_1):PAGE33
     7     SG @TIMECARD_LIB.TIMECARD(SCH_1):SG     I2 @TIMECARD_LIB.TIMECARD(SCH_1):PAGE33
     8     SG @TIMECARD_LIB.TIMECARD(SCH_1):SG     I2 @TIMECARD_LIB.TIMECARD(SCH_1):PAGE33

  P1 CONN_HDR_2X10_M_S_SMT-G200-130A
     1 R_MAC_PPS_IN1P @TIMECARD_LIB.TIMECARD(SCH_1):R_MAC_PPS_IN1P   I193 @TIMECARD_LIB.TIMECARD(SCH_1):PAGE527
     3 R_MAC_PPS_IN1N @TIMECARD_LIB.TIMECARD(SCH_1):R_MAC_PPS_IN1N   I193 @TIMECARD_LIB.TIMECARD(SCH_1):PAGE527
     5 R_MAC_PPS_IN0P @TIMECARD_LIB.TIMECARD(SCH_1):R_MAC_PPS_IN0P   I193 @TIMECARD_LIB.TIMECARD(SCH_1):PAGE527
     7 R_MAC_PPS_IN0N @TIMECARD_LIB.TIMECARD(SCH_1):R_MAC_PPS_IN0N   I193 @TIMECARD_LIB.TIMECARD(SCH_1):PAGE527
     9     SG @TIMECARD_LIB.TIMECARD(SCH_1):SG   I193 @TIMECARD_LIB.TIMECARD(SCH_1):PAGE527
    11     NC     NC   I193 @TIMECARD_LIB.TIMECARD(SCH_1):PAGE527
    13     NC     NC   I193 @TIMECARD_LIB.TIMECARD(SCH_1):PAGE527
    15     SG @TIMECARD_LIB.TIMECARD(SCH_1):SG   I193 @TIMECARD_LIB.TIMECARD(SCH_1):PAGE527
    17 R_MAC_PPS_OUTP @TIMECARD_LIB.TIMECARD(SCH_1):R_MAC_PPS_OUTP   I193 @TIMECARD_LIB.TIMECARD(SCH_1):PAGE527
    19 R_MAC_PPS_OUTN @TIMECARD_LIB.TIMECARD(SCH_1):R_MAC_PPS_OUTN   I193 @TIMECARD_LIB.TIMECARD(SCH_1):PAGE527
     2 R_MAC_USB_DP @TIMECARD_LIB.TIMECARD(SCH_1):R_MAC_USB_DP   I193 @TIMECARD_LIB.TIMECARD(SCH_1):PAGE527
     4 R_MAC_USB_DM @TIMECARD_LIB.TIMECARD(SCH_1):R_MAC_USB_DM   I193 @TIMECARD_LIB.TIMECARD(SCH_1):PAGE527
     6 XP5R0V_MAC_USB @TIMECARD_LIB.TIMECARD(SCH_1):XP5R0V_MAC_USB   I193 @TIMECARD_LIB.TIMECARD(SCH_1):PAGE527
     8     SG @TIMECARD_LIB.TIMECARD(SCH_1):SG   I193 @TIMECARD_LIB.TIMECARD(SCH_1):PAGE527
    10     NC     NC   I193 @TIMECARD_LIB.TIMECARD(SCH_1):PAGE527
    12     NC     NC   I193 @TIMECARD_LIB.TIMECARD(SCH_1):PAGE527
    14     NC     NC   I193 @TIMECARD_LIB.TIMECARD(SCH_1):PAGE527
    16     NC     NC   I193 @TIMECARD_LIB.TIMECARD(SCH_1):PAGE527
    18     NC     NC   I193 @TIMECARD_LIB.TIMECARD(SCH_1):PAGE527
    20 MAC_ALARM @TIMECARD_LIB.TIMECARD(SCH_1):MAC_ALARM   I193 @TIMECARD_LIB.TIMECARD(SCH_1):PAGE527

  P2 CONN_HDR_2X4_F_S_SMT-G200-1307A
     1 XP5R0V_VCC_ANT @TIMECARD_LIB.TIMECARD(SCH_1):XP5R0V_VCC_ANT    I36 @TIMECARD_LIB.TIMECARD(SCH_1):PAGE11
     2 XP3R3V_GPS @TIMECARD_LIB.TIMECARD(SCH_1):XP3R3V_GPS    I36 @TIMECARD_LIB.TIMECARD(SCH_1):PAGE11
     3 GPS_UART_TXD @TIMECARD_LIB.TIMECARD(SCH_1):GPS_UART_TXD    I36 @TIMECARD_LIB.TIMECARD(SCH_1):PAGE11
     4 GPS_RST_N @TIMECARD_LIB.TIMECARD(SCH_1):GPS_RST_N    I36 @TIMECARD_LIB.TIMECARD(SCH_1):PAGE11
     5 GPS_UART_RXD @TIMECARD_LIB.TIMECARD(SCH_1):GPS_UART_RXD    I36 @TIMECARD_LIB.TIMECARD(SCH_1):PAGE11
     6 GPSTP1_OUT @TIMECARD_LIB.TIMECARD(SCH_1):GPSTP1_OUT    I36 @TIMECARD_LIB.TIMECARD(SCH_1):PAGE11
     7 GPSTP2_OUT @TIMECARD_LIB.TIMECARD(SCH_1):GPSTP2_OUT    I36 @TIMECARD_LIB.TIMECARD(SCH_1):PAGE11
     8     SG @TIMECARD_LIB.TIMECARD(SCH_1):SG    I36 @TIMECARD_LIB.TIMECARD(SCH_1):PAGE11

  P3 CONN_HDR_2X3_M_RA_TH-G200-1251A
     1 XP12R0V_EXT @TIMECARD_LIB.TIMECARD(SCH_1):XP12R0V_EXT   I238 @TIMECARD_LIB.TIMECARD(SCH_1):PAGE15
     2 XP12R0V_EXT @TIMECARD_LIB.TIMECARD(SCH_1):XP12R0V_EXT   I238 @TIMECARD_LIB.TIMECARD(SCH_1):PAGE15
     3 XP12R0V_EXT @TIMECARD_LIB.TIMECARD(SCH_1):XP12R0V_EXT   I238 @TIMECARD_LIB.TIMECARD(SCH_1):PAGE15
     4     SG @TIMECARD_LIB.TIMECARD(SCH_1):SG   I238 @TIMECARD_LIB.TIMECARD(SCH_1):PAGE15
     5     SG @TIMECARD_LIB.TIMECARD(SCH_1):SG   I238 @TIMECARD_LIB.TIMECARD(SCH_1):PAGE15
     6     SG @TIMECARD_LIB.TIMECARD(SCH_1):SG   I238 @TIMECARD_LIB.TIMECARD(SCH_1):PAGE15

  Q1 POWERMOS_3P_NCH_V1-G121-10200-A
     1 FT_USB_DETECT @TIMECARD_LIB.TIMECARD(SCH_1):FT_USB_DETECT   I445 @TIMECARD_LIB.TIMECARD(SCH_1):PAGE524
     2     SG @TIMECARD_LIB.TIMECARD(SCH_1):SG   I445 @TIMECARD_LIB.TIMECARD(SCH_1):PAGE524
     3 UNNAMED_524_POWERMOS3PNCHV1_I44 @TIMECARD_LIB.TIMECARD(SCH_1):UNNAMED_524_POWERMOS3PNCHV1_I445_D   I445 @TIMECARD_LIB.TIMECARD(SCH_1):PAGE524

  Q2 POWERMOS_3P_NCH_V1-G121-10200-A
     1 USB_PWR_EN @TIMECARD_LIB.TIMECARD(SCH_1):USB_PWR_EN   I232 @TIMECARD_LIB.TIMECARD(SCH_1):PAGE527
     2     SG @TIMECARD_LIB.TIMECARD(SCH_1):SG   I232 @TIMECARD_LIB.TIMECARD(SCH_1):PAGE527
     3 UNNAMED_527_POWERMOS3PNCHV1_I23 @TIMECARD_LIB.TIMECARD(SCH_1):UNNAMED_527_POWERMOS3PNCHV1_I232_D   I232 @TIMECARD_LIB.TIMECARD(SCH_1):PAGE527

  Q3 POWERMOS_3P_PCH-G121-10216-01
     1 UNNAMED_527_POWERMOS3PNCHV1_I23 @TIMECARD_LIB.TIMECARD(SCH_1):UNNAMED_527_POWERMOS3PNCHV1_I232_D   I231 @TIMECARD_LIB.TIMECARD(SCH_1):PAGE527
     2 XP5R0V_MAC @TIMECARD_LIB.TIMECARD(SCH_1):XP5R0V_MAC   I231 @TIMECARD_LIB.TIMECARD(SCH_1):PAGE527
     3 UNNAMED_527_FUSE_I244_1 @TIMECARD_LIB.TIMECARD(SCH_1):UNNAMED_527_FUSE_I244_1   I231 @TIMECARD_LIB.TIMECARD(SCH_1):PAGE527

  R1 RESISTOR-G155-13300-01,330OHM,A
     2 SN_EEPROM_WP @TIMECARD_LIB.TIMECARD(SCH_1):SN_EEPROM_WP   I130 @TIMECARD_LIB.TIMECARD(SCH_1):PAGE5
     1 FPGA_OUT_SN_EEPROM_WP @TIMECARD_LIB.TIMECARD(SCH_1):FPGA_OUT_SN_EEPROM_WP   I130 @TIMECARD_LIB.TIMECARD(SCH_1):PAGE5

  R2 RESISTOR-G155-13300-01,330OHM,A
     2 SEC_EEPROM_WP @TIMECARD_LIB.TIMECARD(SCH_1):SEC_EEPROM_WP   I173 @TIMECARD_LIB.TIMECARD(SCH_1):PAGE5
     1 FPGA_OUT_SEC_EEPROM_WP @TIMECARD_LIB.TIMECARD(SCH_1):FPGA_OUT_SEC_EEPROM_WP   I173 @TIMECARD_LIB.TIMECARD(SCH_1):PAGE5

  R3 RESISTOR-G155-14701-01,4.7KOHMA
     2 SEC_EEPROM_WP @TIMECARD_LIB.TIMECARD(SCH_1):SEC_EEPROM_WP   I169 @TIMECARD_LIB.TIMECARD(SCH_1):PAGE5
     1 XP3R3V_FPGA @TIMECARD_LIB.TIMECARD(SCH_1):XP3R3V_FPGA   I169 @TIMECARD_LIB.TIMECARD(SCH_1):PAGE5

  R4 RESISTOR-G155-11002-01,10KOHM,A
     2 XP12R0V_A_EN @TIMECARD_LIB.TIMECARD(SCH_1):XP12R0V_A_EN   I170 @TIMECARD_LIB.TIMECARD(SCH_1):PAGE15
     1 XP12R0V_IN @TIMECARD_LIB.TIMECARD(SCH_1):XP12R0V_IN   I170 @TIMECARD_LIB.TIMECARD(SCH_1):PAGE15

  R5 RESISTOR-G155-11002-01,10KOHM,A
     2     SG @TIMECARD_LIB.TIMECARD(SCH_1):SG   I169 @TIMECARD_LIB.TIMECARD(SCH_1):PAGE15
     1 XP12R0V_A_EN @TIMECARD_LIB.TIMECARD(SCH_1):XP12R0V_A_EN   I169 @TIMECARD_LIB.TIMECARD(SCH_1):PAGE15

  R6 RESISTOR-G155-120R0-01,20OHM,1%
     2 UNNAMED_516_CAPACITOR_I29_1 @TIMECARD_LIB.TIMECARD(SCH_1):UNNAMED_516_CAPACITOR_I29_1    I31 @TIMECARD_LIB.TIMECARD(SCH_1):PAGE516
     1 XP5R0V @TIMECARD_LIB.TIMECARD(SCH_1):XP5R0V    I31 @TIMECARD_LIB.TIMECARD(SCH_1):PAGE516

  R7 RESISTOR-G155-100R0-J0,0OHM,-
     2 UNNAMED_15_MP5022CGQVZQFN22_I_2 @TIMECARD_LIB.TIMECARD(SCH_1):UNNAMED_15_MP5022CGQVZQFN22_I212_LOADEN   I174 @TIMECARD_LIB.TIMECARD(SCH_1):PAGE15
     1     SG @TIMECARD_LIB.TIMECARD(SCH_1):SG   I174 @TIMECARD_LIB.TIMECARD(SCH_1):PAGE15

  R8 RESISTOR-G155-100R0-J0,0OHM,-
     2 UNNAMED_15_MP5022CGQVZQFN22_I21 @TIMECARD_LIB.TIMECARD(SCH_1):UNNAMED_15_MP5022CGQVZQFN22_I212_ENTM   I173 @TIMECARD_LIB.TIMECARD(SCH_1):PAGE15
     1     SG @TIMECARD_LIB.TIMECARD(SCH_1):SG   I173 @TIMECARD_LIB.TIMECARD(SCH_1):PAGE15

  R9 RESISTOR-G156-049R9-01,49.9OHMA
     2 XP12R0V_A_AVIN @TIMECARD_LIB.TIMECARD(SCH_1):XP12R0V_A_AVIN   I198 @TIMECARD_LIB.TIMECARD(SCH_1):PAGE15
     1 XP12R0V_IN @TIMECARD_LIB.TIMECARD(SCH_1):XP12R0V_IN   I198 @TIMECARD_LIB.TIMECARD(SCH_1):PAGE15

 R10 RESISTOR-G155-11002-01,10KOHM,A
     2     SG @TIMECARD_LIB.TIMECARD(SCH_1):SG   I183 @TIMECARD_LIB.TIMECARD(SCH_1):PAGE15
     1 XP12R0V_A_IMON @TIMECARD_LIB.TIMECARD(SCH_1):XP12R0V_A_IMON   I183 @TIMECARD_LIB.TIMECARD(SCH_1):PAGE15

 R11 RESISTOR-G155-01203-01,120KOHMA
     2 XP12R0V_A_OV @TIMECARD_LIB.TIMECARD(SCH_1):XP12R0V_A_OV   I199 @TIMECARD_LIB.TIMECARD(SCH_1):PAGE15
     1 XP12R0V_IN @TIMECARD_LIB.TIMECARD(SCH_1):XP12R0V_IN   I199 @TIMECARD_LIB.TIMECARD(SCH_1):PAGE15

 R12 RESISTOR-G155-11002-01,10KOHM,A
     2     SG @TIMECARD_LIB.TIMECARD(SCH_1):SG   I197 @TIMECARD_LIB.TIMECARD(SCH_1):PAGE15
     1 XP12R0V_A_OV @TIMECARD_LIB.TIMECARD(SCH_1):XP12R0V_A_OV   I197 @TIMECARD_LIB.TIMECARD(SCH_1):PAGE15

 R13 RESISTOR-G155-11002-01,10KOHM,A
     2 XP12R0V_A_PG @TIMECARD_LIB.TIMECARD(SCH_1):XP12R0V_A_PG   I202 @TIMECARD_LIB.TIMECARD(SCH_1):PAGE15
     1 XP12R0V @TIMECARD_LIB.TIMECARD(SCH_1):XP12R0V   I202 @TIMECARD_LIB.TIMECARD(SCH_1):PAGE15

 R14 RESISTOR-G155-03921-01,3.92KOHA
     2     SG @TIMECARD_LIB.TIMECARD(SCH_1):SG   I186 @TIMECARD_LIB.TIMECARD(SCH_1):PAGE15
     1 XP12R0V_A_PG @TIMECARD_LIB.TIMECARD(SCH_1):XP12R0V_A_PG   I186 @TIMECARD_LIB.TIMECARD(SCH_1):PAGE15

 R15 RESISTOR-G155-11002-01,10KOHM,A
     2 XP12R0V_A_FLTB @TIMECARD_LIB.TIMECARD(SCH_1):XP12R0V_A_FLTB   I203 @TIMECARD_LIB.TIMECARD(SCH_1):PAGE15
     1 XP12R0V @TIMECARD_LIB.TIMECARD(SCH_1):XP12R0V   I203 @TIMECARD_LIB.TIMECARD(SCH_1):PAGE15

 R16 RESISTOR-G155-03921-01,3.92KOHA
     2     SG @TIMECARD_LIB.TIMECARD(SCH_1):SG   I188 @TIMECARD_LIB.TIMECARD(SCH_1):PAGE15
     1 XP12R0V_A_FLTB @TIMECARD_LIB.TIMECARD(SCH_1):XP12R0V_A_FLTB   I188 @TIMECARD_LIB.TIMECARD(SCH_1):PAGE15

 R17 RESISTOR-G155-120R0-01,20OHM,1%
     2 UNNAMED_517_CAPACITOR_I30_1 @TIMECARD_LIB.TIMECARD(SCH_1):UNNAMED_517_CAPACITOR_I30_1    I33 @TIMECARD_LIB.TIMECARD(SCH_1):PAGE517
     1 XP3R3V @TIMECARD_LIB.TIMECARD(SCH_1):XP3R3V    I33 @TIMECARD_LIB.TIMECARD(SCH_1):PAGE517

 R18 RESISTOR-G155-14701-01,4.7KOHMA
     2 FT_USB_DETECT @TIMECARD_LIB.TIMECARD(SCH_1):FT_USB_DETECT    I27 @TIMECARD_LIB.TIMECARD(SCH_1):PAGE524
     1 XP5R0V_FT4232 @TIMECARD_LIB.TIMECARD(SCH_1):XP5R0V_FT4232    I27 @TIMECARD_LIB.TIMECARD(SCH_1):PAGE524

 R19 RESISTOR-G155-11002-01,10KOHM,A
     2 EEPROM_SCL @TIMECARD_LIB.TIMECARD(SCH_1):EEPROM_SCL    I95 @TIMECARD_LIB.TIMECARD(SCH_1):PAGE5
     1 XP3R3V_FPGA @TIMECARD_LIB.TIMECARD(SCH_1):XP3R3V_FPGA    I95 @TIMECARD_LIB.TIMECARD(SCH_1):PAGE5

 R20 RESISTOR-G155-14701-01,4.7KOHMA
     2 LM75B_I2C_SDA @TIMECARD_LIB.TIMECARD(SCH_1):LM75B_I2C_SDA    I14 @TIMECARD_LIB.TIMECARD(SCH_1):PAGE6
     1 XP3R3V_FPGA @TIMECARD_LIB.TIMECARD(SCH_1):XP3R3V_FPGA    I14 @TIMECARD_LIB.TIMECARD(SCH_1):PAGE6

 R21 RESISTOR-G155-14701-01,4.7KOHMA
     2 LM75B_I2C_SCL @TIMECARD_LIB.TIMECARD(SCH_1):LM75B_I2C_SCL    I16 @TIMECARD_LIB.TIMECARD(SCH_1):PAGE6
     1 XP3R3V_FPGA @TIMECARD_LIB.TIMECARD(SCH_1):XP3R3V_FPGA    I16 @TIMECARD_LIB.TIMECARD(SCH_1):PAGE6

 R22 RESISTOR-G155-100R0-J0,0OHM,-
     2 UNNAMED_3_CONN64PGF_I61_PRSNT21 @TIMECARD_LIB.TIMECARD(SCH_1):UNNAMED_3_CONN64PGF_I61_PRSNT21    I16 @TIMECARD_LIB.TIMECARD(SCH_1):PAGE3
     1 CARD_PRESENT @TIMECARD_LIB.TIMECARD(SCH_1):CARD_PRESENT    I16 @TIMECARD_LIB.TIMECARD(SCH_1):PAGE3

 R23 RESISTOR-G155-100R0-J0,0OHM,-
     2 UNNAMED_3_CONN64PGF_I61_PRSNT22 @TIMECARD_LIB.TIMECARD(SCH_1):UNNAMED_3_CONN64PGF_I61_PRSNT22    I15 @TIMECARD_LIB.TIMECARD(SCH_1):PAGE3
     1 CARD_PRESENT @TIMECARD_LIB.TIMECARD(SCH_1):CARD_PRESENT    I15 @TIMECARD_LIB.TIMECARD(SCH_1):PAGE3

 R24 RESISTOR-G155-14701-01,4.7KOHMA
     2     SG @TIMECARD_LIB.TIMECARD(SCH_1):SG   I167 @TIMECARD_LIB.TIMECARD(SCH_1):PAGE5
     1 SEC_EEPROM_WP @TIMECARD_LIB.TIMECARD(SCH_1):SEC_EEPROM_WP   I167 @TIMECARD_LIB.TIMECARD(SCH_1):PAGE5

 R25 RESISTOR-G155-14701-01,4.7KOHMA
     2 UNNAMED_3_G2201019801_I100_EN @TIMECARD_LIB.TIMECARD(SCH_1):UNNAMED_3_G2201019801_I100_EN   I103 @TIMECARD_LIB.TIMECARD(SCH_1):PAGE3
     1 XP3R3V_FPGA @TIMECARD_LIB.TIMECARD(SCH_1):XP3R3V_FPGA   I103 @TIMECARD_LIB.TIMECARD(SCH_1):PAGE3

 R26 RESISTOR-G155-133R0-01,33OHM,1%
     2 R_PCA9546_I2C_SDA @TIMECARD_LIB.TIMECARD(SCH_1):R_PCA9546_I2C_SDA    I69 @TIMECARD_LIB.TIMECARD(SCH_1):PAGE5
     1 PCIE_SMDAT @TIMECARD_LIB.TIMECARD(SCH_1):PCIE_SMDAT    I69 @TIMECARD_LIB.TIMECARD(SCH_1):PAGE5

 R27 RESISTOR-G155-133R0-01,33OHM,1%
     2 R_PCA9546_I2C_SCL @TIMECARD_LIB.TIMECARD(SCH_1):R_PCA9546_I2C_SCL    I72 @TIMECARD_LIB.TIMECARD(SCH_1):PAGE5
     1 PCIE_SMCLK @TIMECARD_LIB.TIMECARD(SCH_1):PCIE_SMCLK    I72 @TIMECARD_LIB.TIMECARD(SCH_1):PAGE5

 R28 RESISTOR-G155-100R0-J0,0OHM,-
     2 FPGA_TCK @TIMECARD_LIB.TIMECARD(SCH_1):FPGA_TCK    I54 @TIMECARD_LIB.TIMECARD(SCH_1):PAGE3
     1 PCIE_CONN_TCK @TIMECARD_LIB.TIMECARD(SCH_1):PCIE_CONN_TCK    I54 @TIMECARD_LIB.TIMECARD(SCH_1):PAGE3

 R29 RESISTOR-G155-11003-01,100KOHMA
     2 XP5R0V_AGND @TIMECARD_LIB.TIMECARD(SCH_1):XP5R0V_AGND    I12 @TIMECARD_LIB.TIMECARD(SCH_1):PAGE516
     1 XP5R0V_RT @TIMECARD_LIB.TIMECARD(SCH_1):XP5R0V_RT    I12 @TIMECARD_LIB.TIMECARD(SCH_1):PAGE516

 R30 RESISTOR-G155-12201-01,2.2KOHMA
     2 UNNAMED_516_CAPACITOR_I13_1 @TIMECARD_LIB.TIMECARD(SCH_1):UNNAMED_516_CAPACITOR_I13_1    I14 @TIMECARD_LIB.TIMECARD(SCH_1):PAGE516
     1 XP5R0V_COMP @TIMECARD_LIB.TIMECARD(SCH_1):XP5R0V_COMP    I14 @TIMECARD_LIB.TIMECARD(SCH_1):PAGE516

 R31 RESISTOR-G155-100R0-J0,0OHM,-
     2 UNNAMED_516_CAPACITOR_I27_1 @TIMECARD_LIB.TIMECARD(SCH_1):UNNAMED_516_CAPACITOR_I27_1    I26 @TIMECARD_LIB.TIMECARD(SCH_1):PAGE516
     1 XP5R0V_BT @TIMECARD_LIB.TIMECARD(SCH_1):XP5R0V_BT    I26 @TIMECARD_LIB.TIMECARD(SCH_1):PAGE516

 R32 RESISTOR-G155-03241-01,3.24KOHA
     2 XP5R0V_AGND @TIMECARD_LIB.TIMECARD(SCH_1):XP5R0V_AGND    I25 @TIMECARD_LIB.TIMECARD(SCH_1):PAGE516
     1 XP5R0V_FB_R_TO_AGND @TIMECARD_LIB.TIMECARD(SCH_1):XP5R0V_FB_R_TO_AGND    I25 @TIMECARD_LIB.TIMECARD(SCH_1):PAGE516

 R33 RESISTOR-G157-12R20-01,2.2OHM,A
     2     SG @TIMECARD_LIB.TIMECARD(SCH_1):SG    I38 @TIMECARD_LIB.TIMECARD(SCH_1):PAGE516
     1 UNNAMED_516_CAPACITOR_I37_2 @TIMECARD_LIB.TIMECARD(SCH_1):UNNAMED_516_CAPACITOR_I37_2    I38 @TIMECARD_LIB.TIMECARD(SCH_1):PAGE516

 R34 RESISTOR-G155-02402-01,24KOHM,A
     2 XP5R0V_FB_R_TO_AGND @TIMECARD_LIB.TIMECARD(SCH_1):XP5R0V_FB_R_TO_AGND    I30 @TIMECARD_LIB.TIMECARD(SCH_1):PAGE516
     1 UNNAMED_516_CAPACITOR_I29_1 @TIMECARD_LIB.TIMECARD(SCH_1):UNNAMED_516_CAPACITOR_I29_1    I30 @TIMECARD_LIB.TIMECARD(SCH_1):PAGE516

 R35 RESISTOR-G155-11003-01,100KOHMA
     2 XP3R3V_AGND @TIMECARD_LIB.TIMECARD(SCH_1):XP3R3V_AGND    I10 @TIMECARD_LIB.TIMECARD(SCH_1):PAGE517
     1 XP3R3V_RT @TIMECARD_LIB.TIMECARD(SCH_1):XP3R3V_RT    I10 @TIMECARD_LIB.TIMECARD(SCH_1):PAGE517

 R36 RESISTOR-G155-11002-01,10KOHM,A
     2 UNNAMED_517_CAPACITOR_I17_1 @TIMECARD_LIB.TIMECARD(SCH_1):UNNAMED_517_CAPACITOR_I17_1    I18 @TIMECARD_LIB.TIMECARD(SCH_1):PAGE517
     1 XP3R3V_COMP @TIMECARD_LIB.TIMECARD(SCH_1):XP3R3V_COMP    I18 @TIMECARD_LIB.TIMECARD(SCH_1):PAGE517

 R37 RESISTOR-G155-100R0-J0,0OHM,-
     2 UNNAMED_517_CAPACITOR_I27_1 @TIMECARD_LIB.TIMECARD(SCH_1):UNNAMED_517_CAPACITOR_I27_1    I25 @TIMECARD_LIB.TIMECARD(SCH_1):PAGE517
     1 XP3R3V_BT @TIMECARD_LIB.TIMECARD(SCH_1):XP3R3V_BT    I25 @TIMECARD_LIB.TIMECARD(SCH_1):PAGE517

 R38 RESISTOR-G155-04421-01,4.42KOHA
     2 XP3R3V_AGND @TIMECARD_LIB.TIMECARD(SCH_1):XP3R3V_AGND    I26 @TIMECARD_LIB.TIMECARD(SCH_1):PAGE517
     1 XP3R3V_FB_R_TO_AGND @TIMECARD_LIB.TIMECARD(SCH_1):XP3R3V_FB_R_TO_AGND    I26 @TIMECARD_LIB.TIMECARD(SCH_1):PAGE517

 R39 RESISTOR-G157-12R20-01,2.2OHM,A
     2     SG @TIMECARD_LIB.TIMECARD(SCH_1):SG    I32 @TIMECARD_LIB.TIMECARD(SCH_1):PAGE517
     1 UNNAMED_517_CAPACITOR_I29_2 @TIMECARD_LIB.TIMECARD(SCH_1):UNNAMED_517_CAPACITOR_I29_2    I32 @TIMECARD_LIB.TIMECARD(SCH_1):PAGE517

 R40 RESISTOR-G155-12002-01,20KOHM,A
     2 XP3R3V_FB_R_TO_AGND @TIMECARD_LIB.TIMECARD(SCH_1):XP3R3V_FB_R_TO_AGND    I31 @TIMECARD_LIB.TIMECARD(SCH_1):PAGE517
     1 UNNAMED_517_CAPACITOR_I30_1 @TIMECARD_LIB.TIMECARD(SCH_1):UNNAMED_517_CAPACITOR_I30_1    I31 @TIMECARD_LIB.TIMECARD(SCH_1):PAGE517

 R41 RESISTOR-G155-100R0-J0,0OHM,-
     2 FPGA_TDI @TIMECARD_LIB.TIMECARD(SCH_1):FPGA_TDI    I53 @TIMECARD_LIB.TIMECARD(SCH_1):PAGE3
     1 PCIE_CONN_TDI @TIMECARD_LIB.TIMECARD(SCH_1):PCIE_CONN_TDI    I53 @TIMECARD_LIB.TIMECARD(SCH_1):PAGE3

 R42 RESISTOR-G155-100R0-J0,0OHM,-
     2 FPGA_TDO @TIMECARD_LIB.TIMECARD(SCH_1):FPGA_TDO    I52 @TIMECARD_LIB.TIMECARD(SCH_1):PAGE3
     1 PCIE_CONN_TDO @TIMECARD_LIB.TIMECARD(SCH_1):PCIE_CONN_TDO    I52 @TIMECARD_LIB.TIMECARD(SCH_1):PAGE3

 R43 RESISTOR-G155-100R0-J0,0OHM,-
     2 FPGA_TMS @TIMECARD_LIB.TIMECARD(SCH_1):FPGA_TMS    I51 @TIMECARD_LIB.TIMECARD(SCH_1):PAGE3
     1 PCIE_CONN_TMS @TIMECARD_LIB.TIMECARD(SCH_1):PCIE_CONN_TMS    I51 @TIMECARD_LIB.TIMECARD(SCH_1):PAGE3

 R44 RESISTOR-G155-14701-01,4.7KOHMA
     2 UNNAMED_527_POWERMOS3PNCHV1_I23 @TIMECARD_LIB.TIMECARD(SCH_1):UNNAMED_527_POWERMOS3PNCHV1_I232_D   I233 @TIMECARD_LIB.TIMECARD(SCH_1):PAGE527
     1 XP5R0V_MAC @TIMECARD_LIB.TIMECARD(SCH_1):XP5R0V_MAC   I233 @TIMECARD_LIB.TIMECARD(SCH_1):PAGE527

 R45 RESISTOR-G155-133R0-01,33OHM,1%
     2 SEC_EEPROM_SDA @TIMECARD_LIB.TIMECARD(SCH_1):SEC_EEPROM_SDA   I162 @TIMECARD_LIB.TIMECARD(SCH_1):PAGE5
     1 EEPROM_SDA @TIMECARD_LIB.TIMECARD(SCH_1):EEPROM_SDA   I162 @TIMECARD_LIB.TIMECARD(SCH_1):PAGE5

 R46 RESISTOR-G155-02672-01,26.7K,1%
     2 XP12R0V_A_ISET @TIMECARD_LIB.TIMECARD(SCH_1):XP12R0V_A_ISET   I171 @TIMECARD_LIB.TIMECARD(SCH_1):PAGE15
     1     SG @TIMECARD_LIB.TIMECARD(SCH_1):SG   I171 @TIMECARD_LIB.TIMECARD(SCH_1):PAGE15

 R47 RESISTOR-G155-11002-01,10KOHM,A
     2 XP5R0V_PG @TIMECARD_LIB.TIMECARD(SCH_1):XP5R0V_PG     I1 @TIMECARD_LIB.TIMECARD(SCH_1):PAGE516
     1 XP3R3V @TIMECARD_LIB.TIMECARD(SCH_1):XP3R3V     I1 @TIMECARD_LIB.TIMECARD(SCH_1):PAGE516

 R48 RESISTOR-A155-05101-DL,5.1KOHMA
     2     SG @TIMECARD_LIB.TIMECARD(SCH_1):SG     I9 @TIMECARD_LIB.TIMECARD(SCH_1):PAGE516
     1 R_XP5R0V_EN @TIMECARD_LIB.TIMECARD(SCH_1):R_XP5R0V_EN     I9 @TIMECARD_LIB.TIMECARD(SCH_1):PAGE516

 R49 RESISTOR-G155-11002-01,10KOHM,A
     2 R_XP5R0V_EN @TIMECARD_LIB.TIMECARD(SCH_1):R_XP5R0V_EN    I16 @TIMECARD_LIB.TIMECARD(SCH_1):PAGE516
     1 VIN_XP5R0V @TIMECARD_LIB.TIMECARD(SCH_1):VIN_XP5R0V    I16 @TIMECARD_LIB.TIMECARD(SCH_1):PAGE516

 R50 RESISTOR-G156-100R0-J0,0OHM,-
     2 XP5R0V_FB_R_TO_AGND @TIMECARD_LIB.TIMECARD(SCH_1):XP5R0V_FB_R_TO_AGND    I28 @TIMECARD_LIB.TIMECARD(SCH_1):PAGE516
     1 XP5R0V_AGND @TIMECARD_LIB.TIMECARD(SCH_1):XP5R0V_AGND    I28 @TIMECARD_LIB.TIMECARD(SCH_1):PAGE516

 R51 RESISTOR-G155-11002-01,10KOHM,A
     2 R_XP3R3V_PG @TIMECARD_LIB.TIMECARD(SCH_1):R_XP3R3V_PG     I3 @TIMECARD_LIB.TIMECARD(SCH_1):PAGE517
     1 XP3R3V @TIMECARD_LIB.TIMECARD(SCH_1):XP3R3V     I3 @TIMECARD_LIB.TIMECARD(SCH_1):PAGE517

 R52 RESISTOR-G155-05101-01,5.1KOHMA
     2     SG @TIMECARD_LIB.TIMECARD(SCH_1):SG    I11 @TIMECARD_LIB.TIMECARD(SCH_1):PAGE517
     1 XP3R3V_EN @TIMECARD_LIB.TIMECARD(SCH_1):XP3R3V_EN    I11 @TIMECARD_LIB.TIMECARD(SCH_1):PAGE517

 R53 RESISTOR-G152-10344-01,30KOHM,A
     2 XP3R3V_EN @TIMECARD_LIB.TIMECARD(SCH_1):XP3R3V_EN    I13 @TIMECARD_LIB.TIMECARD(SCH_1):PAGE517
     1 VIN_XP3R3 @TIMECARD_LIB.TIMECARD(SCH_1):VIN_XP3R3    I13 @TIMECARD_LIB.TIMECARD(SCH_1):PAGE517

 R54 RESISTOR-G156-100R0-J0,0OHM,-
     2 XP3R3V_FB_R_TO_AGND @TIMECARD_LIB.TIMECARD(SCH_1):XP3R3V_FB_R_TO_AGND    I41 @TIMECARD_LIB.TIMECARD(SCH_1):PAGE517
     1 XP3R3V_AGND @TIMECARD_LIB.TIMECARD(SCH_1):XP3R3V_AGND    I41 @TIMECARD_LIB.TIMECARD(SCH_1):PAGE517

 R55 RESISTOR-G155-14701-01,4.7KOHMA
     2     SG @TIMECARD_LIB.TIMECARD(SCH_1):SG    I62 @TIMECARD_LIB.TIMECARD(SCH_1):PAGE3
     1 PCIE_CONN_PERST_N @TIMECARD_LIB.TIMECARD(SCH_1):PCIE_CONN_PERST_N    I62 @TIMECARD_LIB.TIMECARD(SCH_1):PAGE3

 R56 RESISTOR-G155-14701-01,4.7KOHMA
     2 PCIE_CONN_PERST_N @TIMECARD_LIB.TIMECARD(SCH_1):PCIE_CONN_PERST_N    I63 @TIMECARD_LIB.TIMECARD(SCH_1):PAGE3
     1 XP3R3V @TIMECARD_LIB.TIMECARD(SCH_1):XP3R3V    I63 @TIMECARD_LIB.TIMECARD(SCH_1):PAGE3

 R57 RESISTOR-G155-133R0-01,33OHM,1%
     2 PCIE_PERST_N @TIMECARD_LIB.TIMECARD(SCH_1):PCIE_PERST_N   I153 @TIMECARD_LIB.TIMECARD(SCH_1):PAGE3
     1 BF_PCIE_PERST_N @TIMECARD_LIB.TIMECARD(SCH_1):BF_PCIE_PERST_N   I153 @TIMECARD_LIB.TIMECARD(SCH_1):PAGE3

 R58 RESISTOR-G155-133R0-01,33OHM,1%
     2 R_PCA9546_I2C_SDA @TIMECARD_LIB.TIMECARD(SCH_1):R_PCA9546_I2C_SDA    I88 @TIMECARD_LIB.TIMECARD(SCH_1):PAGE5
     1 UNNAMED_5_CONNHDR2X2MSSMT_I126_ @TIMECARD_LIB.TIMECARD(SCH_1):UNNAMED_5_CONNHDR2X2MSSMT_I126_1    I88 @TIMECARD_LIB.TIMECARD(SCH_1):PAGE5

 R59 RESISTOR-G155-133R0-01,33OHM,1%
     2 R_PCA9546_I2C_SCL @TIMECARD_LIB.TIMECARD(SCH_1):R_PCA9546_I2C_SCL     I4 @TIMECARD_LIB.TIMECARD(SCH_1):PAGE5
     1 UNNAMED_5_CONNHDR2X2MSSMT_I12_1 @TIMECARD_LIB.TIMECARD(SCH_1):UNNAMED_5_CONNHDR2X2MSSMT_I126_3     I4 @TIMECARD_LIB.TIMECARD(SCH_1):PAGE5

 R60 RESISTOR-G155-133R0-01,33OHM,1%
     2 PCA9546_RST_N @TIMECARD_LIB.TIMECARD(SCH_1):PCA9546_RST_N   I125 @TIMECARD_LIB.TIMECARD(SCH_1):PAGE5
     1 FPGA_OUT_PCA9546_RST_N @TIMECARD_LIB.TIMECARD(SCH_1):FPGA_OUT_PCA9546_RST_N   I125 @TIMECARD_LIB.TIMECARD(SCH_1):PAGE5

 R61 RESISTOR-G155-100R0-J0,0OHM,-
     2 XP2R5V_FPGA @TIMECARD_LIB.TIMECARD(SCH_1):XP2R5V_FPGA    I52 @TIMECARD_LIB.TIMECARD(SCH_1):PAGE5
     1 VDD_PCA9546A @TIMECARD_LIB.TIMECARD(SCH_1):VDD_PCA9546A    I52 @TIMECARD_LIB.TIMECARD(SCH_1):PAGE5

 R62 RESISTOR-G155-100R0-J0,0OHM,-
     2 XP3R3V_FPGA @TIMECARD_LIB.TIMECARD(SCH_1):XP3R3V_FPGA    I55 @TIMECARD_LIB.TIMECARD(SCH_1):PAGE5
     1 VDD_PCA9546A @TIMECARD_LIB.TIMECARD(SCH_1):VDD_PCA9546A    I55 @TIMECARD_LIB.TIMECARD(SCH_1):PAGE5

 R63 RESISTOR-G155-14701-01,4.7KOHMA
     2 PCIE_PERST_N @TIMECARD_LIB.TIMECARD(SCH_1):PCIE_PERST_N   I144 @TIMECARD_LIB.TIMECARD(SCH_1):PAGE3
     1 XP3R3V_FPGA @TIMECARD_LIB.TIMECARD(SCH_1):XP3R3V_FPGA   I144 @TIMECARD_LIB.TIMECARD(SCH_1):PAGE3

 R64 RESISTOR-G155-14701-01,4.7KOHMA
     2 SHT3X_I2C_SDA @TIMECARD_LIB.TIMECARD(SCH_1):SHT3X_I2C_SDA     I3 @TIMECARD_LIB.TIMECARD(SCH_1):PAGE7
     1 XP3R3V_FPGA @TIMECARD_LIB.TIMECARD(SCH_1):XP3R3V_FPGA     I3 @TIMECARD_LIB.TIMECARD(SCH_1):PAGE7

 R65 RESISTOR-G155-14701-01,4.7KOHMA
     2 SHT3X_I2C_SCL @TIMECARD_LIB.TIMECARD(SCH_1):SHT3X_I2C_SCL     I4 @TIMECARD_LIB.TIMECARD(SCH_1):PAGE7
     1 XP3R3V_FPGA @TIMECARD_LIB.TIMECARD(SCH_1):XP3R3V_FPGA     I4 @TIMECARD_LIB.TIMECARD(SCH_1):PAGE7

 R66 RESISTOR-G155-133R0-01,33OHM,1%
     2 R_SHT3X_I2C_SDA @TIMECARD_LIB.TIMECARD(SCH_1):R_SHT3X_I2C_SDA    I14 @TIMECARD_LIB.TIMECARD(SCH_1):PAGE7
     1 SHT3X_I2C_SDA @TIMECARD_LIB.TIMECARD(SCH_1):SHT3X_I2C_SDA    I14 @TIMECARD_LIB.TIMECARD(SCH_1):PAGE7

 R67 RESISTOR-G155-133R0-01,33OHM,1%
     2 R_SHT3X_I2C_SCL @TIMECARD_LIB.TIMECARD(SCH_1):R_SHT3X_I2C_SCL    I13 @TIMECARD_LIB.TIMECARD(SCH_1):PAGE7
     1 SHT3X_I2C_SCL @TIMECARD_LIB.TIMECARD(SCH_1):SHT3X_I2C_SCL    I13 @TIMECARD_LIB.TIMECARD(SCH_1):PAGE7

 R68 RESISTOR-G155-14701-01,4.7KOHMA
     2 SHT3X_ADDR @TIMECARD_LIB.TIMECARD(SCH_1):SHT3X_ADDR     I8 @TIMECARD_LIB.TIMECARD(SCH_1):PAGE7
     1 XP3R3V_FPGA @TIMECARD_LIB.TIMECARD(SCH_1):XP3R3V_FPGA     I8 @TIMECARD_LIB.TIMECARD(SCH_1):PAGE7

 R69 RESISTOR-G155-11001-01,1KOHM,1%
     2     SG @TIMECARD_LIB.TIMECARD(SCH_1):SG     I7 @TIMECARD_LIB.TIMECARD(SCH_1):PAGE7
     1 SHT3X_ADDR @TIMECARD_LIB.TIMECARD(SCH_1):SHT3X_ADDR     I7 @TIMECARD_LIB.TIMECARD(SCH_1):PAGE7

 R70 RESISTOR-G155-14701-01,4.7KOHMA
     2 BF_ICP10100_I2C_SDA @TIMECARD_LIB.TIMECARD(SCH_1):BF_ICP10100_I2C_SDA     I3 @TIMECARD_LIB.TIMECARD(SCH_1):PAGE8
     1 XP1R8V_ICP10100 @TIMECARD_LIB.TIMECARD(SCH_1):XP1R8V_ICP10100     I3 @TIMECARD_LIB.TIMECARD(SCH_1):PAGE8

 R71 RESISTOR-G155-14701-01,4.7KOHMA
     2 BF_ICP10100_I2C_SCL @TIMECARD_LIB.TIMECARD(SCH_1):BF_ICP10100_I2C_SCL     I5 @TIMECARD_LIB.TIMECARD(SCH_1):PAGE8
     1 XP1R8V_ICP10100 @TIMECARD_LIB.TIMECARD(SCH_1):XP1R8V_ICP10100     I5 @TIMECARD_LIB.TIMECARD(SCH_1):PAGE8

 R72 RESISTOR-G155-133R0-01,33OHM,1%
     2 R_ICP10100_I2C_SDA @TIMECARD_LIB.TIMECARD(SCH_1):R_ICP10100_I2C_SDA     I7 @TIMECARD_LIB.TIMECARD(SCH_1):PAGE8
     1 BF_ICP10100_I2C_SDA @TIMECARD_LIB.TIMECARD(SCH_1):BF_ICP10100_I2C_SDA     I7 @TIMECARD_LIB.TIMECARD(SCH_1):PAGE8

 R73 RESISTOR-G155-133R0-01,33OHM,1%
     2 R_ICP10100_I2C_SCL @TIMECARD_LIB.TIMECARD(SCH_1):R_ICP10100_I2C_SCL     I6 @TIMECARD_LIB.TIMECARD(SCH_1):PAGE8
     1 BF_ICP10100_I2C_SCL @TIMECARD_LIB.TIMECARD(SCH_1):BF_ICP10100_I2C_SCL     I6 @TIMECARD_LIB.TIMECARD(SCH_1):PAGE8

 R74 RESISTOR-G155-14701-01,4.7KOHMA
     2 BNO080_I2C_SDA @TIMECARD_LIB.TIMECARD(SCH_1):BNO080_I2C_SDA     I6 @TIMECARD_LIB.TIMECARD(SCH_1):PAGE9
     1 XP3R3V_FPGA @TIMECARD_LIB.TIMECARD(SCH_1):XP3R3V_FPGA     I6 @TIMECARD_LIB.TIMECARD(SCH_1):PAGE9

 R75 RESISTOR-G155-14701-01,4.7KOHMA
     2 BNO080_I2C_SCL @TIMECARD_LIB.TIMECARD(SCH_1):BNO080_I2C_SCL     I7 @TIMECARD_LIB.TIMECARD(SCH_1):PAGE9
     1 XP3R3V_FPGA @TIMECARD_LIB.TIMECARD(SCH_1):XP3R3V_FPGA     I7 @TIMECARD_LIB.TIMECARD(SCH_1):PAGE9

 R76 RESISTOR-G155-133R0-01,33OHM,1%
     2 R_BNO080_I2C_SDA @TIMECARD_LIB.TIMECARD(SCH_1):R_BNO080_I2C_SDA    I12 @TIMECARD_LIB.TIMECARD(SCH_1):PAGE9
     1 BNO080_I2C_SDA @TIMECARD_LIB.TIMECARD(SCH_1):BNO080_I2C_SDA    I12 @TIMECARD_LIB.TIMECARD(SCH_1):PAGE9

 R77 RESISTOR-G155-133R0-01,33OHM,1%
     2 R_BNO080_I2C_SCL @TIMECARD_LIB.TIMECARD(SCH_1):R_BNO080_I2C_SCL    I11 @TIMECARD_LIB.TIMECARD(SCH_1):PAGE9
     1 BNO080_I2C_SCL @TIMECARD_LIB.TIMECARD(SCH_1):BNO080_I2C_SCL    I11 @TIMECARD_LIB.TIMECARD(SCH_1):PAGE9

 R78 RESISTOR-G155-133R0-01,33OHM,1%
     2 FPGA_OUT_BNO080_RST_N @TIMECARD_LIB.TIMECARD(SCH_1):FPGA_OUT_BNO080_RST_N    I41 @TIMECARD_LIB.TIMECARD(SCH_1):PAGE9
     1 R_BNO080_RST_N @TIMECARD_LIB.TIMECARD(SCH_1):R_BNO080_RST_N    I41 @TIMECARD_LIB.TIMECARD(SCH_1):PAGE9

 R79 RESISTOR-G155-133R0-01,33OHM,1%
     2 R_BNO080_INT_N @TIMECARD_LIB.TIMECARD(SCH_1):R_BNO080_INT_N    I31 @TIMECARD_LIB.TIMECARD(SCH_1):PAGE9
     1 FPGA_IN_BNO080_INT_N @TIMECARD_LIB.TIMECARD(SCH_1):FPGA_IN_BNO080_INT_N    I31 @TIMECARD_LIB.TIMECARD(SCH_1):PAGE9

 R80 RESISTOR-G155-133R0-01,33OHM,1%
     2 R_BNO080_BOOT_N @TIMECARD_LIB.TIMECARD(SCH_1):R_BNO080_BOOT_N    I32 @TIMECARD_LIB.TIMECARD(SCH_1):PAGE9
     1 FPGA_OUT_BNO080_BOOT_N @TIMECARD_LIB.TIMECARD(SCH_1):FPGA_OUT_BNO080_BOOT_N    I32 @TIMECARD_LIB.TIMECARD(SCH_1):PAGE9

 R81 RESISTOR-G155-133R0-01,33OHM,1%
     2 DBG_UART_MAC_RX @TIMECARD_LIB.TIMECARD(SCH_1):DBG_UART_MAC_RX   I240 @TIMECARD_LIB.TIMECARD(SCH_1):PAGE527
     1 R_MAC_UART_RX_FPGA_TX @TIMECARD_LIB.TIMECARD(SCH_1):R_MAC_UART_RX_FPGA_TX   I240 @TIMECARD_LIB.TIMECARD(SCH_1):PAGE527

 R82 RESISTOR-G155-133R0-01,33OHM,1%
     2 DBG_UART_MAC_TX @TIMECARD_LIB.TIMECARD(SCH_1):DBG_UART_MAC_TX   I241 @TIMECARD_LIB.TIMECARD(SCH_1):PAGE527
     1 R_MAC_UART_TX_FPGA_RX @TIMECARD_LIB.TIMECARD(SCH_1):R_MAC_UART_TX_FPGA_RX   I241 @TIMECARD_LIB.TIMECARD(SCH_1):PAGE527

 R83 RESISTOR-G155-100R0-J0,0OHM,-
     2 R_MAC_PPS_IN1P @TIMECARD_LIB.TIMECARD(SCH_1):R_MAC_PPS_IN1P    I32 @TIMECARD_LIB.TIMECARD(SCH_1):PAGE527
     1 FPGA_OUT_MAC_PPS_IN1P @TIMECARD_LIB.TIMECARD(SCH_1):FPGA_OUT_MAC_PPS_IN1P    I32 @TIMECARD_LIB.TIMECARD(SCH_1):PAGE527

 R84 RESISTOR-G155-100R0-J0,0OHM,-
     2 R_MAC_PPS_IN1N @TIMECARD_LIB.TIMECARD(SCH_1):R_MAC_PPS_IN1N    I31 @TIMECARD_LIB.TIMECARD(SCH_1):PAGE527
     1 FPGA_OUT_MAC_PPS_IN1N @TIMECARD_LIB.TIMECARD(SCH_1):FPGA_OUT_MAC_PPS_IN1N    I31 @TIMECARD_LIB.TIMECARD(SCH_1):PAGE527

 R85 RESISTOR-G155-100R0-J0,0OHM,-
     2 R_MAC_PPS_IN0P @TIMECARD_LIB.TIMECARD(SCH_1):R_MAC_PPS_IN0P    I30 @TIMECARD_LIB.TIMECARD(SCH_1):PAGE527
     1 FPGA_OUT_MAC_PPS_IN0P @TIMECARD_LIB.TIMECARD(SCH_1):FPGA_OUT_MAC_PPS_IN0P    I30 @TIMECARD_LIB.TIMECARD(SCH_1):PAGE527

 R86 RESISTOR-G155-100R0-J0,0OHM,-
     2 R_MAC_PPS_IN0N @TIMECARD_LIB.TIMECARD(SCH_1):R_MAC_PPS_IN0N    I29 @TIMECARD_LIB.TIMECARD(SCH_1):PAGE527
     1 FPGA_OUT_MAC_PPS_IN0N @TIMECARD_LIB.TIMECARD(SCH_1):FPGA_OUT_MAC_PPS_IN0N    I29 @TIMECARD_LIB.TIMECARD(SCH_1):PAGE527

 R87 RESISTOR-G155-100R0-J0,0OHM,-
     2 R_MAC_PPS_OUTP @TIMECARD_LIB.TIMECARD(SCH_1):R_MAC_PPS_OUTP    I14 @TIMECARD_LIB.TIMECARD(SCH_1):PAGE527
     1 FPGA_IN_MAC_PPS_OUTP @TIMECARD_LIB.TIMECARD(SCH_1):FPGA_IN_MAC_PPS_OUTP    I14 @TIMECARD_LIB.TIMECARD(SCH_1):PAGE527

 R88 RESISTOR-G155-100R0-J0,0OHM,-
     2 R_MAC_PPS_OUTN @TIMECARD_LIB.TIMECARD(SCH_1):R_MAC_PPS_OUTN    I13 @TIMECARD_LIB.TIMECARD(SCH_1):PAGE527
     1 FPGA_IN_MAC_PPS_OUTN @TIMECARD_LIB.TIMECARD(SCH_1):FPGA_IN_MAC_PPS_OUTN    I13 @TIMECARD_LIB.TIMECARD(SCH_1):PAGE527

 R89 RESISTOR-G155-11000-01,100OHM,A
     2 R_MAC_PPS_IN1N @TIMECARD_LIB.TIMECARD(SCH_1):R_MAC_PPS_IN1N    I34 @TIMECARD_LIB.TIMECARD(SCH_1):PAGE527
     1 R_MAC_PPS_IN1P @TIMECARD_LIB.TIMECARD(SCH_1):R_MAC_PPS_IN1P    I34 @TIMECARD_LIB.TIMECARD(SCH_1):PAGE527

 R90 RESISTOR-G155-11000-01,100OHM,A
     2 R_MAC_PPS_IN0P @TIMECARD_LIB.TIMECARD(SCH_1):R_MAC_PPS_IN0P    I33 @TIMECARD_LIB.TIMECARD(SCH_1):PAGE527
     1 R_MAC_PPS_IN0N @TIMECARD_LIB.TIMECARD(SCH_1):R_MAC_PPS_IN0N    I33 @TIMECARD_LIB.TIMECARD(SCH_1):PAGE527

 R91 RESISTOR-G155-133R0-01,33OHM,1%
     2 SMA_ANALOG_TUNING_IN @TIMECARD_LIB.TIMECARD(SCH_1):SMA_ANALOG_TUNING_IN   I187 @TIMECARD_LIB.TIMECARD(SCH_1):PAGE527
     1 ANALOG_TUNING_IN @TIMECARD_LIB.TIMECARD(SCH_1):ANALOG_TUNING_IN   I187 @TIMECARD_LIB.TIMECARD(SCH_1):PAGE527

 R92 RESISTOR-G155-11000-01,100OHM,A
     2 FPGA_IN_MAC_10MHZ_OUT @TIMECARD_LIB.TIMECARD(SCH_1):FPGA_IN_MAC_10MHZ_OUT    I55 @TIMECARD_LIB.TIMECARD(SCH_1):PAGE527
     1 R_MAC_10MHZ_RF_OUT @TIMECARD_LIB.TIMECARD(SCH_1):R_MAC_10MHZ_RF_OUT    I55 @TIMECARD_LIB.TIMECARD(SCH_1):PAGE527

 R93 RESISTOR-G155-133R0-01,33OHM,1%
     2 FPGA_IN_MAC_BITEOUT @TIMECARD_LIB.TIMECARD(SCH_1):FPGA_IN_MAC_BITE OUT    I53 @TIMECARD_LIB.TIMECARD(SCH_1):PAGE527
     1 R_MAC_BITEOUT @TIMECARD_LIB.TIMECARD(SCH_1):R_MAC_BITE OUT    I53 @TIMECARD_LIB.TIMECARD(SCH_1):PAGE527

 R94 RESISTOR-G155-133R0-01,33OHM,1%
     2 UART_MAC_TX_FPGA_RX @TIMECARD_LIB.TIMECARD(SCH_1):UART_MAC_TX_FPGA_RX    I54 @TIMECARD_LIB.TIMECARD(SCH_1):PAGE527
     1 R_MAC_UART_TX_FPGA_RX @TIMECARD_LIB.TIMECARD(SCH_1):R_MAC_UART_TX_FPGA_RX    I54 @TIMECARD_LIB.TIMECARD(SCH_1):PAGE527

 R95 RESISTOR-G155-133R0-01,33OHM,1%
     2 UART_MAC_RX_FPGA_TX @TIMECARD_LIB.TIMECARD(SCH_1):UART_MAC_RX_FPGA_TX    I52 @TIMECARD_LIB.TIMECARD(SCH_1):PAGE527
     1 R_MAC_UART_RX_FPGA_TX @TIMECARD_LIB.TIMECARD(SCH_1):R_MAC_UART_RX_FPGA_TX    I52 @TIMECARD_LIB.TIMECARD(SCH_1):PAGE527

 R96 RESISTOR-G155-133R0-01,33OHM,1%
     2 FPGA_IN_MAC_ALARM_OUT_N @TIMECARD_LIB.TIMECARD(SCH_1):FPGA_IN_MAC_ALARM_OUT_N    I23 @TIMECARD_LIB.TIMECARD(SCH_1):PAGE527
     1 MAC_ALARM @TIMECARD_LIB.TIMECARD(SCH_1):MAC_ALARM    I23 @TIMECARD_LIB.TIMECARD(SCH_1):PAGE527

 R97 RESISTOR-G155-100R0-J0,0OHM,-
     2 MUX_USB_DP @TIMECARD_LIB.TIMECARD(SCH_1):MUX_USB_DP   I176 @TIMECARD_LIB.TIMECARD(SCH_1):PAGE527
     1 R_MAC_USB_DP @TIMECARD_LIB.TIMECARD(SCH_1):R_MAC_USB_DP   I176 @TIMECARD_LIB.TIMECARD(SCH_1):PAGE527

 R98 RESISTOR-G155-100R0-J0,0OHM,-
     2 MUX_USB_DM @TIMECARD_LIB.TIMECARD(SCH_1):MUX_USB_DM   I175 @TIMECARD_LIB.TIMECARD(SCH_1):PAGE527
     1 R_MAC_USB_DM @TIMECARD_LIB.TIMECARD(SCH_1):R_MAC_USB_DM   I175 @TIMECARD_LIB.TIMECARD(SCH_1):PAGE527

 R99 RESISTOR-G155-14701-01,4.7KOHMA
     2     SG @TIMECARD_LIB.TIMECARD(SCH_1):SG   I149 @TIMECARD_LIB.TIMECARD(SCH_1):PAGE527
     1 FPGA_OUT_MACUSBPOWER_EN @TIMECARD_LIB.TIMECARD(SCH_1):FPGA_OUT_MACUSBPOWER_EN   I149 @TIMECARD_LIB.TIMECARD(SCH_1):PAGE527

R100 RESISTOR-G155-133R0-01,33OHM,1%
     2 USB_PWR_EN @TIMECARD_LIB.TIMECARD(SCH_1):USB_PWR_EN   I155 @TIMECARD_LIB.TIMECARD(SCH_1):PAGE527
     1 FPGA_OUT_MACUSBPOWER_EN @TIMECARD_LIB.TIMECARD(SCH_1):FPGA_OUT_MACUSBPOWER_EN   I155 @TIMECARD_LIB.TIMECARD(SCH_1):PAGE527

R101 RESISTOR-G155-11001-01,1KOHM,1%
     2 XP5R0V_USB_CONN_DET @TIMECARD_LIB.TIMECARD(SCH_1):XP5R0V_USB_CONN_DET   I200 @TIMECARD_LIB.TIMECARD(SCH_1):PAGE527
     1 XP5R0V_USB_CONN @TIMECARD_LIB.TIMECARD(SCH_1):XP5R0V_USB_CONN   I200 @TIMECARD_LIB.TIMECARD(SCH_1):PAGE527

R102 RESISTOR-G155-11001-01,1KOHM,1%
     2 UNNAMED_527_RESISTOR_I201_2 @TIMECARD_LIB.TIMECARD(SCH_1):UNNAMED_527_RESISTOR_I201_2   I201 @TIMECARD_LIB.TIMECARD(SCH_1):PAGE527
     1 XP5R0V_USB_CONN_DET @TIMECARD_LIB.TIMECARD(SCH_1):XP5R0V_USB_CONN_DET   I201 @TIMECARD_LIB.TIMECARD(SCH_1):PAGE527

R103 RESISTOR-G155-11001-01,1KOHM,1%
     2     SG @TIMECARD_LIB.TIMECARD(SCH_1):SG   I202 @TIMECARD_LIB.TIMECARD(SCH_1):PAGE527
     1 UNNAMED_527_RESISTOR_I201_2 @TIMECARD_LIB.TIMECARD(SCH_1):UNNAMED_527_RESISTOR_I201_2   I202 @TIMECARD_LIB.TIMECARD(SCH_1):PAGE527

R104 RESISTOR-G155-14701-01,4.7KOHMA
     2     SG @TIMECARD_LIB.TIMECARD(SCH_1):SG   I126 @TIMECARD_LIB.TIMECARD(SCH_1):PAGE527
     1 UNNAMED_527_RESISTOR_I126_1 @TIMECARD_LIB.TIMECARD(SCH_1):UNNAMED_527_RESISTOR_I126_1   I126 @TIMECARD_LIB.TIMECARD(SCH_1):PAGE527

R105 RESISTOR-G155-100R0-J0,0OHM,-
     2 MAC_USB_DM @TIMECARD_LIB.TIMECARD(SCH_1):MAC_USB_DM   I123 @TIMECARD_LIB.TIMECARD(SCH_1):PAGE527
     1 MUX_USB_DM @TIMECARD_LIB.TIMECARD(SCH_1):MUX_USB_DM   I123 @TIMECARD_LIB.TIMECARD(SCH_1):PAGE527

R106 RESISTOR-G155-100R0-J0,0OHM,-
     2 MAC_USB_DP @TIMECARD_LIB.TIMECARD(SCH_1):MAC_USB_DP   I124 @TIMECARD_LIB.TIMECARD(SCH_1):PAGE527
     1 MUX_USB_DP @TIMECARD_LIB.TIMECARD(SCH_1):MUX_USB_DP   I124 @TIMECARD_LIB.TIMECARD(SCH_1):PAGE527

R107 RESISTOR-G155-14701-01,4.7KOHMA
     2 FPGA_IN_MAC_USB_OC_N @TIMECARD_LIB.TIMECARD(SCH_1):FPGA_IN_MAC_USB_OC_N    I83 @TIMECARD_LIB.TIMECARD(SCH_1):PAGE527
     1 XP3R3V_FPGA @TIMECARD_LIB.TIMECARD(SCH_1):XP3R3V_FPGA    I83 @TIMECARD_LIB.TIMECARD(SCH_1):PAGE527

R108 RESISTOR-G155-11000-01,100OHM,A
     2 UNNAMED_14_RESISTOR_I58_2 @TIMECARD_LIB.TIMECARD(SCH_1):UNNAMED_14_RESISTOR_I58_2    I58 @TIMECARD_LIB.TIMECARD(SCH_1):PAGE14
     1 UNNAMED_14_OPTICAL_I141_A @TIMECARD_LIB.TIMECARD(SCH_1):UNNAMED_14_OPTICAL_I141_A    I58 @TIMECARD_LIB.TIMECARD(SCH_1):PAGE14

R109 RESISTOR-G155-133R0-01,33OHM,1%
     2 GPS_UART_TXD @TIMECARD_LIB.TIMECARD(SCH_1):GPS_UART_TXD    I11 @TIMECARD_LIB.TIMECARD(SCH_1):PAGE11
     1 UART_GPS_TX_FPGA_RX @TIMECARD_LIB.TIMECARD(SCH_1):UART_GPS_TX_FPGA_RX    I11 @TIMECARD_LIB.TIMECARD(SCH_1):PAGE11

R110 RESISTOR-G155-133R0-01,33OHM,1%
     2 GPS_UART_RXD @TIMECARD_LIB.TIMECARD(SCH_1):GPS_UART_RXD    I29 @TIMECARD_LIB.TIMECARD(SCH_1):PAGE11
     1 UART_GPS_RX_FPGA_TX @TIMECARD_LIB.TIMECARD(SCH_1):UART_GPS_RX_FPGA_TX    I29 @TIMECARD_LIB.TIMECARD(SCH_1):PAGE11

R111 RESISTOR-G155-133R0-01,33OHM,1%
     2 GPSTP2_OUT @TIMECARD_LIB.TIMECARD(SCH_1):GPSTP2_OUT     I5 @TIMECARD_LIB.TIMECARD(SCH_1):PAGE11
     1 FPGA_IN_GPSTP2_OUT @TIMECARD_LIB.TIMECARD(SCH_1):FPGA_IN_GPSTP2_OUT     I5 @TIMECARD_LIB.TIMECARD(SCH_1):PAGE11

R112 RESISTOR-G155-133R0-01,33OHM,1%
     2 GPS_UART_TXD @TIMECARD_LIB.TIMECARD(SCH_1):GPS_UART_TXD     I8 @TIMECARD_LIB.TIMECARD(SCH_1):PAGE11
     1 DBG_UART_GPS_TXD @TIMECARD_LIB.TIMECARD(SCH_1):DBG_UART_GPS_TXD     I8 @TIMECARD_LIB.TIMECARD(SCH_1):PAGE11

R113 RESISTOR-G155-133R0-01,33OHM,1%
     2 GPS_UART_RXD @TIMECARD_LIB.TIMECARD(SCH_1):GPS_UART_RXD     I7 @TIMECARD_LIB.TIMECARD(SCH_1):PAGE11
     1 DBG_UART_GPS_RXD @TIMECARD_LIB.TIMECARD(SCH_1):DBG_UART_GPS_RXD     I7 @TIMECARD_LIB.TIMECARD(SCH_1):PAGE11

R114 RESISTOR-G155-14701-01,4.7KOHMA
     2     SG @TIMECARD_LIB.TIMECARD(SCH_1):SG    I18 @TIMECARD_LIB.TIMECARD(SCH_1):PAGE11
     1 GPS_RST_N @TIMECARD_LIB.TIMECARD(SCH_1):GPS_RST_N    I18 @TIMECARD_LIB.TIMECARD(SCH_1):PAGE11

R115 RESISTOR-G155-14701-01,4.7KOHMA
     2 GPS_RST_N @TIMECARD_LIB.TIMECARD(SCH_1):GPS_RST_N    I21 @TIMECARD_LIB.TIMECARD(SCH_1):PAGE11
     1 XP3R3V_GPS @TIMECARD_LIB.TIMECARD(SCH_1):XP3R3V_GPS    I21 @TIMECARD_LIB.TIMECARD(SCH_1):PAGE11

R116 RESISTOR-G155-133R0-01,33OHM,1%
     2 FPGA_OUT_GPS_RST_N @TIMECARD_LIB.TIMECARD(SCH_1):FPGA_OUT_GPS_RST_N    I25 @TIMECARD_LIB.TIMECARD(SCH_1):PAGE11
     1 GPS_RST_N @TIMECARD_LIB.TIMECARD(SCH_1):GPS_RST_N    I25 @TIMECARD_LIB.TIMECARD(SCH_1):PAGE11

R117 RESISTOR-G155-133R0-01,33OHM,1%
     2 FPGA_IN_GPSTP1_OUT @TIMECARD_LIB.TIMECARD(SCH_1):FPGA_IN_GPSTP1_OUT    I20 @TIMECARD_LIB.TIMECARD(SCH_1):PAGE11
     1 GPSTP1_OUT @TIMECARD_LIB.TIMECARD(SCH_1):GPSTP1_OUT    I20 @TIMECARD_LIB.TIMECARD(SCH_1):PAGE11

R118 RESISTOR-G155-13300-01,330OHM,A
     2 XP3R3V_PCIE @TIMECARD_LIB.TIMECARD(SCH_1):XP3R3V_PCIE   I190 @TIMECARD_LIB.TIMECARD(SCH_1):PAGE14
     1 UNNAMED_14_OPTICAL_I191_A @TIMECARD_LIB.TIMECARD(SCH_1):UNNAMED_14_OPTICAL_I191_A   I190 @TIMECARD_LIB.TIMECARD(SCH_1):PAGE14

R119 RESISTOR-G155-13300-01,330OHM,A
     2 XP3R3V_AUX_PCIE @TIMECARD_LIB.TIMECARD(SCH_1):XP3R3V_AUX_PCIE   I192 @TIMECARD_LIB.TIMECARD(SCH_1):PAGE14
     1 UNNAMED_14_OPTICAL_I194_A @TIMECARD_LIB.TIMECARD(SCH_1):UNNAMED_14_OPTICAL_I194_A   I192 @TIMECARD_LIB.TIMECARD(SCH_1):PAGE14

R120 RESISTOR-G155-11000-01,100OHM,A
     2 UNNAMED_12_74HCT2G125DPTSSOP8_6 @TIMECARD_LIB.TIMECARD(SCH_1):UNNAMED_12_74HCT2G125DPTSSOP8_I255_1A   I265 @TIMECARD_LIB.TIMECARD(SCH_1):PAGE12
     1 ANT1_OUT @TIMECARD_LIB.TIMECARD(SCH_1):ANT1_OUT   I265 @TIMECARD_LIB.TIMECARD(SCH_1):PAGE12

R121 RESISTOR-G155-11000-01,100OHM,A
     2 UNNAMED_12_74HCT2G125DPTSSOP8_9 @TIMECARD_LIB.TIMECARD(SCH_1):UNNAMED_12_74HCT2G125DPTSSOP8_I273_1A   I284 @TIMECARD_LIB.TIMECARD(SCH_1):PAGE12
     1 ANT2_OUT @TIMECARD_LIB.TIMECARD(SCH_1):ANT2_OUT   I284 @TIMECARD_LIB.TIMECARD(SCH_1):PAGE12

R122 RESISTOR-G155-149R9-01,49.9OHMA
     2 SMA3_SIG_IO_CONN @TIMECARD_LIB.TIMECARD(SCH_1):SMA3_SIG_IO_CONN   I197 @TIMECARD_LIB.TIMECARD(SCH_1):PAGE12
     1 BF_SMA3_SIG_IO_CONN @TIMECARD_LIB.TIMECARD(SCH_1):BF_SMA3_SIG_IO_CONN   I197 @TIMECARD_LIB.TIMECARD(SCH_1):PAGE12

R123 RESISTOR-G155-149R9-01,49.9OHMA
     2 SMA4_SIG_IO_CONN @TIMECARD_LIB.TIMECARD(SCH_1):SMA4_SIG_IO_CONN   I228 @TIMECARD_LIB.TIMECARD(SCH_1):PAGE12
     1 BF_SMA4_SIG_IO_CONN @TIMECARD_LIB.TIMECARD(SCH_1):BF_SMA4_SIG_IO_CONN   I228 @TIMECARD_LIB.TIMECARD(SCH_1):PAGE12

R124 RESISTOR-G155-11000-01,100OHM,A
     2 UNNAMED_14_LED4PV14_I265_1 @TIMECARD_LIB.TIMECARD(SCH_1):UNNAMED_14_LED4PV14_I265_1   I160 @TIMECARD_LIB.TIMECARD(SCH_1):PAGE14
     1 FPGA_OUT_SMA1_LED_BLUE_N @TIMECARD_LIB.TIMECARD(SCH_1):FPGA_OUT_SMA1_LED_BLUE_N   I160 @TIMECARD_LIB.TIMECARD(SCH_1):PAGE14

R125 RESISTOR-G155-11000-01,100OHM,A
     2 UNNAMED_14_LED4PV14_I265_4 @TIMECARD_LIB.TIMECARD(SCH_1):UNNAMED_14_LED4PV14_I265_4   I161 @TIMECARD_LIB.TIMECARD(SCH_1):PAGE14
     1 FPGA_OUT_SMA1_LED_GREEN_N @TIMECARD_LIB.TIMECARD(SCH_1):FPGA_OUT_SMA1_LED_GREEN_N   I161 @TIMECARD_LIB.TIMECARD(SCH_1):PAGE14

R126 RESISTOR-G155-149R9-01,49.9OHMA
     2 SMA2_SIG_IO_CONN @TIMECARD_LIB.TIMECARD(SCH_1):SMA2_SIG_IO_CONN   I276 @TIMECARD_LIB.TIMECARD(SCH_1):PAGE12
     1 BF_SMA2_SIG_IO_CONN @TIMECARD_LIB.TIMECARD(SCH_1):BF_SMA2_SIG_IO_CONN   I276 @TIMECARD_LIB.TIMECARD(SCH_1):PAGE12

R127 RESISTOR-G155-149R9-01,49.9OHMA
     2 SMA1_SIG_IO_CONN @TIMECARD_LIB.TIMECARD(SCH_1):SMA1_SIG_IO_CONN   I257 @TIMECARD_LIB.TIMECARD(SCH_1):PAGE12
     1 BF_SMA1_SIG_IO_CONN @TIMECARD_LIB.TIMECARD(SCH_1):BF_SMA1_SIG_IO_CONN   I257 @TIMECARD_LIB.TIMECARD(SCH_1):PAGE12

R128 RESISTOR-G155-100R0-J0,0OHM,-
     2 R_FT_USB_DM @TIMECARD_LIB.TIMECARD(SCH_1):R_FT_USB_DM    I28 @TIMECARD_LIB.TIMECARD(SCH_1):PAGE524
     1 FT_USB_DM @TIMECARD_LIB.TIMECARD(SCH_1):FT_USB_DM    I28 @TIMECARD_LIB.TIMECARD(SCH_1):PAGE524

R129 RESISTOR-G155-100R0-J0,0OHM,-
     2 R_FT_USB_DP @TIMECARD_LIB.TIMECARD(SCH_1):R_FT_USB_DP    I26 @TIMECARD_LIB.TIMECARD(SCH_1):PAGE524
     1 FT_USB_DP @TIMECARD_LIB.TIMECARD(SCH_1):FT_USB_DP    I26 @TIMECARD_LIB.TIMECARD(SCH_1):PAGE524

R130 RESISTOR-G155-11002-01,10KOHM,A
     2     SG @TIMECARD_LIB.TIMECARD(SCH_1):SG    I23 @TIMECARD_LIB.TIMECARD(SCH_1):PAGE524
     1 FT_USB_DETECT @TIMECARD_LIB.TIMECARD(SCH_1):FT_USB_DETECT    I23 @TIMECARD_LIB.TIMECARD(SCH_1):PAGE524

R131 RESISTOR-G155-11000-01,100OHM,A
     2 FT4232_CHD_TX @TIMECARD_LIB.TIMECARD(SCH_1):FT4232_CHD_TX   I187 @TIMECARD_LIB.TIMECARD(SCH_1):PAGE524
     1 R_FT4232_CHD_TX @TIMECARD_LIB.TIMECARD(SCH_1):R_FT4232_CHD_TX   I187 @TIMECARD_LIB.TIMECARD(SCH_1):PAGE524

R132 RESISTOR-G155-11000-01,100OHM,A
     2 FT4232_CHD_RX @TIMECARD_LIB.TIMECARD(SCH_1):FT4232_CHD_RX   I188 @TIMECARD_LIB.TIMECARD(SCH_1):PAGE524
     1 R_FT4232_CHD_RX @TIMECARD_LIB.TIMECARD(SCH_1):R_FT4232_CHD_RX   I188 @TIMECARD_LIB.TIMECARD(SCH_1):PAGE524

R133 RESISTOR-G155-133R0-01,33OHM,1%
     2 UNNAMED_127_G2001028301_I427_4 @TIMECARD_LIB.TIMECARD(SCH_1):UNNAMED_127_G2001028301_I427_4   I446 @TIMECARD_LIB.TIMECARD(SCH_1):PAGE127
     1 XP3R3V_FPGA @TIMECARD_LIB.TIMECARD(SCH_1):XP3R3V_FPGA   I446 @TIMECARD_LIB.TIMECARD(SCH_1):PAGE127

R134 RESISTOR-G155-133R0-01,33OHM,1%
     2 FPGA_TCK @TIMECARD_LIB.TIMECARD(SCH_1):FPGA_TCK   I436 @TIMECARD_LIB.TIMECARD(SCH_1):PAGE127
     1 FT4232_FPGA_TCK @TIMECARD_LIB.TIMECARD(SCH_1):FT4232_FPGA_TCK   I436 @TIMECARD_LIB.TIMECARD(SCH_1):PAGE127

R135 RESISTOR-G155-100R0-J0,0OHM,-
     2 FPGA_TDO @TIMECARD_LIB.TIMECARD(SCH_1):FPGA_TDO   I438 @TIMECARD_LIB.TIMECARD(SCH_1):PAGE127
     1 FT4232_FPGA_TDO @TIMECARD_LIB.TIMECARD(SCH_1):FT4232_FPGA_TDO   I438 @TIMECARD_LIB.TIMECARD(SCH_1):PAGE127

R136 RESISTOR-G155-133R0-01,33OHM,1%
     2 FPGA_TMS @TIMECARD_LIB.TIMECARD(SCH_1):FPGA_TMS   I437 @TIMECARD_LIB.TIMECARD(SCH_1):PAGE127
     1 FT4232_FPGA_TMS @TIMECARD_LIB.TIMECARD(SCH_1):FT4232_FPGA_TMS   I437 @TIMECARD_LIB.TIMECARD(SCH_1):PAGE127

R137 RESISTOR-G155-133R0-01,33OHM,1%
     2 FPGA_TDI @TIMECARD_LIB.TIMECARD(SCH_1):FPGA_TDI   I439 @TIMECARD_LIB.TIMECARD(SCH_1):PAGE127
     1 FT4232_FPGA_TDI @TIMECARD_LIB.TIMECARD(SCH_1):FT4232_FPGA_TDI   I439 @TIMECARD_LIB.TIMECARD(SCH_1):PAGE127

R138 RESISTOR-G155-13300-01,330OHM,A
     2 XP3R3V_FPGA @TIMECARD_LIB.TIMECARD(SCH_1):XP3R3V_FPGA    I63 @TIMECARD_LIB.TIMECARD(SCH_1):PAGE14
     1 UNNAMED_14_OPTICAL_I140_A @TIMECARD_LIB.TIMECARD(SCH_1):UNNAMED_14_OPTICAL_I140_A    I63 @TIMECARD_LIB.TIMECARD(SCH_1):PAGE14

R139 RESISTOR-G155-133R0-01,33OHM,1%
     2 XP2R5V_FPGA @TIMECARD_LIB.TIMECARD(SCH_1):XP2R5V_FPGA    I60 @TIMECARD_LIB.TIMECARD(SCH_1):PAGE14
     1 UNNAMED_14_RESISTOR_I58_2 @TIMECARD_LIB.TIMECARD(SCH_1):UNNAMED_14_RESISTOR_I58_2    I60 @TIMECARD_LIB.TIMECARD(SCH_1):PAGE14

R140 RESISTOR-G155-100R0-J0,0OHM,-
     2 XP1R2V_EN_R @TIMECARD_LIB.TIMECARD(SCH_1):XP1R2V_EN_R    I18 @TIMECARD_LIB.TIMECARD(SCH_1):PAGE68
     1 XP1R0V_FPGA_PG @TIMECARD_LIB.TIMECARD(SCH_1):XP1R0V_FPGA_PG    I18 @TIMECARD_LIB.TIMECARD(SCH_1):PAGE68

R141 RESISTOR-G155-100R0-J0,0OHM,-
     2 XP1R8V_EN_R @TIMECARD_LIB.TIMECARD(SCH_1):XP1R8V_EN_R    I42 @TIMECARD_LIB.TIMECARD(SCH_1):PAGE68
     1 XP1R2V_FPGA_PG @TIMECARD_LIB.TIMECARD(SCH_1):XP1R2V_FPGA_PG    I42 @TIMECARD_LIB.TIMECARD(SCH_1):PAGE68

R142 RESISTOR-G155-11000-01,100OHM,A
     2 R_XP5R0V_EN @TIMECARD_LIB.TIMECARD(SCH_1):R_XP5R0V_EN    I44 @TIMECARD_LIB.TIMECARD(SCH_1):PAGE516
     1 XP1R8V_FPGA_PG @TIMECARD_LIB.TIMECARD(SCH_1):XP1R8V_FPGA_PG    I44 @TIMECARD_LIB.TIMECARD(SCH_1):PAGE516

R143 RESISTOR-G155-133R0-01,33OHM,1%
     2 UNNAMED_515_NCP45560IMNTWGHDFN1 @TIMECARD_LIB.TIMECARD(SCH_1):UNNAMED_515_NCP45560IMNTWGHDFN12_I82_PG   I167 @TIMECARD_LIB.TIMECARD(SCH_1):PAGE515
     1 FPGA_CFG_INIT_N @TIMECARD_LIB.TIMECARD(SCH_1):FPGA_CFG_INIT_N   I167 @TIMECARD_LIB.TIMECARD(SCH_1):PAGE515

R144 RESISTOR-G155-133R0-01,33OHM,1%
     2 R_PCA9546_I2C_SDA @TIMECARD_LIB.TIMECARD(SCH_1):R_PCA9546_I2C_SDA    I68 @TIMECARD_LIB.TIMECARD(SCH_1):PAGE5
     1 PCA9546_I2C_SDA @TIMECARD_LIB.TIMECARD(SCH_1):PCA9546_I2C_SDA    I68 @TIMECARD_LIB.TIMECARD(SCH_1):PAGE5

R145 RESISTOR-G155-133R0-01,33OHM,1%
     2 R_PCA9546_I2C_SCL @TIMECARD_LIB.TIMECARD(SCH_1):R_PCA9546_I2C_SCL    I67 @TIMECARD_LIB.TIMECARD(SCH_1):PAGE5
     1 PCA9546_I2C_SCL @TIMECARD_LIB.TIMECARD(SCH_1):PCA9546_I2C_SCL    I67 @TIMECARD_LIB.TIMECARD(SCH_1):PAGE5

R146 RESISTOR-G155-11002-01,10KOHM,A
     2 PCA9546_RST_N @TIMECARD_LIB.TIMECARD(SCH_1):PCA9546_RST_N    I60 @TIMECARD_LIB.TIMECARD(SCH_1):PAGE5
     1 XP3R3V_FPGA @TIMECARD_LIB.TIMECARD(SCH_1):XP3R3V_FPGA    I60 @TIMECARD_LIB.TIMECARD(SCH_1):PAGE5

R147 RESISTOR-G155-11002-01,10KOHM,A
     2 R_PCA9546_I2C_SDA @TIMECARD_LIB.TIMECARD(SCH_1):R_PCA9546_I2C_SDA    I80 @TIMECARD_LIB.TIMECARD(SCH_1):PAGE5
     1 XP3R3V_FPGA @TIMECARD_LIB.TIMECARD(SCH_1):XP3R3V_FPGA    I80 @TIMECARD_LIB.TIMECARD(SCH_1):PAGE5

R148 RESISTOR-G155-11002-01,10KOHM,A
     2 R_PCA9546_I2C_SCL @TIMECARD_LIB.TIMECARD(SCH_1):R_PCA9546_I2C_SCL    I81 @TIMECARD_LIB.TIMECARD(SCH_1):PAGE5
     1 XP3R3V_FPGA @TIMECARD_LIB.TIMECARD(SCH_1):XP3R3V_FPGA    I81 @TIMECARD_LIB.TIMECARD(SCH_1):PAGE5

R149 RESISTOR-G155-14701-01,4.7KOHMA
     2 UNNAMED_5_PCA9546APWTSSOP16_I33 @TIMECARD_LIB.TIMECARD(SCH_1):UNNAMED_5_PCA9546APWTSSOP16_I33_A0    I82 @TIMECARD_LIB.TIMECARD(SCH_1):PAGE5
     1 XP3R3V_FPGA @TIMECARD_LIB.TIMECARD(SCH_1):XP3R3V_FPGA    I82 @TIMECARD_LIB.TIMECARD(SCH_1):PAGE5

R150 RESISTOR-G155-14701-01,4.7KOHMA
     2 UNNAMED_5_PCA9546APWTSSOP16_I_1 @TIMECARD_LIB.TIMECARD(SCH_1):UNNAMED_5_PCA9546APWTSSOP16_I33_A1    I83 @TIMECARD_LIB.TIMECARD(SCH_1):PAGE5
     1 XP3R3V_FPGA @TIMECARD_LIB.TIMECARD(SCH_1):XP3R3V_FPGA    I83 @TIMECARD_LIB.TIMECARD(SCH_1):PAGE5

R151 RESISTOR-G155-14701-01,4.7KOHMA
     2 UNNAMED_5_PCA9546APWTSSOP16_I_2 @TIMECARD_LIB.TIMECARD(SCH_1):UNNAMED_5_PCA9546APWTSSOP16_I33_A2    I84 @TIMECARD_LIB.TIMECARD(SCH_1):PAGE5
     1 XP3R3V_FPGA @TIMECARD_LIB.TIMECARD(SCH_1):XP3R3V_FPGA    I84 @TIMECARD_LIB.TIMECARD(SCH_1):PAGE5

R152 RESISTOR-G155-14701-01,4.7KOHMA
     2 UNNAMED_5_PCA9546APWTSSOP16_I33 @TIMECARD_LIB.TIMECARD(SCH_1):UNNAMED_5_PCA9546APWTSSOP16_I33_A0    I85 @TIMECARD_LIB.TIMECARD(SCH_1):PAGE5
     1     SG @TIMECARD_LIB.TIMECARD(SCH_1):SG    I85 @TIMECARD_LIB.TIMECARD(SCH_1):PAGE5

R153 RESISTOR-G155-14701-01,4.7KOHMA
     2 UNNAMED_5_PCA9546APWTSSOP16_I_1 @TIMECARD_LIB.TIMECARD(SCH_1):UNNAMED_5_PCA9546APWTSSOP16_I33_A1    I86 @TIMECARD_LIB.TIMECARD(SCH_1):PAGE5
     1     SG @TIMECARD_LIB.TIMECARD(SCH_1):SG    I86 @TIMECARD_LIB.TIMECARD(SCH_1):PAGE5

R154 RESISTOR-G155-14701-01,4.7KOHMA
     2 UNNAMED_5_PCA9546APWTSSOP16_I_2 @TIMECARD_LIB.TIMECARD(SCH_1):UNNAMED_5_PCA9546APWTSSOP16_I33_A2    I87 @TIMECARD_LIB.TIMECARD(SCH_1):PAGE5
     1     SG @TIMECARD_LIB.TIMECARD(SCH_1):SG    I87 @TIMECARD_LIB.TIMECARD(SCH_1):PAGE5

R155 RESISTOR-G155-14701-01,4.7KOHMA
     2 PCA9546_RST_N @TIMECARD_LIB.TIMECARD(SCH_1):PCA9546_RST_N    I66 @TIMECARD_LIB.TIMECARD(SCH_1):PAGE5
     1     SG @TIMECARD_LIB.TIMECARD(SCH_1):SG    I66 @TIMECARD_LIB.TIMECARD(SCH_1):PAGE5

R156 RESISTOR-G155-11000-01,100OHM,A
     2 UNNAMED_12_74HCT2G125DPTSSOP8_I @TIMECARD_LIB.TIMECARD(SCH_1):UNNAMED_12_74HCT2G125DPTSSOP8_I204_1A    I63 @TIMECARD_LIB.TIMECARD(SCH_1):PAGE12
     1 ANT3_OUT @TIMECARD_LIB.TIMECARD(SCH_1):ANT3_OUT    I63 @TIMECARD_LIB.TIMECARD(SCH_1):PAGE12

R157 RESISTOR-G155-11000-01,100OHM,A
     2 UNNAMED_12_74HCT2G125DPTSSOP8_3 @TIMECARD_LIB.TIMECARD(SCH_1):UNNAMED_12_74HCT2G125DPTSSOP8_I226_1A   I237 @TIMECARD_LIB.TIMECARD(SCH_1):PAGE12
     1 ANT4_OUT @TIMECARD_LIB.TIMECARD(SCH_1):ANT4_OUT   I237 @TIMECARD_LIB.TIMECARD(SCH_1):PAGE12

R158 RESISTOR-G155-14701-01,4.7KOHMA
     2 UNNAMED_5_24LC16BTISTTSSOP8_I15 @TIMECARD_LIB.TIMECARD(SCH_1):UNNAMED_5_24LC16BTISTTSSOP8_I151_A0   I153 @TIMECARD_LIB.TIMECARD(SCH_1):PAGE5
     1 XP3R3V_FPGA @TIMECARD_LIB.TIMECARD(SCH_1):XP3R3V_FPGA   I153 @TIMECARD_LIB.TIMECARD(SCH_1):PAGE5

R159 RESISTOR-G155-14701-01,4.7KOHMA
     2     SG @TIMECARD_LIB.TIMECARD(SCH_1):SG   I156 @TIMECARD_LIB.TIMECARD(SCH_1):PAGE5
     1 UNNAMED_5_24LC16BTISTTSSOP8_I15 @TIMECARD_LIB.TIMECARD(SCH_1):UNNAMED_5_24LC16BTISTTSSOP8_I151_A0   I156 @TIMECARD_LIB.TIMECARD(SCH_1):PAGE5

R160 RESISTOR-G155-14701-01,4.7KOHMA
     2 UNNAMED_5_24LC16BTISTTSSOP8_I_1 @TIMECARD_LIB.TIMECARD(SCH_1):UNNAMED_5_24LC16BTISTTSSOP8_I151_A1   I160 @TIMECARD_LIB.TIMECARD(SCH_1):PAGE5
     1 XP3R3V_FPGA @TIMECARD_LIB.TIMECARD(SCH_1):XP3R3V_FPGA   I160 @TIMECARD_LIB.TIMECARD(SCH_1):PAGE5

R161 RESISTOR-G155-14701-01,4.7KOHMA
     2     SG @TIMECARD_LIB.TIMECARD(SCH_1):SG   I165 @TIMECARD_LIB.TIMECARD(SCH_1):PAGE5
     1 UNNAMED_5_24LC16BTISTTSSOP8_I_1 @TIMECARD_LIB.TIMECARD(SCH_1):UNNAMED_5_24LC16BTISTTSSOP8_I151_A1   I165 @TIMECARD_LIB.TIMECARD(SCH_1):PAGE5

R162 RESISTOR-G155-14701-01,4.7KOHMA
     2 UNNAMED_5_24LC16BTISTTSSOP8_I_2 @TIMECARD_LIB.TIMECARD(SCH_1):UNNAMED_5_24LC16BTISTTSSOP8_I151_A2   I161 @TIMECARD_LIB.TIMECARD(SCH_1):PAGE5
     1 XP3R3V_FPGA @TIMECARD_LIB.TIMECARD(SCH_1):XP3R3V_FPGA   I161 @TIMECARD_LIB.TIMECARD(SCH_1):PAGE5

R163 RESISTOR-G155-14701-01,4.7KOHMA
     2     SG @TIMECARD_LIB.TIMECARD(SCH_1):SG   I166 @TIMECARD_LIB.TIMECARD(SCH_1):PAGE5
     1 UNNAMED_5_24LC16BTISTTSSOP8_I_2 @TIMECARD_LIB.TIMECARD(SCH_1):UNNAMED_5_24LC16BTISTTSSOP8_I151_A2   I166 @TIMECARD_LIB.TIMECARD(SCH_1):PAGE5

R164 RESISTOR-G155-11003-01,100KOHMA
     2 UNNAMED_3_RESISTOR_I151_2 @TIMECARD_LIB.TIMECARD(SCH_1):UNNAMED_3_RESISTOR_I151_2   I151 @TIMECARD_LIB.TIMECARD(SCH_1):PAGE3
     1 XP3R3V_FPGA @TIMECARD_LIB.TIMECARD(SCH_1):XP3R3V_FPGA   I151 @TIMECARD_LIB.TIMECARD(SCH_1):PAGE3

R165 RESISTOR-G155-11002-01,10KOHM,A
     2     SG @TIMECARD_LIB.TIMECARD(SCH_1):SG     I2 @TIMECARD_LIB.TIMECARD(SCH_1):PAGE68
     1 XP1R2V_EN_R @TIMECARD_LIB.TIMECARD(SCH_1):XP1R2V_EN_R     I2 @TIMECARD_LIB.TIMECARD(SCH_1):PAGE68

R166 RESISTOR-G152-00055-01,1.13KOHA
     2 XP1R8V_EN_R @TIMECARD_LIB.TIMECARD(SCH_1):XP1R8V_EN_R    I45 @TIMECARD_LIB.TIMECARD(SCH_1):PAGE68
     1 XP1R8V_VIN @TIMECARD_LIB.TIMECARD(SCH_1):XP1R8V_VIN    I45 @TIMECARD_LIB.TIMECARD(SCH_1):PAGE68

R167 RESISTOR-G155-11002-01,10KOHM,A
     2 FPGA_IN_RST_DLY_N @TIMECARD_LIB.TIMECARD(SCH_1):FPGA_IN_RST_DLY_N   I148 @TIMECARD_LIB.TIMECARD(SCH_1):PAGE3
     1 XP3R3V_FPGA @TIMECARD_LIB.TIMECARD(SCH_1):XP3R3V_FPGA   I148 @TIMECARD_LIB.TIMECARD(SCH_1):PAGE3

R168 RESISTOR-G155-11004-01,1MOHM,1%
     2 UNNAMED_9_BNO080LGA28_I29_XOUT3 @TIMECARD_LIB.TIMECARD(SCH_1):UNNAMED_9_BNO080LGA28_I29_XOUT32    I70 @TIMECARD_LIB.TIMECARD(SCH_1):PAGE9
     1 UNNAMED_9_CAPACITOR_I17_1 @TIMECARD_LIB.TIMECARD(SCH_1):UNNAMED_9_CAPACITOR_I17_1    I70 @TIMECARD_LIB.TIMECARD(SCH_1):PAGE9

R169 RESISTOR-G155-13300-01,330OHM,A
     2 XP3R3V_FT4232 @TIMECARD_LIB.TIMECARD(SCH_1):XP3R3V_FT4232   I288 @TIMECARD_LIB.TIMECARD(SCH_1):PAGE14
     1 UNNAMED_14_OPTICAL_I289_A @TIMECARD_LIB.TIMECARD(SCH_1):UNNAMED_14_OPTICAL_I289_A   I288 @TIMECARD_LIB.TIMECARD(SCH_1):PAGE14

R170 RESISTOR-G155-11002-01,10KOHM,A
     2 FPGA_IO_0 @TIMECARD_LIB.TIMECARD(SCH_1):FPGA_IO_0  I1608 @TIMECARD_LIB.TIMECARD(SCH_1):PAGE16
     1 XP3R3V_FPGA @TIMECARD_LIB.TIMECARD(SCH_1):XP3R3V_FPGA  I1608 @TIMECARD_LIB.TIMECARD(SCH_1):PAGE16

R171 RESISTOR-G155-14701-01,4.7KOHMA
     2 FPGA_IO_0 @TIMECARD_LIB.TIMECARD(SCH_1):FPGA_IO_0  I1542 @TIMECARD_LIB.TIMECARD(SCH_1):PAGE16
     1     SG @TIMECARD_LIB.TIMECARD(SCH_1):SG  I1542 @TIMECARD_LIB.TIMECARD(SCH_1):PAGE16

R172 RESISTOR-G155-11002-01,10KOHM,A
     2 FPGA_IO_1 @TIMECARD_LIB.TIMECARD(SCH_1):FPGA_IO_1  I1607 @TIMECARD_LIB.TIMECARD(SCH_1):PAGE16
     1 XP3R3V_FPGA @TIMECARD_LIB.TIMECARD(SCH_1):XP3R3V_FPGA  I1607 @TIMECARD_LIB.TIMECARD(SCH_1):PAGE16

R173 RESISTOR-G155-14701-01,4.7KOHMA
     2 FPGA_IO_1 @TIMECARD_LIB.TIMECARD(SCH_1):FPGA_IO_1  I1544 @TIMECARD_LIB.TIMECARD(SCH_1):PAGE16
     1     SG @TIMECARD_LIB.TIMECARD(SCH_1):SG  I1544 @TIMECARD_LIB.TIMECARD(SCH_1):PAGE16

R174 RESISTOR-G155-11002-01,10KOHM,A
     2     SG @TIMECARD_LIB.TIMECARD(SCH_1):SG    I44 @TIMECARD_LIB.TIMECARD(SCH_1):PAGE68
     1 XP1R8V_EN_R @TIMECARD_LIB.TIMECARD(SCH_1):XP1R8V_EN_R    I44 @TIMECARD_LIB.TIMECARD(SCH_1):PAGE68

R175 RESISTOR-G155-133R0-01,33OHM,1%
     2 EEPROM_SDA @TIMECARD_LIB.TIMECARD(SCH_1):EEPROM_SDA   I100 @TIMECARD_LIB.TIMECARD(SCH_1):PAGE5
     1 PCIE_SMDAT @TIMECARD_LIB.TIMECARD(SCH_1):PCIE_SMDAT   I100 @TIMECARD_LIB.TIMECARD(SCH_1):PAGE5

R176 RESISTOR-G155-133R0-01,33OHM,1%
     2 EEPROM_SCL @TIMECARD_LIB.TIMECARD(SCH_1):EEPROM_SCL   I102 @TIMECARD_LIB.TIMECARD(SCH_1):PAGE5
     1 PCIE_SMCLK @TIMECARD_LIB.TIMECARD(SCH_1):PCIE_SMCLK   I102 @TIMECARD_LIB.TIMECARD(SCH_1):PAGE5

R177 RESISTOR-G152-00055-01,1.13KOHA
     2 XP1R2V_EN_R @TIMECARD_LIB.TIMECARD(SCH_1):XP1R2V_EN_R    I26 @TIMECARD_LIB.TIMECARD(SCH_1):PAGE68
     1 XP1R2V_VIN @TIMECARD_LIB.TIMECARD(SCH_1):XP1R2V_VIN    I26 @TIMECARD_LIB.TIMECARD(SCH_1):PAGE68

R178 RESISTOR-G155-14701-01,4.7KOHMA
     2 XP1R2V_PG_R @TIMECARD_LIB.TIMECARD(SCH_1):XP1R2V_PG_R    I11 @TIMECARD_LIB.TIMECARD(SCH_1):PAGE68
     1 XP3R3V @TIMECARD_LIB.TIMECARD(SCH_1):XP3R3V    I11 @TIMECARD_LIB.TIMECARD(SCH_1):PAGE68

R179 RESISTOR-G155-14701-01,4.7KOHMA
     2 XP1R8V_PG_R @TIMECARD_LIB.TIMECARD(SCH_1):XP1R8V_PG_R    I73 @TIMECARD_LIB.TIMECARD(SCH_1):PAGE68
     1 XP3R3V @TIMECARD_LIB.TIMECARD(SCH_1):XP3R3V    I73 @TIMECARD_LIB.TIMECARD(SCH_1):PAGE68

R180 RESISTOR-G155-11001-01,1KOHM,1%
     2 XP5R0V @TIMECARD_LIB.TIMECARD(SCH_1):XP5R0V    I44 @TIMECARD_LIB.TIMECARD(SCH_1):PAGE14
     1 UNNAMED_14_OPTICAL_I142_A @TIMECARD_LIB.TIMECARD(SCH_1):UNNAMED_14_OPTICAL_I142_A    I44 @TIMECARD_LIB.TIMECARD(SCH_1):PAGE14

R181 RESISTOR-G155-100R0-J0,0OHM,-
     2 XP1R2V_FPGA_PG @TIMECARD_LIB.TIMECARD(SCH_1):XP1R2V_FPGA_PG    I10 @TIMECARD_LIB.TIMECARD(SCH_1):PAGE68
     1 XP1R2V_PG_R @TIMECARD_LIB.TIMECARD(SCH_1):XP1R2V_PG_R    I10 @TIMECARD_LIB.TIMECARD(SCH_1):PAGE68

R182 RESISTOR-G155-100R0-J0,0OHM,-
     2 XP1R8V_FPGA_PG @TIMECARD_LIB.TIMECARD(SCH_1):XP1R8V_FPGA_PG    I74 @TIMECARD_LIB.TIMECARD(SCH_1):PAGE68
     1 XP1R8V_PG_R @TIMECARD_LIB.TIMECARD(SCH_1):XP1R8V_PG_R    I74 @TIMECARD_LIB.TIMECARD(SCH_1):PAGE68

R183 RESISTOR-G155-133R0-01,33OHM,1%
     2 EEPROM_SDA @TIMECARD_LIB.TIMECARD(SCH_1):EEPROM_SDA   I101 @TIMECARD_LIB.TIMECARD(SCH_1):PAGE5
     1 EEPROM_I2C_SDA @TIMECARD_LIB.TIMECARD(SCH_1):EEPROM_I2C_SDA   I101 @TIMECARD_LIB.TIMECARD(SCH_1):PAGE5

R184 RESISTOR-G155-133R0-01,33OHM,1%
     2 EEPROM_SCL @TIMECARD_LIB.TIMECARD(SCH_1):EEPROM_SCL   I103 @TIMECARD_LIB.TIMECARD(SCH_1):PAGE5
     1 EEPROM_I2C_SCL @TIMECARD_LIB.TIMECARD(SCH_1):EEPROM_I2C_SCL   I103 @TIMECARD_LIB.TIMECARD(SCH_1):PAGE5

R185 RESISTOR-G155-04221-01,4.22KOHA
     2 XP1R2V_FB @TIMECARD_LIB.TIMECARD(SCH_1):XP1R2V_FB    I59 @TIMECARD_LIB.TIMECARD(SCH_1):PAGE68
     1 XP1R2V_FPGA @TIMECARD_LIB.TIMECARD(SCH_1):XP1R2V_FPGA    I59 @TIMECARD_LIB.TIMECARD(SCH_1):PAGE68

R186 RESISTOR-G155-03001-01,3KOHM,1%
     2 XP1R2V_FB @TIMECARD_LIB.TIMECARD(SCH_1):XP1R2V_FB    I14 @TIMECARD_LIB.TIMECARD(SCH_1):PAGE68
     1     SG @TIMECARD_LIB.TIMECARD(SCH_1):SG    I14 @TIMECARD_LIB.TIMECARD(SCH_1):PAGE68

R187 RESISTOR-G155-04221-01,4.22KOHA
     2 XP1R8V_FB @TIMECARD_LIB.TIMECARD(SCH_1):XP1R8V_FB    I78 @TIMECARD_LIB.TIMECARD(SCH_1):PAGE68
     1 XP1R8V_FPGA @TIMECARD_LIB.TIMECARD(SCH_1):XP1R8V_FPGA    I78 @TIMECARD_LIB.TIMECARD(SCH_1):PAGE68

R188 RESISTOR-G155-03241-01,3.24KOHA
     2 XP1R8V_FB @TIMECARD_LIB.TIMECARD(SCH_1):XP1R8V_FB    I79 @TIMECARD_LIB.TIMECARD(SCH_1):PAGE68
     1     SG @TIMECARD_LIB.TIMECARD(SCH_1):SG    I79 @TIMECARD_LIB.TIMECARD(SCH_1):PAGE68

R189 RESISTOR-G155-03241-01,3.24KOHA
     2 XP1R2V_FB @TIMECARD_LIB.TIMECARD(SCH_1):XP1R2V_FB    I16 @TIMECARD_LIB.TIMECARD(SCH_1):PAGE68
     1     SG @TIMECARD_LIB.TIMECARD(SCH_1):SG    I16 @TIMECARD_LIB.TIMECARD(SCH_1):PAGE68

R190 RESISTOR-G155-03241-01,3.24KOHA
     2 XP1R8V_FB @TIMECARD_LIB.TIMECARD(SCH_1):XP1R8V_FB    I80 @TIMECARD_LIB.TIMECARD(SCH_1):PAGE68
     1     SG @TIMECARD_LIB.TIMECARD(SCH_1):SG    I80 @TIMECARD_LIB.TIMECARD(SCH_1):PAGE68

R191 RESISTOR-G155-14701-01,4.7KOHMA
     2 FLASH_CS_N @TIMECARD_LIB.TIMECARD(SCH_1):FLASH_CS_N   I471 @TIMECARD_LIB.TIMECARD(SCH_1):PAGE127
     1 XP3R3V_FPGA @TIMECARD_LIB.TIMECARD(SCH_1):XP3R3V_FPGA   I471 @TIMECARD_LIB.TIMECARD(SCH_1):PAGE127

R192 RESISTOR-G155-14701-01,4.7KOHMA
     2     SG @TIMECARD_LIB.TIMECARD(SCH_1):SG   I470 @TIMECARD_LIB.TIMECARD(SCH_1):PAGE127
     1 FLASH_CLK @TIMECARD_LIB.TIMECARD(SCH_1):FLASH_CLK   I470 @TIMECARD_LIB.TIMECARD(SCH_1):PAGE127

R193 RESISTOR-G155-14701-01,4.7KOHMA
     2 FPGA_PROGRAM_N @TIMECARD_LIB.TIMECARD(SCH_1):FPGA_PROGRAM_N   I330 @TIMECARD_LIB.TIMECARD(SCH_1):PAGE127
     1 XP3R3V_FPGA @TIMECARD_LIB.TIMECARD(SCH_1):XP3R3V_FPGA   I330 @TIMECARD_LIB.TIMECARD(SCH_1):PAGE127

R194 RESISTOR-G155-14701-01,4.7KOHMA
     2 CFGBVS @TIMECARD_LIB.TIMECARD(SCH_1):CFGBVS   I329 @TIMECARD_LIB.TIMECARD(SCH_1):PAGE127
     1 XP3R3V_FPGA @TIMECARD_LIB.TIMECARD(SCH_1):XP3R3V_FPGA   I329 @TIMECARD_LIB.TIMECARD(SCH_1):PAGE127

R195 RESISTOR-G155-133R0-01,33OHM,1%
     2 R_FPGA_TDO @TIMECARD_LIB.TIMECARD(SCH_1):R_FPGA_TDO   I331 @TIMECARD_LIB.TIMECARD(SCH_1):PAGE127
     1 FPGA_TDO @TIMECARD_LIB.TIMECARD(SCH_1):FPGA_TDO   I331 @TIMECARD_LIB.TIMECARD(SCH_1):PAGE127

R196 RESISTOR-G155-11000-01,100OHM,A
     2 FPGA_MGTRREF @TIMECARD_LIB.TIMECARD(SCH_1):FPGA_MGTRREF   I332 @TIMECARD_LIB.TIMECARD(SCH_1):PAGE127
     1 FPGA_MGTAVTT @TIMECARD_LIB.TIMECARD(SCH_1):FPGA_MGTAVTT   I332 @TIMECARD_LIB.TIMECARD(SCH_1):PAGE127

R197 RESISTOR-G155-11000-01,100OHM,A
     2 MHZ125CLKN_CLKIN @TIMECARD_LIB.TIMECARD(SCH_1):MHZ125CLKN_CLKIN   I333 @TIMECARD_LIB.TIMECARD(SCH_1):PAGE127
     1 MHZ125CLKP_CLKIN @TIMECARD_LIB.TIMECARD(SCH_1):MHZ125CLKP_CLKIN   I333 @TIMECARD_LIB.TIMECARD(SCH_1):PAGE127

R198 RESISTOR-G155-11000-01,100OHM,A
     2 PCIE_REFCLKN @TIMECARD_LIB.TIMECARD(SCH_1):PCIE_REFCLKN   I334 @TIMECARD_LIB.TIMECARD(SCH_1):PAGE127
     1 PCIE_REFCLKP @TIMECARD_LIB.TIMECARD(SCH_1):PCIE_REFCLKP   I334 @TIMECARD_LIB.TIMECARD(SCH_1):PAGE127

R199 RESISTOR-G155-14701-01,4.7KOHMA
     2 XP3R3V_FPGA @TIMECARD_LIB.TIMECARD(SCH_1):XP3R3V_FPGA   I462 @TIMECARD_LIB.TIMECARD(SCH_1):PAGE127
     1 UNNAMED_127_MT25QL128ABA1ESESOP @TIMECARD_LIB.TIMECARD(SCH_1):UNNAMED_127_MT25QL128ABA1ESESOP8_I456_DQ0   I462 @TIMECARD_LIB.TIMECARD(SCH_1):PAGE127

R200 RESISTOR-G155-14701-01,4.7KOHMA
     2 XP3R3V_FPGA @TIMECARD_LIB.TIMECARD(SCH_1):XP3R3V_FPGA   I465 @TIMECARD_LIB.TIMECARD(SCH_1):PAGE127
     1 UNNAMED_127_MT25QL128ABA1ESES_1 @TIMECARD_LIB.TIMECARD(SCH_1):UNNAMED_127_MT25QL128ABA1ESESOP8_I456_DQ1   I465 @TIMECARD_LIB.TIMECARD(SCH_1):PAGE127

R201 RESISTOR-G155-14701-01,4.7KOHMA
     2 XP3R3V_FPGA @TIMECARD_LIB.TIMECARD(SCH_1):XP3R3V_FPGA   I463 @TIMECARD_LIB.TIMECARD(SCH_1):PAGE127
     1 UNNAMED_127_MT25QL128ABA1ESES_3 @TIMECARD_LIB.TIMECARD(SCH_1):UNNAMED_127_MT25QL128ABA1ESESOP8_I456_W   I463 @TIMECARD_LIB.TIMECARD(SCH_1):PAGE127

R202 RESISTOR-G155-14701-01,4.7KOHMA
     2 XP3R3V_FPGA @TIMECARD_LIB.TIMECARD(SCH_1):XP3R3V_FPGA   I464 @TIMECARD_LIB.TIMECARD(SCH_1):PAGE127
     1 UNNAMED_127_MT25QL128ABA1ESES_2 @TIMECARD_LIB.TIMECARD(SCH_1):UNNAMED_127_MT25QL128ABA1ESESOP8_I456_HOLD   I464 @TIMECARD_LIB.TIMECARD(SCH_1):PAGE127

R203 RESISTOR-G155-133R0-01,33OHM,1%
     2 FLASH_DQ0_MOSI @TIMECARD_LIB.TIMECARD(SCH_1):FLASH_DQ0_MOSI   I467 @TIMECARD_LIB.TIMECARD(SCH_1):PAGE127
     1 UNNAMED_127_MT25QL128ABA1ESESOP @TIMECARD_LIB.TIMECARD(SCH_1):UNNAMED_127_MT25QL128ABA1ESESOP8_I456_DQ0   I467 @TIMECARD_LIB.TIMECARD(SCH_1):PAGE127

R204 RESISTOR-G155-133R0-01,33OHM,1%
     2 FLASH_DQ1_MISO @TIMECARD_LIB.TIMECARD(SCH_1):FLASH_DQ1_MISO   I466 @TIMECARD_LIB.TIMECARD(SCH_1):PAGE127
     1 UNNAMED_127_MT25QL128ABA1ESES_1 @TIMECARD_LIB.TIMECARD(SCH_1):UNNAMED_127_MT25QL128ABA1ESESOP8_I456_DQ1   I466 @TIMECARD_LIB.TIMECARD(SCH_1):PAGE127

R205 RESISTOR-G155-133R0-01,33OHM,1%
     2 FLASH_DQ2 @TIMECARD_LIB.TIMECARD(SCH_1):FLASH_DQ2   I468 @TIMECARD_LIB.TIMECARD(SCH_1):PAGE127
     1 UNNAMED_127_MT25QL128ABA1ESES_3 @TIMECARD_LIB.TIMECARD(SCH_1):UNNAMED_127_MT25QL128ABA1ESESOP8_I456_W   I468 @TIMECARD_LIB.TIMECARD(SCH_1):PAGE127

R206 RESISTOR-G155-133R0-01,33OHM,1%
     2 FLASH_DQ3 @TIMECARD_LIB.TIMECARD(SCH_1):FLASH_DQ3   I469 @TIMECARD_LIB.TIMECARD(SCH_1):PAGE127
     1 UNNAMED_127_MT25QL128ABA1ESES_2 @TIMECARD_LIB.TIMECARD(SCH_1):UNNAMED_127_MT25QL128ABA1ESESOP8_I456_HOLD   I469 @TIMECARD_LIB.TIMECARD(SCH_1):PAGE127

R207 RESISTOR-G155-100R0-J0,0OHM,-
     2 FPGA_FLASH_CLK @TIMECARD_LIB.TIMECARD(SCH_1):FPGA_FLASH_CLK   I337 @TIMECARD_LIB.TIMECARD(SCH_1):PAGE127
     1 CCLK_0 @TIMECARD_LIB.TIMECARD(SCH_1):CCLK_0   I337 @TIMECARD_LIB.TIMECARD(SCH_1):PAGE127

R208 RESISTOR-G155-13300-01,330OHM,A
     2 FPGA_DONE @TIMECARD_LIB.TIMECARD(SCH_1):FPGA_DONE   I293 @TIMECARD_LIB.TIMECARD(SCH_1):PAGE14
     1 UNNAMED_14_OPTICAL_I292_A @TIMECARD_LIB.TIMECARD(SCH_1):UNNAMED_14_OPTICAL_I292_A   I293 @TIMECARD_LIB.TIMECARD(SCH_1):PAGE14

R209 RESISTOR-G155-14701-01,4.7KOHMA
     2 XP3R3V_FPGA @TIMECARD_LIB.TIMECARD(SCH_1):XP3R3V_FPGA   I339 @TIMECARD_LIB.TIMECARD(SCH_1):PAGE127
     1 FPGA_CFG_INIT_N @TIMECARD_LIB.TIMECARD(SCH_1):FPGA_CFG_INIT_N   I339 @TIMECARD_LIB.TIMECARD(SCH_1):PAGE127

R210 RESISTOR-G155-13300-01,330OHM,A
     2 XP3R3V_FPGA @TIMECARD_LIB.TIMECARD(SCH_1):XP3R3V_FPGA   I338 @TIMECARD_LIB.TIMECARD(SCH_1):PAGE127
     1 FPGA_DONE @TIMECARD_LIB.TIMECARD(SCH_1):FPGA_DONE   I338 @TIMECARD_LIB.TIMECARD(SCH_1):PAGE127

R211 RESISTOR-G155-11000-01,100OHM,A
     2 FPGA_M0 @TIMECARD_LIB.TIMECARD(SCH_1):FPGA_M0   I404 @TIMECARD_LIB.TIMECARD(SCH_1):PAGE127
     1 XP3R3V_FPGA @TIMECARD_LIB.TIMECARD(SCH_1):XP3R3V_FPGA   I404 @TIMECARD_LIB.TIMECARD(SCH_1):PAGE127

R212 RESISTOR-G155-11000-01,100OHM,A
     2     SG @TIMECARD_LIB.TIMECARD(SCH_1):SG   I407 @TIMECARD_LIB.TIMECARD(SCH_1):PAGE127
     1 FPGA_M0 @TIMECARD_LIB.TIMECARD(SCH_1):FPGA_M0   I407 @TIMECARD_LIB.TIMECARD(SCH_1):PAGE127

R213 RESISTOR-G155-11002-01,10KOHM,A
     2 FPGA_BRD_REV2 @TIMECARD_LIB.TIMECARD(SCH_1):FPGA_BRD_REV2   I396 @TIMECARD_LIB.TIMECARD(SCH_1):PAGE127
     1 XP3R3V_FPGA @TIMECARD_LIB.TIMECARD(SCH_1):XP3R3V_FPGA   I396 @TIMECARD_LIB.TIMECARD(SCH_1):PAGE127

R214 RESISTOR-G155-11001-01,1KOHM,1%
     2     SG @TIMECARD_LIB.TIMECARD(SCH_1):SG   I397 @TIMECARD_LIB.TIMECARD(SCH_1):PAGE127
     1 FPGA_BRD_REV2 @TIMECARD_LIB.TIMECARD(SCH_1):FPGA_BRD_REV2   I397 @TIMECARD_LIB.TIMECARD(SCH_1):PAGE127

R215 RESISTOR-G155-11002-01,10KOHM,A
     2 FPGA_BRD_REV1 @TIMECARD_LIB.TIMECARD(SCH_1):FPGA_BRD_REV1   I394 @TIMECARD_LIB.TIMECARD(SCH_1):PAGE127
     1 XP3R3V_FPGA @TIMECARD_LIB.TIMECARD(SCH_1):XP3R3V_FPGA   I394 @TIMECARD_LIB.TIMECARD(SCH_1):PAGE127

R216 RESISTOR-G155-11001-01,1KOHM,1%
     2     SG @TIMECARD_LIB.TIMECARD(SCH_1):SG   I391 @TIMECARD_LIB.TIMECARD(SCH_1):PAGE127
     1 FPGA_BRD_REV1 @TIMECARD_LIB.TIMECARD(SCH_1):FPGA_BRD_REV1   I391 @TIMECARD_LIB.TIMECARD(SCH_1):PAGE127

R217 RESISTOR-G155-11000-01,100OHM,A
     2 FPGA_M1 @TIMECARD_LIB.TIMECARD(SCH_1):FPGA_M1   I402 @TIMECARD_LIB.TIMECARD(SCH_1):PAGE127
     1 XP3R3V_FPGA @TIMECARD_LIB.TIMECARD(SCH_1):XP3R3V_FPGA   I402 @TIMECARD_LIB.TIMECARD(SCH_1):PAGE127

R218 RESISTOR-G155-11000-01,100OHM,A
     2     SG @TIMECARD_LIB.TIMECARD(SCH_1):SG   I406 @TIMECARD_LIB.TIMECARD(SCH_1):PAGE127
     1 FPGA_M1 @TIMECARD_LIB.TIMECARD(SCH_1):FPGA_M1   I406 @TIMECARD_LIB.TIMECARD(SCH_1):PAGE127

R219 RESISTOR-G155-11002-01,10KOHM,A
     2 FPGA_BRD_REV0 @TIMECARD_LIB.TIMECARD(SCH_1):FPGA_BRD_REV0   I392 @TIMECARD_LIB.TIMECARD(SCH_1):PAGE127
     1 XP3R3V_FPGA @TIMECARD_LIB.TIMECARD(SCH_1):XP3R3V_FPGA   I392 @TIMECARD_LIB.TIMECARD(SCH_1):PAGE127

R220 RESISTOR-G155-11001-01,1KOHM,1%
     2     SG @TIMECARD_LIB.TIMECARD(SCH_1):SG   I393 @TIMECARD_LIB.TIMECARD(SCH_1):PAGE127
     1 FPGA_BRD_REV0 @TIMECARD_LIB.TIMECARD(SCH_1):FPGA_BRD_REV0   I393 @TIMECARD_LIB.TIMECARD(SCH_1):PAGE127

R221 RESISTOR-G155-11000-01,100OHM,A
     2 FPGA_M2 @TIMECARD_LIB.TIMECARD(SCH_1):FPGA_M2   I403 @TIMECARD_LIB.TIMECARD(SCH_1):PAGE127
     1 XP3R3V_FPGA @TIMECARD_LIB.TIMECARD(SCH_1):XP3R3V_FPGA   I403 @TIMECARD_LIB.TIMECARD(SCH_1):PAGE127

R222 RESISTOR-G155-11000-01,100OHM,A
     2     SG @TIMECARD_LIB.TIMECARD(SCH_1):SG   I405 @TIMECARD_LIB.TIMECARD(SCH_1):PAGE127
     1 FPGA_M2 @TIMECARD_LIB.TIMECARD(SCH_1):FPGA_M2   I405 @TIMECARD_LIB.TIMECARD(SCH_1):PAGE127

R223 RESISTOR-G155-11001-01,1KOHM,1%
     2 XP3R3V_FPGA @TIMECARD_LIB.TIMECARD(SCH_1):XP3R3V_FPGA   I252 @TIMECARD_LIB.TIMECARD(SCH_1):PAGE161
     1   PUDC @TIMECARD_LIB.TIMECARD(SCH_1):PUDC   I252 @TIMECARD_LIB.TIMECARD(SCH_1):PAGE161

R224 RESISTOR-G155-11001-01,1KOHM,1%
     2   PUDC @TIMECARD_LIB.TIMECARD(SCH_1):PUDC   I253 @TIMECARD_LIB.TIMECARD(SCH_1):PAGE161
     1     SG @TIMECARD_LIB.TIMECARD(SCH_1):SG   I253 @TIMECARD_LIB.TIMECARD(SCH_1):PAGE161

R225 RESISTOR-G155-13300-01,330OHM,A
     2 UNNAMED_515_CAPACITOR_I128_1 @TIMECARD_LIB.TIMECARD(SCH_1):UNNAMED_515_CAPACITOR_I128_1   I152 @TIMECARD_LIB.TIMECARD(SCH_1):PAGE515
     1 XP1R8V_FPGA_PG @TIMECARD_LIB.TIMECARD(SCH_1):XP1R8V_FPGA_PG   I152 @TIMECARD_LIB.TIMECARD(SCH_1):PAGE515

R226 RESISTOR-G155-13300-01,330OHM,A
     2 XP3R3V_FPGA_EN_R @TIMECARD_LIB.TIMECARD(SCH_1):XP3R3V_FPGA_EN_R   I122 @TIMECARD_LIB.TIMECARD(SCH_1):PAGE515
     1 XP1R8V_FPGA_PG @TIMECARD_LIB.TIMECARD(SCH_1):XP1R8V_FPGA_PG   I122 @TIMECARD_LIB.TIMECARD(SCH_1):PAGE515

R227 RESISTOR-G155-11002-01,10KOHM,A
     2     SG @TIMECARD_LIB.TIMECARD(SCH_1):SG   I127 @TIMECARD_LIB.TIMECARD(SCH_1):PAGE515
     1 UNNAMED_515_CAPACITOR_I128_1 @TIMECARD_LIB.TIMECARD(SCH_1):UNNAMED_515_CAPACITOR_I128_1   I127 @TIMECARD_LIB.TIMECARD(SCH_1):PAGE515

R228 RESISTOR-G152-00055-01,1.13KOHA
     2 UNNAMED_515_CAPACITOR_I128_1 @TIMECARD_LIB.TIMECARD(SCH_1):UNNAMED_515_CAPACITOR_I128_1   I129 @TIMECARD_LIB.TIMECARD(SCH_1):PAGE515
     1 UNNAMED_515_CAPACITOR_I130_1 @TIMECARD_LIB.TIMECARD(SCH_1):UNNAMED_515_CAPACITOR_I130_1   I129 @TIMECARD_LIB.TIMECARD(SCH_1):PAGE515

R229 RESISTOR-G155-14701-01,4.7KOHMA
     2 UNNAMED_515_CAPACITOR_I138_1 @TIMECARD_LIB.TIMECARD(SCH_1):UNNAMED_515_CAPACITOR_I138_1   I139 @TIMECARD_LIB.TIMECARD(SCH_1):PAGE515
     1 XP3R3V_FPGA @TIMECARD_LIB.TIMECARD(SCH_1):XP3R3V_FPGA   I139 @TIMECARD_LIB.TIMECARD(SCH_1):PAGE515

R230 RESISTOR-G155-100R0-J0,0OHM,-
     2 FPGA_CFG_INIT_N @TIMECARD_LIB.TIMECARD(SCH_1):FPGA_CFG_INIT_N   I140 @TIMECARD_LIB.TIMECARD(SCH_1):PAGE515
     1 UNNAMED_515_CAPACITOR_I138_1 @TIMECARD_LIB.TIMECARD(SCH_1):UNNAMED_515_CAPACITOR_I138_1   I140 @TIMECARD_LIB.TIMECARD(SCH_1):PAGE515

R231 RESISTOR-G155-04221-01,4.22KOHA
     2 UNNAMED_515_ISL80101IRAJZDFN10_ @TIMECARD_LIB.TIMECARD(SCH_1):UNNAMED_515_ISL80101IRAJZDFN10_I151_SENSE   I146 @TIMECARD_LIB.TIMECARD(SCH_1):PAGE515
     1 XP2R5V_FPGA @TIMECARD_LIB.TIMECARD(SCH_1):XP2R5V_FPGA   I146 @TIMECARD_LIB.TIMECARD(SCH_1):PAGE515

R232 RESISTOR-G155-02101-01,2.1KOHMA
     2 UNNAMED_515_ISL80101IRAJZDFN10_ @TIMECARD_LIB.TIMECARD(SCH_1):UNNAMED_515_ISL80101IRAJZDFN10_I151_SENSE   I143 @TIMECARD_LIB.TIMECARD(SCH_1):PAGE515
     1     SG @TIMECARD_LIB.TIMECARD(SCH_1):SG   I143 @TIMECARD_LIB.TIMECARD(SCH_1):PAGE515

R233 RESISTOR-G155-02101-01,2.1KOHMA
     2 UNNAMED_515_ISL80101IRAJZDFN10_ @TIMECARD_LIB.TIMECARD(SCH_1):UNNAMED_515_ISL80101IRAJZDFN10_I151_SENSE   I145 @TIMECARD_LIB.TIMECARD(SCH_1):PAGE515
     1     SG @TIMECARD_LIB.TIMECARD(SCH_1):SG   I145 @TIMECARD_LIB.TIMECARD(SCH_1):PAGE515

R234 RESISTOR-G155-133R0-01,33OHM,1%
     2 FPGA_FLASH_DQ0_MOSI @TIMECARD_LIB.TIMECARD(SCH_1):FPGA_FLASH_DQ0_MOSI   I258 @TIMECARD_LIB.TIMECARD(SCH_1):PAGE161
     1 FPGA_D00_MOSI @TIMECARD_LIB.TIMECARD(SCH_1):FPGA_D00_MOSI   I258 @TIMECARD_LIB.TIMECARD(SCH_1):PAGE161

R235 RESISTOR-G155-14701-01,4.7KOHMA
     2 CLK_200M_OE @TIMECARD_LIB.TIMECARD(SCH_1):CLK_200M_OE   I149 @TIMECARD_LIB.TIMECARD(SCH_1):PAGE522
     1 VDD3V3_OSC_200M @TIMECARD_LIB.TIMECARD(SCH_1):VDD3V3_OSC_200M   I149 @TIMECARD_LIB.TIMECARD(SCH_1):PAGE522

R236 RESISTOR-G155-14701-01,4.7KOHMA
     2 CLK_125M_OE @TIMECARD_LIB.TIMECARD(SCH_1):CLK_125M_OE   I156 @TIMECARD_LIB.TIMECARD(SCH_1):PAGE522
     1 VDD3V3_OSC_125M @TIMECARD_LIB.TIMECARD(SCH_1):VDD3V3_OSC_125M   I156 @TIMECARD_LIB.TIMECARD(SCH_1):PAGE522

R237 RESISTOR-G155-11002-01,10KOHM,A
     2     SG @TIMECARD_LIB.TIMECARD(SCH_1):SG    I56 @TIMECARD_LIB.TIMECARD(SCH_1):PAGE515
     1 XP3R3V_FPGA_EN_R @TIMECARD_LIB.TIMECARD(SCH_1):XP3R3V_FPGA_EN_R    I56 @TIMECARD_LIB.TIMECARD(SCH_1):PAGE515

R238 RESISTOR-G155-133R0-01,33OHM,1%
     2 FPGA_FLASH_DQ1_MISO @TIMECARD_LIB.TIMECARD(SCH_1):FPGA_FLASH_DQ1_MISO   I259 @TIMECARD_LIB.TIMECARD(SCH_1):PAGE161
     1 FPGA_D01 @TIMECARD_LIB.TIMECARD(SCH_1):FPGA_D01   I259 @TIMECARD_LIB.TIMECARD(SCH_1):PAGE161

R239 RESISTOR-G155-11500-01,150OHM,A
     2     SG @TIMECARD_LIB.TIMECARD(SCH_1):SG   I169 @TIMECARD_LIB.TIMECARD(SCH_1):PAGE522
     1 OSC_200M_CLKN @TIMECARD_LIB.TIMECARD(SCH_1):OSC_200M_CLKN   I169 @TIMECARD_LIB.TIMECARD(SCH_1):PAGE522

R240 RESISTOR-G155-11500-01,150OHM,A
     2     SG @TIMECARD_LIB.TIMECARD(SCH_1):SG   I172 @TIMECARD_LIB.TIMECARD(SCH_1):PAGE522
     1 OSC_125M_CLKN @TIMECARD_LIB.TIMECARD(SCH_1):OSC_125M_CLKN   I172 @TIMECARD_LIB.TIMECARD(SCH_1):PAGE522

R241 RESISTOR-G155-11500-01,150OHM,A
     2     SG @TIMECARD_LIB.TIMECARD(SCH_1):SG   I170 @TIMECARD_LIB.TIMECARD(SCH_1):PAGE522
     1 OSC_200M_CLKP @TIMECARD_LIB.TIMECARD(SCH_1):OSC_200M_CLKP   I170 @TIMECARD_LIB.TIMECARD(SCH_1):PAGE522

R242 RESISTOR-G155-11500-01,150OHM,A
     2     SG @TIMECARD_LIB.TIMECARD(SCH_1):SG   I174 @TIMECARD_LIB.TIMECARD(SCH_1):PAGE522
     1 OSC_125M_CLKP @TIMECARD_LIB.TIMECARD(SCH_1):OSC_125M_CLKP   I174 @TIMECARD_LIB.TIMECARD(SCH_1):PAGE522

R243 RESISTOR-G155-14701-01,4.7KOHMA
     2 XP1R0V_PG @TIMECARD_LIB.TIMECARD(SCH_1):XP1R0V_PG    I44 @TIMECARD_LIB.TIMECARD(SCH_1):PAGE523
     1 XP3R3V @TIMECARD_LIB.TIMECARD(SCH_1):XP3R3V    I44 @TIMECARD_LIB.TIMECARD(SCH_1):PAGE523

R244 RESISTOR-G155-100R0-J0,0OHM,-
     2 UNNAMED_523_CAPACITOR_I7_1 @TIMECARD_LIB.TIMECARD(SCH_1):UNNAMED_523_CAPACITOR_I7_1   I109 @TIMECARD_LIB.TIMECARD(SCH_1):PAGE523
     1 XP3R3V_PG @TIMECARD_LIB.TIMECARD(SCH_1):XP3R3V_PG   I109 @TIMECARD_LIB.TIMECARD(SCH_1):PAGE523

R245 RESISTOR-G155-100R0-J0,0OHM,-
     2 XP1R0V_PG @TIMECARD_LIB.TIMECARD(SCH_1):XP1R0V_PG   I104 @TIMECARD_LIB.TIMECARD(SCH_1):PAGE523
     1 XP1R0V_FPGA_PG @TIMECARD_LIB.TIMECARD(SCH_1):XP1R0V_FPGA_PG   I104 @TIMECARD_LIB.TIMECARD(SCH_1):PAGE523

R246 RESISTOR-A155-05101-DL,5.1KOHMA
     2     SG @TIMECARD_LIB.TIMECARD(SCH_1):SG    I51 @TIMECARD_LIB.TIMECARD(SCH_1):PAGE523
     1 UNNAMED_523_CAPACITOR_I7_1 @TIMECARD_LIB.TIMECARD(SCH_1):UNNAMED_523_CAPACITOR_I7_1    I51 @TIMECARD_LIB.TIMECARD(SCH_1):PAGE523

R247 RESISTOR-G155-11002-01,10KOHM,A
     2 UNNAMED_523_CAPACITOR_I7_1 @TIMECARD_LIB.TIMECARD(SCH_1):UNNAMED_523_CAPACITOR_I7_1    I54 @TIMECARD_LIB.TIMECARD(SCH_1):PAGE523
     1 VIN_XP1R0V @TIMECARD_LIB.TIMECARD(SCH_1):VIN_XP1R0V    I54 @TIMECARD_LIB.TIMECARD(SCH_1):PAGE523

R248 RESISTOR-G155-11003-01,100KOHMA
     2 XP1R0V_AGND @TIMECARD_LIB.TIMECARD(SCH_1):XP1R0V_AGND    I15 @TIMECARD_LIB.TIMECARD(SCH_1):PAGE523
     1 XP1R0V_RT @TIMECARD_LIB.TIMECARD(SCH_1):XP1R0V_RT    I15 @TIMECARD_LIB.TIMECARD(SCH_1):PAGE523

R249 RESISTOR-G155-14701-01,4.7KOHMA
     2 UNNAMED_523_CAPACITOR_I9_1 @TIMECARD_LIB.TIMECARD(SCH_1):UNNAMED_523_CAPACITOR_I9_1    I16 @TIMECARD_LIB.TIMECARD(SCH_1):PAGE523
     1 XP1R0V_COMP @TIMECARD_LIB.TIMECARD(SCH_1):XP1R0V_COMP    I16 @TIMECARD_LIB.TIMECARD(SCH_1):PAGE523

R250 RESISTOR-G155-100R0-J0,0OHM,-
     2 UNNAMED_523_CAPACITOR_I24_1 @TIMECARD_LIB.TIMECARD(SCH_1):UNNAMED_523_CAPACITOR_I24_1    I23 @TIMECARD_LIB.TIMECARD(SCH_1):PAGE523
     1 XP1R0V_BT @TIMECARD_LIB.TIMECARD(SCH_1):XP1R0V_BT    I23 @TIMECARD_LIB.TIMECARD(SCH_1):PAGE523

R251 RESISTOR-G155-03322-01,33.2KOHA
     2 XP1R0V_FB_R_TO_AGND @TIMECARD_LIB.TIMECARD(SCH_1):XP1R0V_FB_R_TO_AGND    I56 @TIMECARD_LIB.TIMECARD(SCH_1):PAGE523
     1 XP1R0V_AGND @TIMECARD_LIB.TIMECARD(SCH_1):XP1R0V_AGND    I56 @TIMECARD_LIB.TIMECARD(SCH_1):PAGE523

R252 RESISTOR-G156-100R0-J0,0OHM,-
     2 XP1R0V_FB_R_TO_AGND @TIMECARD_LIB.TIMECARD(SCH_1):XP1R0V_FB_R_TO_AGND    I57 @TIMECARD_LIB.TIMECARD(SCH_1):PAGE523
     1 XP1R0V_AGND @TIMECARD_LIB.TIMECARD(SCH_1):XP1R0V_AGND    I57 @TIMECARD_LIB.TIMECARD(SCH_1):PAGE523

R253 RESISTOR-G157-12R20-01,2.2OHM,A
     2     SG @TIMECARD_LIB.TIMECARD(SCH_1):SG    I26 @TIMECARD_LIB.TIMECARD(SCH_1):PAGE523
     1 UNNAMED_523_CAPACITOR_I31_2 @TIMECARD_LIB.TIMECARD(SCH_1):UNNAMED_523_CAPACITOR_I31_2    I26 @TIMECARD_LIB.TIMECARD(SCH_1):PAGE523

R254 RESISTOR-G155-120R0-01,20OHM,1%
     2 UNNAMED_523_CAPACITOR_I28_1 @TIMECARD_LIB.TIMECARD(SCH_1):UNNAMED_523_CAPACITOR_I28_1    I30 @TIMECARD_LIB.TIMECARD(SCH_1):PAGE523
     1 XP1R0V_FPGA @TIMECARD_LIB.TIMECARD(SCH_1):XP1R0V_FPGA    I30 @TIMECARD_LIB.TIMECARD(SCH_1):PAGE523

R255 RESISTOR-G155-02262-01,22.6K,1%
     2 XP1R0V_FB_R_TO_AGND @TIMECARD_LIB.TIMECARD(SCH_1):XP1R0V_FB_R_TO_AGND    I29 @TIMECARD_LIB.TIMECARD(SCH_1):PAGE523
     1 UNNAMED_523_CAPACITOR_I28_1 @TIMECARD_LIB.TIMECARD(SCH_1):UNNAMED_523_CAPACITOR_I28_1    I29 @TIMECARD_LIB.TIMECARD(SCH_1):PAGE523

R256 RESISTOR-G155-11001-01,1KOHM,1%
     2 UNNAMED_14_RESISTOR_I65_2 @TIMECARD_LIB.TIMECARD(SCH_1):UNNAMED_14_RESISTOR_I65_2    I65 @TIMECARD_LIB.TIMECARD(SCH_1):PAGE14
     1 UNNAMED_14_OPTICAL_I143_A @TIMECARD_LIB.TIMECARD(SCH_1):UNNAMED_14_OPTICAL_I143_A    I65 @TIMECARD_LIB.TIMECARD(SCH_1):PAGE14

R257 RESISTOR-G155-13300-01,330OHM,A
     2 XP3R3V_FPGA @TIMECARD_LIB.TIMECARD(SCH_1):XP3R3V_FPGA    I67 @TIMECARD_LIB.TIMECARD(SCH_1):PAGE14
     1 UNNAMED_14_OPTICAL_I12_A @TIMECARD_LIB.TIMECARD(SCH_1):UNNAMED_14_OPTICAL_I12_A    I67 @TIMECARD_LIB.TIMECARD(SCH_1):PAGE14

R258 RESISTOR-G155-13300-01,330OHM,A
     2 XP3R3V_FPGA @TIMECARD_LIB.TIMECARD(SCH_1):XP3R3V_FPGA    I68 @TIMECARD_LIB.TIMECARD(SCH_1):PAGE14
     1 UNNAMED_14_OPTICAL_I11_A @TIMECARD_LIB.TIMECARD(SCH_1):UNNAMED_14_OPTICAL_I11_A    I68 @TIMECARD_LIB.TIMECARD(SCH_1):PAGE14

R259 RESISTOR-G155-13300-01,330OHM,A
     2 XP3R3V_FPGA @TIMECARD_LIB.TIMECARD(SCH_1):XP3R3V_FPGA    I69 @TIMECARD_LIB.TIMECARD(SCH_1):PAGE14
     1 UNNAMED_14_OPTICAL_I136_A @TIMECARD_LIB.TIMECARD(SCH_1):UNNAMED_14_OPTICAL_I136_A    I69 @TIMECARD_LIB.TIMECARD(SCH_1):PAGE14

R260 RESISTOR-G155-11001-01,1KOHM,1%
     2 XP3R3V_FPGA_EN_R @TIMECARD_LIB.TIMECARD(SCH_1):XP3R3V_FPGA_EN_R    I67 @TIMECARD_LIB.TIMECARD(SCH_1):PAGE515
     1 XP3R3V @TIMECARD_LIB.TIMECARD(SCH_1):XP3R3V    I67 @TIMECARD_LIB.TIMECARD(SCH_1):PAGE515

R261 RESISTOR-G155-13300-01,330OHM,A
     2 XP3R3V_FPGA @TIMECARD_LIB.TIMECARD(SCH_1):XP3R3V_FPGA    I70 @TIMECARD_LIB.TIMECARD(SCH_1):PAGE14
     1 UNNAMED_14_OPTICAL_I137_A @TIMECARD_LIB.TIMECARD(SCH_1):UNNAMED_14_OPTICAL_I137_A    I70 @TIMECARD_LIB.TIMECARD(SCH_1):PAGE14

R262 RESISTOR-G155-11001-01,1KOHM,1%
     2 XP12R0V @TIMECARD_LIB.TIMECARD(SCH_1):XP12R0V    I66 @TIMECARD_LIB.TIMECARD(SCH_1):PAGE14
     1 UNNAMED_14_RESISTOR_I65_2 @TIMECARD_LIB.TIMECARD(SCH_1):UNNAMED_14_RESISTOR_I65_2    I66 @TIMECARD_LIB.TIMECARD(SCH_1):PAGE14

R263 RESISTOR-G155-100R0-J0,0OHM,-
     2 XP3R3V_PG @TIMECARD_LIB.TIMECARD(SCH_1):XP3R3V_PG    I47 @TIMECARD_LIB.TIMECARD(SCH_1):PAGE517
     1 R_XP3R3V_PG @TIMECARD_LIB.TIMECARD(SCH_1):R_XP3R3V_PG    I47 @TIMECARD_LIB.TIMECARD(SCH_1):PAGE517

R264 RESISTOR-G155-11003-01,100KOHMA
     2 R_MAC_UART_RX_FPGA_TX @TIMECARD_LIB.TIMECARD(SCH_1):R_MAC_UART_RX_FPGA_TX   I222 @TIMECARD_LIB.TIMECARD(SCH_1):PAGE527
     1 XP3R3V_FPGA @TIMECARD_LIB.TIMECARD(SCH_1):XP3R3V_FPGA   I222 @TIMECARD_LIB.TIMECARD(SCH_1):PAGE527

R265 RESISTOR-G155-11003-01,100KOHMA
     2 UART_MAC_TX_FPGA_RX @TIMECARD_LIB.TIMECARD(SCH_1):UART_MAC_TX_FPGA_RX   I221 @TIMECARD_LIB.TIMECARD(SCH_1):PAGE527
     1 XP3R3V_FPGA @TIMECARD_LIB.TIMECARD(SCH_1):XP3R3V_FPGA   I221 @TIMECARD_LIB.TIMECARD(SCH_1):PAGE527

R266 RESISTOR-G155-133R0-01,33OHM,1%
     2 XP5R0V_USB_CONN_DET @TIMECARD_LIB.TIMECARD(SCH_1):XP5R0V_USB_CONN_DET   I204 @TIMECARD_LIB.TIMECARD(SCH_1):PAGE527
     1 RSVD_DBG_USB_MUX_SEL @TIMECARD_LIB.TIMECARD(SCH_1):RSVD_DBG_USB_MUX_SEL   I204 @TIMECARD_LIB.TIMECARD(SCH_1):PAGE527

R267 RESISTOR-G155-133R0-01,33OHM,1%
     2 FPGA_IN_MAC_USB_OC_N @TIMECARD_LIB.TIMECARD(SCH_1):FPGA_IN_MAC_USB_OC_N   I206 @TIMECARD_LIB.TIMECARD(SCH_1):PAGE527
     1 UNNAMED_527_RESISTOR_I206_1 @TIMECARD_LIB.TIMECARD(SCH_1):UNNAMED_527_RESISTOR_I206_1   I206 @TIMECARD_LIB.TIMECARD(SCH_1):PAGE527

R268 RESISTOR-G155-11003-01,100KOHMA
     2 GPS_UART_RXD @TIMECARD_LIB.TIMECARD(SCH_1):GPS_UART_RXD    I38 @TIMECARD_LIB.TIMECARD(SCH_1):PAGE11
     1 XP3R3V_FPGA @TIMECARD_LIB.TIMECARD(SCH_1):XP3R3V_FPGA    I38 @TIMECARD_LIB.TIMECARD(SCH_1):PAGE11

R269 RESISTOR-G155-11003-01,100KOHMA
     2 UART_GPS_TX_FPGA_RX @TIMECARD_LIB.TIMECARD(SCH_1):UART_GPS_TX_FPGA_RX    I40 @TIMECARD_LIB.TIMECARD(SCH_1):PAGE11
     1 XP3R3V_FPGA @TIMECARD_LIB.TIMECARD(SCH_1):XP3R3V_FPGA    I40 @TIMECARD_LIB.TIMECARD(SCH_1):PAGE11

R270 RESISTOR-G155-14701-01,4.7KOHMA
     2 FPGA_IN_GPSTP1_OUT @TIMECARD_LIB.TIMECARD(SCH_1):FPGA_IN_GPSTP1_OUT   I140 @TIMECARD_LIB.TIMECARD(SCH_1):PAGE161
     1     SG @TIMECARD_LIB.TIMECARD(SCH_1):SG   I140 @TIMECARD_LIB.TIMECARD(SCH_1):PAGE161

R271 RESISTOR-G155-14701-01,4.7KOHMA
     2 FPGA_IN_GPSTP2_OUT @TIMECARD_LIB.TIMECARD(SCH_1):FPGA_IN_GPSTP2_OUT   I200 @TIMECARD_LIB.TIMECARD(SCH_1):PAGE161
     1     SG @TIMECARD_LIB.TIMECARD(SCH_1):SG   I200 @TIMECARD_LIB.TIMECARD(SCH_1):PAGE161

R272 RESISTOR-G155-11000-01,100OHM,A
     2 UNNAMED_14_LED4PV14_I265_3 @TIMECARD_LIB.TIMECARD(SCH_1):UNNAMED_14_LED4PV14_I265_3   I163 @TIMECARD_LIB.TIMECARD(SCH_1):PAGE14
     1 FPGA_OUT_SMA1_LED_RED_N @TIMECARD_LIB.TIMECARD(SCH_1):FPGA_OUT_SMA1_LED_RED_N   I163 @TIMECARD_LIB.TIMECARD(SCH_1):PAGE14

R273 RESISTOR-G155-11000-01,100OHM,A
     2 UNNAMED_14_LED4PV14_I266_1 @TIMECARD_LIB.TIMECARD(SCH_1):UNNAMED_14_LED4PV14_I266_1   I165 @TIMECARD_LIB.TIMECARD(SCH_1):PAGE14
     1 FPGA_OUT_SMA2_LED_BLUE_N @TIMECARD_LIB.TIMECARD(SCH_1):FPGA_OUT_SMA2_LED_BLUE_N   I165 @TIMECARD_LIB.TIMECARD(SCH_1):PAGE14

R274 RESISTOR-G155-11000-01,100OHM,A
     2 UNNAMED_14_LED4PV14_I266_4 @TIMECARD_LIB.TIMECARD(SCH_1):UNNAMED_14_LED4PV14_I266_4   I171 @TIMECARD_LIB.TIMECARD(SCH_1):PAGE14
     1 FPGA_OUT_SMA2_LED_GREEN_N @TIMECARD_LIB.TIMECARD(SCH_1):FPGA_OUT_SMA2_LED_GREEN_N   I171 @TIMECARD_LIB.TIMECARD(SCH_1):PAGE14

R275 RESISTOR-G155-11000-01,100OHM,A
     2 FPGA_IN_MAC_PPS_OUTN @TIMECARD_LIB.TIMECARD(SCH_1):FPGA_IN_MAC_PPS_OUTN    I39 @TIMECARD_LIB.TIMECARD(SCH_1):PAGE163
     1 FPGA_IN_MAC_PPS_OUTP @TIMECARD_LIB.TIMECARD(SCH_1):FPGA_IN_MAC_PPS_OUTP    I39 @TIMECARD_LIB.TIMECARD(SCH_1):PAGE163

R276 RESISTOR-G155-11000-01,100OHM,A
     2 FPGA_OUT_MAC_PPS_IN0N @TIMECARD_LIB.TIMECARD(SCH_1):FPGA_OUT_MAC_PPS_IN0N    I38 @TIMECARD_LIB.TIMECARD(SCH_1):PAGE163
     1 FPGA_OUT_MAC_PPS_IN0P @TIMECARD_LIB.TIMECARD(SCH_1):FPGA_OUT_MAC_PPS_IN0P    I38 @TIMECARD_LIB.TIMECARD(SCH_1):PAGE163

R277 RESISTOR-G155-11000-01,100OHM,A
     2 FPGA_OUT_MAC_PPS_IN1N @TIMECARD_LIB.TIMECARD(SCH_1):FPGA_OUT_MAC_PPS_IN1N    I37 @TIMECARD_LIB.TIMECARD(SCH_1):PAGE163
     1 FPGA_OUT_MAC_PPS_IN1P @TIMECARD_LIB.TIMECARD(SCH_1):FPGA_OUT_MAC_PPS_IN1P    I37 @TIMECARD_LIB.TIMECARD(SCH_1):PAGE163

R278 RESISTOR-G155-11000-01,100OHM,A
     2 MHZ200CLKN_CLKIN @TIMECARD_LIB.TIMECARD(SCH_1):MHZ200CLKN_CLKIN    I36 @TIMECARD_LIB.TIMECARD(SCH_1):PAGE163
     1 MHZ200CLKP_CLKIN @TIMECARD_LIB.TIMECARD(SCH_1):MHZ200CLKP_CLKIN    I36 @TIMECARD_LIB.TIMECARD(SCH_1):PAGE163

R279 RESISTOR-G155-13300-01,330OHM,A
     2 XP3R3V_FPGA @TIMECARD_LIB.TIMECARD(SCH_1):XP3R3V_FPGA    I72 @TIMECARD_LIB.TIMECARD(SCH_1):PAGE14
     1 UNNAMED_14_OPTICAL_I138_A @TIMECARD_LIB.TIMECARD(SCH_1):UNNAMED_14_OPTICAL_I138_A    I72 @TIMECARD_LIB.TIMECARD(SCH_1):PAGE14

R280 RESISTOR-G155-13300-01,330OHM,A
     2 XP3R3V_FPGA @TIMECARD_LIB.TIMECARD(SCH_1):XP3R3V_FPGA    I74 @TIMECARD_LIB.TIMECARD(SCH_1):PAGE14
     1 UNNAMED_14_OPTICAL_I139_A @TIMECARD_LIB.TIMECARD(SCH_1):UNNAMED_14_OPTICAL_I139_A    I74 @TIMECARD_LIB.TIMECARD(SCH_1):PAGE14

R281 RESISTOR-G155-14701-01,4.7KOHMA
     2 ICP10100_I2C_SDA @TIMECARD_LIB.TIMECARD(SCH_1):ICP10100_I2C_SDA    I70 @TIMECARD_LIB.TIMECARD(SCH_1):PAGE8
     1 XP3R3V_FPGA @TIMECARD_LIB.TIMECARD(SCH_1):XP3R3V_FPGA    I70 @TIMECARD_LIB.TIMECARD(SCH_1):PAGE8

R282 RESISTOR-G155-14701-01,4.7KOHMA
     2 ICP10100_I2C_SCL @TIMECARD_LIB.TIMECARD(SCH_1):ICP10100_I2C_SCL    I69 @TIMECARD_LIB.TIMECARD(SCH_1):PAGE8
     1 XP3R3V_FPGA @TIMECARD_LIB.TIMECARD(SCH_1):XP3R3V_FPGA    I69 @TIMECARD_LIB.TIMECARD(SCH_1):PAGE8

R283 RESISTOR-G155-11002-01,10KOHM,A
     2 FPGA_IO_2 @TIMECARD_LIB.TIMECARD(SCH_1):FPGA_IO_2  I1609 @TIMECARD_LIB.TIMECARD(SCH_1):PAGE16
     1 XP3R3V_FPGA @TIMECARD_LIB.TIMECARD(SCH_1):XP3R3V_FPGA  I1609 @TIMECARD_LIB.TIMECARD(SCH_1):PAGE16

R284 RESISTOR-G155-14701-01,4.7KOHMA
     2 FPGA_IO_2 @TIMECARD_LIB.TIMECARD(SCH_1):FPGA_IO_2  I1547 @TIMECARD_LIB.TIMECARD(SCH_1):PAGE16
     1     SG @TIMECARD_LIB.TIMECARD(SCH_1):SG  I1547 @TIMECARD_LIB.TIMECARD(SCH_1):PAGE16

R285 RESISTOR-G155-11002-01,10KOHM,A
     2 FPGA_IO_3 @TIMECARD_LIB.TIMECARD(SCH_1):FPGA_IO_3  I1606 @TIMECARD_LIB.TIMECARD(SCH_1):PAGE16
     1 XP3R3V_FPGA @TIMECARD_LIB.TIMECARD(SCH_1):XP3R3V_FPGA  I1606 @TIMECARD_LIB.TIMECARD(SCH_1):PAGE16

R286 RESISTOR-G155-14701-01,4.7KOHMA
     2 FPGA_IO_3 @TIMECARD_LIB.TIMECARD(SCH_1):FPGA_IO_3  I1549 @TIMECARD_LIB.TIMECARD(SCH_1):PAGE16
     1     SG @TIMECARD_LIB.TIMECARD(SCH_1):SG  I1549 @TIMECARD_LIB.TIMECARD(SCH_1):PAGE16

R287 RESISTOR-G155-14701-01,4.7KOHMA
     2 XP3R3V_FPGA @TIMECARD_LIB.TIMECARD(SCH_1):XP3R3V_FPGA   I211 @TIMECARD_LIB.TIMECARD(SCH_1):PAGE527
     1 FPGA_IN_MAC_ALARM_OUT_N @TIMECARD_LIB.TIMECARD(SCH_1):FPGA_IN_MAC_ALARM_OUT_N   I211 @TIMECARD_LIB.TIMECARD(SCH_1):PAGE527

R288 RESISTOR-G155-14701-01,4.7KOHMA
     2 FPGA_IN_MAC_BITEOUT @TIMECARD_LIB.TIMECARD(SCH_1):FPGA_IN_MAC_BITE OUT   I201 @TIMECARD_LIB.TIMECARD(SCH_1):PAGE161
     1     SG @TIMECARD_LIB.TIMECARD(SCH_1):SG   I201 @TIMECARD_LIB.TIMECARD(SCH_1):PAGE161

R289 RESISTOR-G155-14701-01,4.7KOHMA
     2 FPGA_IN_BNO080_INT_N @TIMECARD_LIB.TIMECARD(SCH_1):FPGA_IN_BNO080_INT_N    I38 @TIMECARD_LIB.TIMECARD(SCH_1):PAGE9
     1 XP3R3V_FPGA @TIMECARD_LIB.TIMECARD(SCH_1):XP3R3V_FPGA    I38 @TIMECARD_LIB.TIMECARD(SCH_1):PAGE9

R290 RESISTOR-G155-14701-01,4.7KOHMA
     2 BNO080_SA0 @TIMECARD_LIB.TIMECARD(SCH_1):BNO080_SA0    I51 @TIMECARD_LIB.TIMECARD(SCH_1):PAGE9
     1 XP3R3V_FPGA @TIMECARD_LIB.TIMECARD(SCH_1):XP3R3V_FPGA    I51 @TIMECARD_LIB.TIMECARD(SCH_1):PAGE9

R291 RESISTOR-G155-14701-01,4.7KOHMA
     2 R_BNO080_RST_N @TIMECARD_LIB.TIMECARD(SCH_1):R_BNO080_RST_N    I44 @TIMECARD_LIB.TIMECARD(SCH_1):PAGE9
     1 XP3R3V_FPGA @TIMECARD_LIB.TIMECARD(SCH_1):XP3R3V_FPGA    I44 @TIMECARD_LIB.TIMECARD(SCH_1):PAGE9

R292 RESISTOR-G155-11002-01,10KOHM,A
     2 FPGA_IO_4 @TIMECARD_LIB.TIMECARD(SCH_1):FPGA_IO_4  I1605 @TIMECARD_LIB.TIMECARD(SCH_1):PAGE16
     1 XP3R3V_FPGA @TIMECARD_LIB.TIMECARD(SCH_1):XP3R3V_FPGA  I1605 @TIMECARD_LIB.TIMECARD(SCH_1):PAGE16

R293 RESISTOR-G155-14701-01,4.7KOHMA
     2 FPGA_IO_4 @TIMECARD_LIB.TIMECARD(SCH_1):FPGA_IO_4  I1555 @TIMECARD_LIB.TIMECARD(SCH_1):PAGE16
     1     SG @TIMECARD_LIB.TIMECARD(SCH_1):SG  I1555 @TIMECARD_LIB.TIMECARD(SCH_1):PAGE16

R294 RESISTOR-G155-133R0-01,33OHM,1%
     2 FPGA_CFG_INIT_N @TIMECARD_LIB.TIMECARD(SCH_1):FPGA_CFG_INIT_N    I45 @TIMECARD_LIB.TIMECARD(SCH_1):PAGE516
     1 XP5R0V_PG @TIMECARD_LIB.TIMECARD(SCH_1):XP5R0V_PG    I45 @TIMECARD_LIB.TIMECARD(SCH_1):PAGE516

R295 RESISTOR-G155-11002-01,10KOHM,A
     2 UNNAMED_515_NCP45560IMNTWGHDFN1 @TIMECARD_LIB.TIMECARD(SCH_1):UNNAMED_515_NCP45560IMNTWGHDFN12_I82_PG    I69 @TIMECARD_LIB.TIMECARD(SCH_1):PAGE515
     1 XP3R3V_FPGA @TIMECARD_LIB.TIMECARD(SCH_1):XP3R3V_FPGA    I69 @TIMECARD_LIB.TIMECARD(SCH_1):PAGE515

R296 RESISTOR-G155-14701-01,4.7KOHMA
     2 R_SHT3X_RST_N @TIMECARD_LIB.TIMECARD(SCH_1):R_SHT3X_RST_N    I38 @TIMECARD_LIB.TIMECARD(SCH_1):PAGE7
     1 XP3R3V_FPGA @TIMECARD_LIB.TIMECARD(SCH_1):XP3R3V_FPGA    I38 @TIMECARD_LIB.TIMECARD(SCH_1):PAGE7

R297 RESISTOR-G155-14701-01,4.7KOHMA
     2     SG @TIMECARD_LIB.TIMECARD(SCH_1):SG    I39 @TIMECARD_LIB.TIMECARD(SCH_1):PAGE7
     1 R_SHT3X_RST_N @TIMECARD_LIB.TIMECARD(SCH_1):R_SHT3X_RST_N    I39 @TIMECARD_LIB.TIMECARD(SCH_1):PAGE7

R298 RESISTOR-G155-133R0-01,33OHM,1%
     2 FPGA_OUT_SHT3X_RST_N @TIMECARD_LIB.TIMECARD(SCH_1):FPGA_OUT_SHT3X_RST_N    I33 @TIMECARD_LIB.TIMECARD(SCH_1):PAGE7
     1 R_SHT3X_RST_N @TIMECARD_LIB.TIMECARD(SCH_1):R_SHT3X_RST_N    I33 @TIMECARD_LIB.TIMECARD(SCH_1):PAGE7

R299 RESISTOR-G155-133R0-01,33OHM,1%
     2 FPGA_IN_SHT3X_ALERT_N @TIMECARD_LIB.TIMECARD(SCH_1):FPGA_IN_SHT3X_ALERT_N    I40 @TIMECARD_LIB.TIMECARD(SCH_1):PAGE7
     1 R_SHT3X_ALERT_N @TIMECARD_LIB.TIMECARD(SCH_1):R_SHT3X_ALERT_N    I40 @TIMECARD_LIB.TIMECARD(SCH_1):PAGE7

R300 RESISTOR-G155-14701-01,4.7KOHMA
     2 FPGA_IN_SHT3X_ALERT_N @TIMECARD_LIB.TIMECARD(SCH_1):FPGA_IN_SHT3X_ALERT_N    I41 @TIMECARD_LIB.TIMECARD(SCH_1):PAGE7
     1 XP3R3V_FPGA @TIMECARD_LIB.TIMECARD(SCH_1):XP3R3V_FPGA    I41 @TIMECARD_LIB.TIMECARD(SCH_1):PAGE7

R301 RESISTOR-G155-14701-01,4.7KOHMA
     2     SG @TIMECARD_LIB.TIMECARD(SCH_1):SG    I43 @TIMECARD_LIB.TIMECARD(SCH_1):PAGE9
     1 R_BNO080_RST_N @TIMECARD_LIB.TIMECARD(SCH_1):R_BNO080_RST_N    I43 @TIMECARD_LIB.TIMECARD(SCH_1):PAGE9

R302 RESISTOR-G155-11001-01,1KOHM,1%
     2     SG @TIMECARD_LIB.TIMECARD(SCH_1):SG    I52 @TIMECARD_LIB.TIMECARD(SCH_1):PAGE9
     1 BNO080_SA0 @TIMECARD_LIB.TIMECARD(SCH_1):BNO080_SA0    I52 @TIMECARD_LIB.TIMECARD(SCH_1):PAGE9

R303 RESISTOR-G155-11001-01,1KOHM,1%
     2     SG @TIMECARD_LIB.TIMECARD(SCH_1):SG    I50 @TIMECARD_LIB.TIMECARD(SCH_1):PAGE9
     1 UNNAMED_9_BNO080LGA28_I29_PS1 @TIMECARD_LIB.TIMECARD(SCH_1):UNNAMED_9_BNO080LGA28_I29_PS1    I50 @TIMECARD_LIB.TIMECARD(SCH_1):PAGE9

R304 RESISTOR-G155-14701-01,4.7KOHMA
     2 R_BNO080_BOOT_N @TIMECARD_LIB.TIMECARD(SCH_1):R_BNO080_BOOT_N    I37 @TIMECARD_LIB.TIMECARD(SCH_1):PAGE9
     1 XP3R3V_FPGA @TIMECARD_LIB.TIMECARD(SCH_1):XP3R3V_FPGA    I37 @TIMECARD_LIB.TIMECARD(SCH_1):PAGE9

R305 RESISTOR-G155-11001-01,1KOHM,1%
     2     SG @TIMECARD_LIB.TIMECARD(SCH_1):SG    I49 @TIMECARD_LIB.TIMECARD(SCH_1):PAGE9
     1 UNNAMED_9_BNO080LGA28_I29_PS0 @TIMECARD_LIB.TIMECARD(SCH_1):UNNAMED_9_BNO080LGA28_I29_PS0    I49 @TIMECARD_LIB.TIMECARD(SCH_1):PAGE9

R306 RESISTOR-G155-14701-01,4.7KOHMA
     2 UNNAMED_9_BNO080LGA28_I29_CLKSE @TIMECARD_LIB.TIMECARD(SCH_1):UNNAMED_9_BNO080LGA28_I29_CLKSEL0    I55 @TIMECARD_LIB.TIMECARD(SCH_1):PAGE9
     1 XP3R3V_FPGA @TIMECARD_LIB.TIMECARD(SCH_1):XP3R3V_FPGA    I55 @TIMECARD_LIB.TIMECARD(SCH_1):PAGE9

R307 RESISTOR-G155-11001-01,1KOHM,1%
     2     SG @TIMECARD_LIB.TIMECARD(SCH_1):SG    I47 @TIMECARD_LIB.TIMECARD(SCH_1):PAGE9
     1 UNNAMED_9_BNO080LGA28_I29_CLKSE @TIMECARD_LIB.TIMECARD(SCH_1):UNNAMED_9_BNO080LGA28_I29_CLKSEL0    I47 @TIMECARD_LIB.TIMECARD(SCH_1):PAGE9

R308 RESISTOR-G155-11002-01,10KOHM,A
     2 FPGA_IO_5 @TIMECARD_LIB.TIMECARD(SCH_1):FPGA_IO_5  I1604 @TIMECARD_LIB.TIMECARD(SCH_1):PAGE16
     1 XP3R3V_FPGA @TIMECARD_LIB.TIMECARD(SCH_1):XP3R3V_FPGA  I1604 @TIMECARD_LIB.TIMECARD(SCH_1):PAGE16

R309 RESISTOR-G155-14701-01,4.7KOHMA
     2 FPGA_IO_5 @TIMECARD_LIB.TIMECARD(SCH_1):FPGA_IO_5  I1557 @TIMECARD_LIB.TIMECARD(SCH_1):PAGE16
     1     SG @TIMECARD_LIB.TIMECARD(SCH_1):SG  I1557 @TIMECARD_LIB.TIMECARD(SCH_1):PAGE16

R310 RESISTOR-G155-100R0-J0,0OHM,-
     2 R_PCA9546_I2C_SDA @TIMECARD_LIB.TIMECARD(SCH_1):R_PCA9546_I2C_SDA   I116 @TIMECARD_LIB.TIMECARD(SCH_1):PAGE5
     1 RGB_LED_I2C_SDA @TIMECARD_LIB.TIMECARD(SCH_1):RGB_LED_I2C_SDA   I116 @TIMECARD_LIB.TIMECARD(SCH_1):PAGE5

R311 RESISTOR-G155-100R0-J0,0OHM,-
     2 R_PCA9546_I2C_SCL @TIMECARD_LIB.TIMECARD(SCH_1):R_PCA9546_I2C_SCL   I115 @TIMECARD_LIB.TIMECARD(SCH_1):PAGE5
     1 RGB_LED_I2C_SCL @TIMECARD_LIB.TIMECARD(SCH_1):RGB_LED_I2C_SCL   I115 @TIMECARD_LIB.TIMECARD(SCH_1):PAGE5

R312 RESISTOR-G155-100R0-J0,0OHM,-
     2 EEPROM_SDA @TIMECARD_LIB.TIMECARD(SCH_1):EEPROM_SDA   I112 @TIMECARD_LIB.TIMECARD(SCH_1):PAGE5
     1 RGB_LED_I2C_SDA @TIMECARD_LIB.TIMECARD(SCH_1):RGB_LED_I2C_SDA   I112 @TIMECARD_LIB.TIMECARD(SCH_1):PAGE5

R313 RESISTOR-G155-100R0-J0,0OHM,-
     2 EEPROM_SCL @TIMECARD_LIB.TIMECARD(SCH_1):EEPROM_SCL   I111 @TIMECARD_LIB.TIMECARD(SCH_1):PAGE5
     1 RGB_LED_I2C_SCL @TIMECARD_LIB.TIMECARD(SCH_1):RGB_LED_I2C_SCL   I111 @TIMECARD_LIB.TIMECARD(SCH_1):PAGE5

R314 RESISTOR-G155-14701-01,4.7KOHMA
     2 UNNAMED_8_PCA9508DPTSSOP8_I51_E @TIMECARD_LIB.TIMECARD(SCH_1):UNNAMED_8_PCA9508DPTSSOP8_I51_EN    I71 @TIMECARD_LIB.TIMECARD(SCH_1):PAGE8
     1 XP3R3V_FPGA @TIMECARD_LIB.TIMECARD(SCH_1):XP3R3V_FPGA    I71 @TIMECARD_LIB.TIMECARD(SCH_1):PAGE8

R315 RESISTOR-G155-100R0-J0,0OHM,-
     2 BF_ICP10100_I2C_SCL @TIMECARD_LIB.TIMECARD(SCH_1):BF_ICP10100_I2C_SCL    I63 @TIMECARD_LIB.TIMECARD(SCH_1):PAGE8
     1 ICP10100_I2C_SCL @TIMECARD_LIB.TIMECARD(SCH_1):ICP10100_I2C_SCL    I63 @TIMECARD_LIB.TIMECARD(SCH_1):PAGE8

R316 RESISTOR-G155-100R0-J0,0OHM,-
     2 BF_ICP10100_I2C_SDA @TIMECARD_LIB.TIMECARD(SCH_1):BF_ICP10100_I2C_SDA    I64 @TIMECARD_LIB.TIMECARD(SCH_1):PAGE8
     1 ICP10100_I2C_SDA @TIMECARD_LIB.TIMECARD(SCH_1):ICP10100_I2C_SDA    I64 @TIMECARD_LIB.TIMECARD(SCH_1):PAGE8

R317 RESISTOR-G155-11002-01,10KOHM,A
     2 R_RGB_LED_I2C_SDA @TIMECARD_LIB.TIMECARD(SCH_1):R_RGB_LED_I2C_SDA   I259 @TIMECARD_LIB.TIMECARD(SCH_1):PAGE14
     1 XP3R3V_FPGA @TIMECARD_LIB.TIMECARD(SCH_1):XP3R3V_FPGA   I259 @TIMECARD_LIB.TIMECARD(SCH_1):PAGE14

R318 RESISTOR-G155-11002-01,10KOHM,A
     2 R_RGB_LED_I2C_SCL @TIMECARD_LIB.TIMECARD(SCH_1):R_RGB_LED_I2C_SCL   I261 @TIMECARD_LIB.TIMECARD(SCH_1):PAGE14
     1 XP3R3V_FPGA @TIMECARD_LIB.TIMECARD(SCH_1):XP3R3V_FPGA   I261 @TIMECARD_LIB.TIMECARD(SCH_1):PAGE14

R319 RESISTOR-G155-133R0-01,33OHM,1%
     2 RGB_LED_SHUTDOWN_N @TIMECARD_LIB.TIMECARD(SCH_1):RGB_LED_SHUTDOWN_N   I249 @TIMECARD_LIB.TIMECARD(SCH_1):PAGE14
     1 FPGA_OUT_RGB_LED_SHUTDOWN_N @TIMECARD_LIB.TIMECARD(SCH_1):FPGA_OUT_RGB_LED_SHUTDOWN_N   I249 @TIMECARD_LIB.TIMECARD(SCH_1):PAGE14

R320 RESISTOR-G155-14701-01,4.7KOHMA
     2 RGB_LED_SHUTDOWN_N @TIMECARD_LIB.TIMECARD(SCH_1):RGB_LED_SHUTDOWN_N   I264 @TIMECARD_LIB.TIMECARD(SCH_1):PAGE14
     1 XP3R3V_FPGA @TIMECARD_LIB.TIMECARD(SCH_1):XP3R3V_FPGA   I264 @TIMECARD_LIB.TIMECARD(SCH_1):PAGE14

R321 RESISTOR-G155-133R0-01,33OHM,1%
     2 R_RGB_LED_I2C_SDA @TIMECARD_LIB.TIMECARD(SCH_1):R_RGB_LED_I2C_SDA   I258 @TIMECARD_LIB.TIMECARD(SCH_1):PAGE14
     1 FPGA_M_RGB_LED_I2C_SDA @TIMECARD_LIB.TIMECARD(SCH_1):FPGA_M_RGB_LED_I2C_SDA   I258 @TIMECARD_LIB.TIMECARD(SCH_1):PAGE14

R322 RESISTOR-G155-133R0-01,33OHM,1%
     2 R_RGB_LED_I2C_SCL @TIMECARD_LIB.TIMECARD(SCH_1):R_RGB_LED_I2C_SCL   I257 @TIMECARD_LIB.TIMECARD(SCH_1):PAGE14
     1 FPGA_M_RGB_LED_I2C_SCL @TIMECARD_LIB.TIMECARD(SCH_1):FPGA_M_RGB_LED_I2C_SCL   I257 @TIMECARD_LIB.TIMECARD(SCH_1):PAGE14

R323 RESISTOR-G155-14701-01,4.7KOHMA
     2     SG @TIMECARD_LIB.TIMECARD(SCH_1):SG   I246 @TIMECARD_LIB.TIMECARD(SCH_1):PAGE14
     1 UNNAMED_14_IS32FL3207QWLA3TRQ_1 @TIMECARD_LIB.TIMECARD(SCH_1):UNNAMED_14_IS32FL3207QWLA3TRQFN29_I219_ISET   I246 @TIMECARD_LIB.TIMECARD(SCH_1):PAGE14

R324 RESISTOR-G155-100R0-J0,0OHM,-
     2 UNNAMED_14_IS32FL3207QWLA3TRQFN @TIMECARD_LIB.TIMECARD(SCH_1):UNNAMED_14_IS32FL3207QWLA3TRQFN29_I219_AD   I247 @TIMECARD_LIB.TIMECARD(SCH_1):PAGE14
     1     SG @TIMECARD_LIB.TIMECARD(SCH_1):SG   I247 @TIMECARD_LIB.TIMECARD(SCH_1):PAGE14

R325 RESISTOR-G155-11002-01,10KOHM,A
     2 FPGA_IO_6 @TIMECARD_LIB.TIMECARD(SCH_1):FPGA_IO_6  I1602 @TIMECARD_LIB.TIMECARD(SCH_1):PAGE16
     1 XP3R3V_FPGA @TIMECARD_LIB.TIMECARD(SCH_1):XP3R3V_FPGA  I1602 @TIMECARD_LIB.TIMECARD(SCH_1):PAGE16

R326 RESISTOR-G155-14701-01,4.7KOHMA
     2 FPGA_IO_6 @TIMECARD_LIB.TIMECARD(SCH_1):FPGA_IO_6  I1552 @TIMECARD_LIB.TIMECARD(SCH_1):PAGE16
     1     SG @TIMECARD_LIB.TIMECARD(SCH_1):SG  I1552 @TIMECARD_LIB.TIMECARD(SCH_1):PAGE16

R327 RESISTOR-G155-11002-01,10KOHM,A
     2 FPGA_IO_7 @TIMECARD_LIB.TIMECARD(SCH_1):FPGA_IO_7  I1603 @TIMECARD_LIB.TIMECARD(SCH_1):PAGE16
     1 XP3R3V_FPGA @TIMECARD_LIB.TIMECARD(SCH_1):XP3R3V_FPGA  I1603 @TIMECARD_LIB.TIMECARD(SCH_1):PAGE16

R328 RESISTOR-G155-14701-01,4.7KOHMA
     2 FPGA_IO_7 @TIMECARD_LIB.TIMECARD(SCH_1):FPGA_IO_7  I1550 @TIMECARD_LIB.TIMECARD(SCH_1):PAGE16
     1     SG @TIMECARD_LIB.TIMECARD(SCH_1):SG  I1550 @TIMECARD_LIB.TIMECARD(SCH_1):PAGE16

R329 RESISTOR-G155-133R0-01,33OHM,1%
     2 UNNAMED_16_CONNHDR2X6FSSMT_I1_4 @TIMECARD_LIB.TIMECARD(SCH_1):UNNAMED_16_CONNHDR2X6FSSMT_I1614_7  I1707 @TIMECARD_LIB.TIMECARD(SCH_1):PAGE16
     1 FPGA_IO_7 @TIMECARD_LIB.TIMECARD(SCH_1):FPGA_IO_7  I1707 @TIMECARD_LIB.TIMECARD(SCH_1):PAGE16

R330 RESISTOR-G155-133R0-01,33OHM,1%
     2 BNO080_EVN_SDA @TIMECARD_LIB.TIMECARD(SCH_1):BNO080_EVN_SDA    I64 @TIMECARD_LIB.TIMECARD(SCH_1):PAGE9
     1 R_BNO080_EVN_SDA @TIMECARD_LIB.TIMECARD(SCH_1):R_BNO080_EVN_SDA    I64 @TIMECARD_LIB.TIMECARD(SCH_1):PAGE9

R331 RESISTOR-G155-14701-01,4.7KOHMA
     2 SMA2_SIG_OUT_BF_EN_N @TIMECARD_LIB.TIMECARD(SCH_1):SMA2_SIG_OUT_BF_EN_N   I280 @TIMECARD_LIB.TIMECARD(SCH_1):PAGE12
     1 XP3R3V_FPGA @TIMECARD_LIB.TIMECARD(SCH_1):XP3R3V_FPGA   I280 @TIMECARD_LIB.TIMECARD(SCH_1):PAGE12

R332 RESISTOR-G155-133R0-01,33OHM,1%
     2 R_LM75B_1_I2C_SDA @TIMECARD_LIB.TIMECARD(SCH_1):R_LM75B_1_I2C_SDA    I15 @TIMECARD_LIB.TIMECARD(SCH_1):PAGE6
     1 LM75B_I2C_SDA @TIMECARD_LIB.TIMECARD(SCH_1):LM75B_I2C_SDA    I15 @TIMECARD_LIB.TIMECARD(SCH_1):PAGE6

R333 RESISTOR-G155-14701-01,4.7KOHMA
     2 UNNAMED_6_LM75BDPTSSOP8_I34_A2 @TIMECARD_LIB.TIMECARD(SCH_1):UNNAMED_6_LM75BDPTSSOP8_I34_A2    I31 @TIMECARD_LIB.TIMECARD(SCH_1):PAGE6
     1 XP3R3V_FPGA @TIMECARD_LIB.TIMECARD(SCH_1):XP3R3V_FPGA    I31 @TIMECARD_LIB.TIMECARD(SCH_1):PAGE6

R334 RESISTOR-G155-11001-01,1KOHM,1%
     2     SG @TIMECARD_LIB.TIMECARD(SCH_1):SG    I30 @TIMECARD_LIB.TIMECARD(SCH_1):PAGE6
     1 UNNAMED_6_LM75BDPTSSOP8_I34_A2 @TIMECARD_LIB.TIMECARD(SCH_1):UNNAMED_6_LM75BDPTSSOP8_I34_A2    I30 @TIMECARD_LIB.TIMECARD(SCH_1):PAGE6

R335 RESISTOR-G155-14701-01,4.7KOHMA
     2 UNNAMED_6_LM75BDPTSSOP8_I34_A1 @TIMECARD_LIB.TIMECARD(SCH_1):UNNAMED_6_LM75BDPTSSOP8_I34_A1    I35 @TIMECARD_LIB.TIMECARD(SCH_1):PAGE6
     1 XP3R3V_FPGA @TIMECARD_LIB.TIMECARD(SCH_1):XP3R3V_FPGA    I35 @TIMECARD_LIB.TIMECARD(SCH_1):PAGE6

R336 RESISTOR-G155-11001-01,1KOHM,1%
     2     SG @TIMECARD_LIB.TIMECARD(SCH_1):SG    I32 @TIMECARD_LIB.TIMECARD(SCH_1):PAGE6
     1 UNNAMED_6_LM75BDPTSSOP8_I34_A1 @TIMECARD_LIB.TIMECARD(SCH_1):UNNAMED_6_LM75BDPTSSOP8_I34_A1    I32 @TIMECARD_LIB.TIMECARD(SCH_1):PAGE6

R337 RESISTOR-G155-14701-01,4.7KOHMA
     2 UNNAMED_6_LM75BDPTSSOP8_I34_A0 @TIMECARD_LIB.TIMECARD(SCH_1):UNNAMED_6_LM75BDPTSSOP8_I34_A0    I36 @TIMECARD_LIB.TIMECARD(SCH_1):PAGE6
     1 XP3R3V_FPGA @TIMECARD_LIB.TIMECARD(SCH_1):XP3R3V_FPGA    I36 @TIMECARD_LIB.TIMECARD(SCH_1):PAGE6

R338 RESISTOR-G155-11001-01,1KOHM,1%
     2     SG @TIMECARD_LIB.TIMECARD(SCH_1):SG    I33 @TIMECARD_LIB.TIMECARD(SCH_1):PAGE6
     1 UNNAMED_6_LM75BDPTSSOP8_I34_A0 @TIMECARD_LIB.TIMECARD(SCH_1):UNNAMED_6_LM75BDPTSSOP8_I34_A0    I33 @TIMECARD_LIB.TIMECARD(SCH_1):PAGE6

R339 RESISTOR-G155-133R0-01,33OHM,1%
     2 FPGA_FLASH_DQ2 @TIMECARD_LIB.TIMECARD(SCH_1):FPGA_FLASH_DQ2   I261 @TIMECARD_LIB.TIMECARD(SCH_1):PAGE161
     1 FPGA_D02 @TIMECARD_LIB.TIMECARD(SCH_1):FPGA_D02   I261 @TIMECARD_LIB.TIMECARD(SCH_1):PAGE161

R340 RESISTOR-G155-14701-01,4.7KOHMA
     2 FPGA_IN_LM75B_INT1_N @TIMECARD_LIB.TIMECARD(SCH_1):FPGA_IN_LM75B_INT1_N    I41 @TIMECARD_LIB.TIMECARD(SCH_1):PAGE6
     1 XP3R3V_FPGA @TIMECARD_LIB.TIMECARD(SCH_1):XP3R3V_FPGA    I41 @TIMECARD_LIB.TIMECARD(SCH_1):PAGE6

R341 RESISTOR-G155-14701-01,4.7KOHMA
     2 BNO080_EVN_SDA @TIMECARD_LIB.TIMECARD(SCH_1):BNO080_EVN_SDA    I65 @TIMECARD_LIB.TIMECARD(SCH_1):PAGE9
     1 XP3R3V_FPGA @TIMECARD_LIB.TIMECARD(SCH_1):XP3R3V_FPGA    I65 @TIMECARD_LIB.TIMECARD(SCH_1):PAGE9

R342 RESISTOR-G155-14701-01,4.7KOHMA
     2 BNO080_EVN_SCL @TIMECARD_LIB.TIMECARD(SCH_1):BNO080_EVN_SCL    I66 @TIMECARD_LIB.TIMECARD(SCH_1):PAGE9
     1 XP3R3V_FPGA @TIMECARD_LIB.TIMECARD(SCH_1):XP3R3V_FPGA    I66 @TIMECARD_LIB.TIMECARD(SCH_1):PAGE9

R343 RESISTOR-G155-100R0-J0,0OHM,-
     2     SG @TIMECARD_LIB.TIMECARD(SCH_1):SG    I34 @TIMECARD_LIB.TIMECARD(SCH_1):PAGE8
     1 UNNAMED_8_ICP10100LGA10_I24_RES @TIMECARD_LIB.TIMECARD(SCH_1):UNNAMED_8_ICP10100LGA10_I24_RESV1    I34 @TIMECARD_LIB.TIMECARD(SCH_1):PAGE8

R344 RESISTOR-G155-14701-01,4.7KOHMA
     2     SG @TIMECARD_LIB.TIMECARD(SCH_1):SG    I97 @TIMECARD_LIB.TIMECARD(SCH_1):PAGE5
     1 SN_EEPROM_WP @TIMECARD_LIB.TIMECARD(SCH_1):SN_EEPROM_WP    I97 @TIMECARD_LIB.TIMECARD(SCH_1):PAGE5

R345 RESISTOR-G155-133R0-01,33OHM,1%
     2 PRI_EEPROM_SDA @TIMECARD_LIB.TIMECARD(SCH_1):PRI_EEPROM_SDA    I90 @TIMECARD_LIB.TIMECARD(SCH_1):PAGE5
     1 EEPROM_SDA @TIMECARD_LIB.TIMECARD(SCH_1):EEPROM_SDA    I90 @TIMECARD_LIB.TIMECARD(SCH_1):PAGE5

R346 RESISTOR-G155-100R0-J0,0OHM,-
     2     SG @TIMECARD_LIB.TIMECARD(SCH_1):SG    I33 @TIMECARD_LIB.TIMECARD(SCH_1):PAGE8
     1 UNNAMED_8_ICP10100LGA10_I24_R_1 @TIMECARD_LIB.TIMECARD(SCH_1):UNNAMED_8_ICP10100LGA10_I24_RESV2    I33 @TIMECARD_LIB.TIMECARD(SCH_1):PAGE8

R347 RESISTOR-G155-100R0-J0,0OHM,-
     2 XP1R8V_ICP10100 @TIMECARD_LIB.TIMECARD(SCH_1):XP1R8V_ICP10100    I32 @TIMECARD_LIB.TIMECARD(SCH_1):PAGE8
     1 UNNAMED_8_ICP10100LGA10_I24_R_2 @TIMECARD_LIB.TIMECARD(SCH_1):UNNAMED_8_ICP10100LGA10_I24_RESV3    I32 @TIMECARD_LIB.TIMECARD(SCH_1):PAGE8

R348 RESISTOR-G155-133R0-01,33OHM,1%
     2 FPGA_FLASH_DQ3 @TIMECARD_LIB.TIMECARD(SCH_1):FPGA_FLASH_DQ3   I260 @TIMECARD_LIB.TIMECARD(SCH_1):PAGE161
     1 FPGA_D03 @TIMECARD_LIB.TIMECARD(SCH_1):FPGA_D03   I260 @TIMECARD_LIB.TIMECARD(SCH_1):PAGE161

R349 RESISTOR-G155-11003-01,100KOHMA
     2 XP3R3V_FT4232 @TIMECARD_LIB.TIMECARD(SCH_1):XP3R3V_FT4232   I184 @TIMECARD_LIB.TIMECARD(SCH_1):PAGE524
     1 R_FT4232_CHD_RX @TIMECARD_LIB.TIMECARD(SCH_1):R_FT4232_CHD_RX   I184 @TIMECARD_LIB.TIMECARD(SCH_1):PAGE524

R350 RESISTOR-G155-100R0-J0,0OHM,-
     2 XP1R8V_ICP10100 @TIMECARD_LIB.TIMECARD(SCH_1):XP1R8V_ICP10100    I31 @TIMECARD_LIB.TIMECARD(SCH_1):PAGE8
     1 UNNAMED_8_ICP10100LGA10_I24_R_3 @TIMECARD_LIB.TIMECARD(SCH_1):UNNAMED_8_ICP10100LGA10_I24_RESV4    I31 @TIMECARD_LIB.TIMECARD(SCH_1):PAGE8

R351 RESISTOR-G155-100R0-J0,0OHM,-
     2     SG @TIMECARD_LIB.TIMECARD(SCH_1):SG    I30 @TIMECARD_LIB.TIMECARD(SCH_1):PAGE8
     1 UNNAMED_8_ICP10100LGA10_I24_R_4 @TIMECARD_LIB.TIMECARD(SCH_1):UNNAMED_8_ICP10100LGA10_I24_RESV5    I30 @TIMECARD_LIB.TIMECARD(SCH_1):PAGE8

R352 RESISTOR-G155-11000-01,100OHM,A
     2 UART_FT4232_RX_FPGA_TX @TIMECARD_LIB.TIMECARD(SCH_1):UART_FT4232_RX_FPGA_TX   I154 @TIMECARD_LIB.TIMECARD(SCH_1):PAGE524
     1 R_FT4232_CHC_RX @TIMECARD_LIB.TIMECARD(SCH_1):R_FT4232_CHC_RX   I154 @TIMECARD_LIB.TIMECARD(SCH_1):PAGE524

R353 RESISTOR-G155-11000-01,100OHM,A
     2 UART_FT4232_TX_FPGA_RX @TIMECARD_LIB.TIMECARD(SCH_1):UART_FT4232_TX_FPGA_RX   I153 @TIMECARD_LIB.TIMECARD(SCH_1):PAGE524
     1 R_FT4232_CHC_TX @TIMECARD_LIB.TIMECARD(SCH_1):R_FT4232_CHC_TX   I153 @TIMECARD_LIB.TIMECARD(SCH_1):PAGE524

R354 RESISTOR-G155-133R0-01,33OHM,1%
     2 UNNAMED_3_G2201019801_I100_EN @TIMECARD_LIB.TIMECARD(SCH_1):UNNAMED_3_G2201019801_I100_EN   I114 @TIMECARD_LIB.TIMECARD(SCH_1):PAGE3
     1 FPGA_OUT_I2C_BUFFER_EN @TIMECARD_LIB.TIMECARD(SCH_1):FPGA_OUT_I2C_BUFFER_EN   I114 @TIMECARD_LIB.TIMECARD(SCH_1):PAGE3

R355 RESISTOR-G155-11002-01,10KOHM,A
     2 XP2R5V_FPGA @TIMECARD_LIB.TIMECARD(SCH_1):XP2R5V_FPGA   I120 @TIMECARD_LIB.TIMECARD(SCH_1):PAGE163
     1 MHZ200CLKN_CLKIN @TIMECARD_LIB.TIMECARD(SCH_1):MHZ200CLKN_CLKIN   I120 @TIMECARD_LIB.TIMECARD(SCH_1):PAGE163

R356 RESISTOR-G155-100R0-J0,0OHM,-
     2 FPGA_PROGRAM_N @TIMECARD_LIB.TIMECARD(SCH_1):FPGA_PROGRAM_N   I122 @TIMECARD_LIB.TIMECARD(SCH_1):PAGE3
     1 BF_PCIE_PERST_N @TIMECARD_LIB.TIMECARD(SCH_1):BF_PCIE_PERST_N   I122 @TIMECARD_LIB.TIMECARD(SCH_1):PAGE3

R357 RESISTOR-G157-100R0-J0,0OHM,-
     2 UNNAMED_527_FUSE_I244_1 @TIMECARD_LIB.TIMECARD(SCH_1):UNNAMED_527_FUSE_I244_1   I245 @TIMECARD_LIB.TIMECARD(SCH_1):PAGE527
     1 XP5R0V_MAC @TIMECARD_LIB.TIMECARD(SCH_1):XP5R0V_MAC   I245 @TIMECARD_LIB.TIMECARD(SCH_1):PAGE527

R358 RESISTOR-G155-11002-01,10KOHM,A
     2 XP2R5V_FPGA @TIMECARD_LIB.TIMECARD(SCH_1):XP2R5V_FPGA   I126 @TIMECARD_LIB.TIMECARD(SCH_1):PAGE163
     1 MHZ200CLKP_CLKIN @TIMECARD_LIB.TIMECARD(SCH_1):MHZ200CLKP_CLKIN   I126 @TIMECARD_LIB.TIMECARD(SCH_1):PAGE163

R359 RESISTOR-G155-11002-01,10KOHM,A
     2     SG @TIMECARD_LIB.TIMECARD(SCH_1):SG   I127 @TIMECARD_LIB.TIMECARD(SCH_1):PAGE163
     1 MHZ200CLKP_CLKIN @TIMECARD_LIB.TIMECARD(SCH_1):MHZ200CLKP_CLKIN   I127 @TIMECARD_LIB.TIMECARD(SCH_1):PAGE163

R360 RESISTOR-G155-11002-01,10KOHM,A
     2     SG @TIMECARD_LIB.TIMECARD(SCH_1):SG   I128 @TIMECARD_LIB.TIMECARD(SCH_1):PAGE163
     1 MHZ200CLKN_CLKIN @TIMECARD_LIB.TIMECARD(SCH_1):MHZ200CLKN_CLKIN   I128 @TIMECARD_LIB.TIMECARD(SCH_1):PAGE163

R361 RESISTOR-G155-14701-01,4.7KOHMA
     2 SMA1_SIG_OUT_BF_EN_N @TIMECARD_LIB.TIMECARD(SCH_1):SMA1_SIG_OUT_BF_EN_N   I261 @TIMECARD_LIB.TIMECARD(SCH_1):PAGE12
     1 XP3R3V_FPGA @TIMECARD_LIB.TIMECARD(SCH_1):XP3R3V_FPGA   I261 @TIMECARD_LIB.TIMECARD(SCH_1):PAGE12

R362 RESISTOR-G155-133R0-01,33OHM,1%
     2 FPGA_FLASH_CS_N @TIMECARD_LIB.TIMECARD(SCH_1):FPGA_FLASH_CS_N   I263 @TIMECARD_LIB.TIMECARD(SCH_1):PAGE161
     1 FPGA_FCS_B @TIMECARD_LIB.TIMECARD(SCH_1):FPGA_FCS_B   I263 @TIMECARD_LIB.TIMECARD(SCH_1):PAGE161

R363 RESISTOR-G155-133R0-01,33OHM,1%
     2 BNO080_EVN_SCL @TIMECARD_LIB.TIMECARD(SCH_1):BNO080_EVN_SCL    I67 @TIMECARD_LIB.TIMECARD(SCH_1):PAGE9
     1 R_BNO080_EVN_SCL @TIMECARD_LIB.TIMECARD(SCH_1):R_BNO080_EVN_SCL    I67 @TIMECARD_LIB.TIMECARD(SCH_1):PAGE9

R364 RESISTOR-G155-133R0-01,33OHM,1%
     2 R_RGB_LED_I2C_SDA @TIMECARD_LIB.TIMECARD(SCH_1):R_RGB_LED_I2C_SDA   I298 @TIMECARD_LIB.TIMECARD(SCH_1):PAGE14
     1 RGB_LED_I2C_SDA @TIMECARD_LIB.TIMECARD(SCH_1):RGB_LED_I2C_SDA   I298 @TIMECARD_LIB.TIMECARD(SCH_1):PAGE14

R365 RESISTOR-G155-14701-01,4.7KOHMA
     2 SMA3_SIG_OUT_BF_EN_N @TIMECARD_LIB.TIMECARD(SCH_1):SMA3_SIG_OUT_BF_EN_N    I88 @TIMECARD_LIB.TIMECARD(SCH_1):PAGE12
     1 XP3R3V_FPGA @TIMECARD_LIB.TIMECARD(SCH_1):XP3R3V_FPGA    I88 @TIMECARD_LIB.TIMECARD(SCH_1):PAGE12

R366 RESISTOR-G155-133R0-01,33OHM,1%
     2 R_RGB_LED_I2C_SCL @TIMECARD_LIB.TIMECARD(SCH_1):R_RGB_LED_I2C_SCL   I299 @TIMECARD_LIB.TIMECARD(SCH_1):PAGE14
     1 RGB_LED_I2C_SCL @TIMECARD_LIB.TIMECARD(SCH_1):RGB_LED_I2C_SCL   I299 @TIMECARD_LIB.TIMECARD(SCH_1):PAGE14

R367 RESISTOR-G155-149R9-01,49.9OHMA
     2 ANT3_IN @TIMECARD_LIB.TIMECARD(SCH_1):ANT3_IN   I209 @TIMECARD_LIB.TIMECARD(SCH_1):PAGE12
     1 BF_ANT3_IN @TIMECARD_LIB.TIMECARD(SCH_1):BF_ANT3_IN   I209 @TIMECARD_LIB.TIMECARD(SCH_1):PAGE12

R368 RESISTOR-G155-14701-01,4.7KOHMA
     2 SMA4_SIG_OUT_BF_EN_N @TIMECARD_LIB.TIMECARD(SCH_1):SMA4_SIG_OUT_BF_EN_N   I233 @TIMECARD_LIB.TIMECARD(SCH_1):PAGE12
     1 XP3R3V_FPGA @TIMECARD_LIB.TIMECARD(SCH_1):XP3R3V_FPGA   I233 @TIMECARD_LIB.TIMECARD(SCH_1):PAGE12

R370 RESISTOR-G155-149R9-01,49.9OHMA
     2 ANT4_IN @TIMECARD_LIB.TIMECARD(SCH_1):ANT4_IN   I229 @TIMECARD_LIB.TIMECARD(SCH_1):PAGE12
     1 BF_ANT4_IN @TIMECARD_LIB.TIMECARD(SCH_1):BF_ANT4_IN   I229 @TIMECARD_LIB.TIMECARD(SCH_1):PAGE12

R371 RESISTOR-G155-149R9-01,49.9OHMA
     2 ANT1_IN @TIMECARD_LIB.TIMECARD(SCH_1):ANT1_IN   I258 @TIMECARD_LIB.TIMECARD(SCH_1):PAGE12
     1 BF_ANT1_IN @TIMECARD_LIB.TIMECARD(SCH_1):BF_ANT1_IN   I258 @TIMECARD_LIB.TIMECARD(SCH_1):PAGE12

R372 RESISTOR-G155-149R9-01,49.9OHMA
     2 ANT2_IN @TIMECARD_LIB.TIMECARD(SCH_1):ANT2_IN   I275 @TIMECARD_LIB.TIMECARD(SCH_1):PAGE12
     1 BF_ANT2_IN @TIMECARD_LIB.TIMECARD(SCH_1):BF_ANT2_IN   I275 @TIMECARD_LIB.TIMECARD(SCH_1):PAGE12

R373 RESISTOR-G155-11000-01,100OHM,A
     2 UNNAMED_14_LED4PV14_I266_3 @TIMECARD_LIB.TIMECARD(SCH_1):UNNAMED_14_LED4PV14_I266_3   I181 @TIMECARD_LIB.TIMECARD(SCH_1):PAGE14
     1 FPGA_OUT_SMA2_LED_RED_N @TIMECARD_LIB.TIMECARD(SCH_1):FPGA_OUT_SMA2_LED_RED_N   I181 @TIMECARD_LIB.TIMECARD(SCH_1):PAGE14

R374 RESISTOR-G155-11000-01,100OHM,A
     2 UNNAMED_14_LED4PV14_I267_1 @TIMECARD_LIB.TIMECARD(SCH_1):UNNAMED_14_LED4PV14_I267_1   I168 @TIMECARD_LIB.TIMECARD(SCH_1):PAGE14
     1 FPGA_OUT_SMA3_LED_BLUE_N @TIMECARD_LIB.TIMECARD(SCH_1):FPGA_OUT_SMA3_LED_BLUE_N   I168 @TIMECARD_LIB.TIMECARD(SCH_1):PAGE14

R375 RESISTOR-G155-11000-01,100OHM,A
     2 UNNAMED_14_LED4PV14_I267_4 @TIMECARD_LIB.TIMECARD(SCH_1):UNNAMED_14_LED4PV14_I267_4   I174 @TIMECARD_LIB.TIMECARD(SCH_1):PAGE14
     1 FPGA_OUT_SMA3_LED_GREEN_N @TIMECARD_LIB.TIMECARD(SCH_1):FPGA_OUT_SMA3_LED_GREEN_N   I174 @TIMECARD_LIB.TIMECARD(SCH_1):PAGE14

R376 RESISTOR-G155-11000-01,100OHM,A
     2 UNNAMED_14_LED4PV14_I267_3 @TIMECARD_LIB.TIMECARD(SCH_1):UNNAMED_14_LED4PV14_I267_3   I184 @TIMECARD_LIB.TIMECARD(SCH_1):PAGE14
     1 FPGA_OUT_SMA3_LED_RED_N @TIMECARD_LIB.TIMECARD(SCH_1):FPGA_OUT_SMA3_LED_RED_N   I184 @TIMECARD_LIB.TIMECARD(SCH_1):PAGE14

R377 RESISTOR-G155-14701-01,4.7KOHMA
     2 SMA3_SIG_IN_BF_EN_N @TIMECARD_LIB.TIMECARD(SCH_1):SMA3_SIG_IN_BF_EN_N   I206 @TIMECARD_LIB.TIMECARD(SCH_1):PAGE12
     1 XP3R3V_FPGA @TIMECARD_LIB.TIMECARD(SCH_1):XP3R3V_FPGA   I206 @TIMECARD_LIB.TIMECARD(SCH_1):PAGE12

R379 RESISTOR-G155-14701-01,4.7KOHMA
     2 SMA4_SIG_IN_BF_EN_N @TIMECARD_LIB.TIMECARD(SCH_1):SMA4_SIG_IN_BF_EN_N   I234 @TIMECARD_LIB.TIMECARD(SCH_1):PAGE12
     1 XP3R3V_FPGA @TIMECARD_LIB.TIMECARD(SCH_1):XP3R3V_FPGA   I234 @TIMECARD_LIB.TIMECARD(SCH_1):PAGE12

R381 RESISTOR-G155-14701-01,4.7KOHMA
     2 SMA1_SIG_IN_BF_EN_N @TIMECARD_LIB.TIMECARD(SCH_1):SMA1_SIG_IN_BF_EN_N   I262 @TIMECARD_LIB.TIMECARD(SCH_1):PAGE12
     1 XP3R3V_FPGA @TIMECARD_LIB.TIMECARD(SCH_1):XP3R3V_FPGA   I262 @TIMECARD_LIB.TIMECARD(SCH_1):PAGE12

R383 RESISTOR-G155-14701-01,4.7KOHMA
     2 SMA2_SIG_IN_BF_EN_N @TIMECARD_LIB.TIMECARD(SCH_1):SMA2_SIG_IN_BF_EN_N   I281 @TIMECARD_LIB.TIMECARD(SCH_1):PAGE12
     1 XP3R3V_FPGA @TIMECARD_LIB.TIMECARD(SCH_1):XP3R3V_FPGA   I281 @TIMECARD_LIB.TIMECARD(SCH_1):PAGE12

R385 RESISTOR-G155-133R0-01,33OHM,1%
     2 UNNAMED_14_LED4PV14_I265_1 @TIMECARD_LIB.TIMECARD(SCH_1):UNNAMED_14_LED4PV14_I265_1   I107 @TIMECARD_LIB.TIMECARD(SCH_1):PAGE14
     1 SMA1_LED_BLUE_N @TIMECARD_LIB.TIMECARD(SCH_1):SMA1_LED_BLUE_N   I107 @TIMECARD_LIB.TIMECARD(SCH_1):PAGE14

R386 RESISTOR-G155-133R0-01,33OHM,1%
     2 UNNAMED_14_LED4PV14_I265_4 @TIMECARD_LIB.TIMECARD(SCH_1):UNNAMED_14_LED4PV14_I265_4   I108 @TIMECARD_LIB.TIMECARD(SCH_1):PAGE14
     1 SMA1_LED_GREEN_N @TIMECARD_LIB.TIMECARD(SCH_1):SMA1_LED_GREEN_N   I108 @TIMECARD_LIB.TIMECARD(SCH_1):PAGE14

R387 RESISTOR-G155-133R0-01,33OHM,1%
     2 UNNAMED_14_LED4PV14_I265_3 @TIMECARD_LIB.TIMECARD(SCH_1):UNNAMED_14_LED4PV14_I265_3   I110 @TIMECARD_LIB.TIMECARD(SCH_1):PAGE14
     1 SMA1_LED_RED_N @TIMECARD_LIB.TIMECARD(SCH_1):SMA1_LED_RED_N   I110 @TIMECARD_LIB.TIMECARD(SCH_1):PAGE14

R388 RESISTOR-G155-133R0-01,33OHM,1%
     2 UNNAMED_14_LED4PV14_I266_1 @TIMECARD_LIB.TIMECARD(SCH_1):UNNAMED_14_LED4PV14_I266_1   I147 @TIMECARD_LIB.TIMECARD(SCH_1):PAGE14
     1 SMA2_LED_BLUE_N @TIMECARD_LIB.TIMECARD(SCH_1):SMA2_LED_BLUE_N   I147 @TIMECARD_LIB.TIMECARD(SCH_1):PAGE14

R389 RESISTOR-G155-133R0-01,33OHM,1%
     2 UNNAMED_14_LED4PV14_I266_4 @TIMECARD_LIB.TIMECARD(SCH_1):UNNAMED_14_LED4PV14_I266_4   I148 @TIMECARD_LIB.TIMECARD(SCH_1):PAGE14
     1 SMA2_LED_GREEN_N @TIMECARD_LIB.TIMECARD(SCH_1):SMA2_LED_GREEN_N   I148 @TIMECARD_LIB.TIMECARD(SCH_1):PAGE14

R390 RESISTOR-G155-133R0-01,33OHM,1%
     2 UNNAMED_14_LED4PV14_I266_3 @TIMECARD_LIB.TIMECARD(SCH_1):UNNAMED_14_LED4PV14_I266_3   I146 @TIMECARD_LIB.TIMECARD(SCH_1):PAGE14
     1 SMA2_LED_RED_N @TIMECARD_LIB.TIMECARD(SCH_1):SMA2_LED_RED_N   I146 @TIMECARD_LIB.TIMECARD(SCH_1):PAGE14

R391 RESISTOR-G155-133R0-01,33OHM,1%
     2 UNNAMED_14_LED4PV14_I267_1 @TIMECARD_LIB.TIMECARD(SCH_1):UNNAMED_14_LED4PV14_I267_1   I150 @TIMECARD_LIB.TIMECARD(SCH_1):PAGE14
     1 SMA3_LED_BLUE_N @TIMECARD_LIB.TIMECARD(SCH_1):SMA3_LED_BLUE_N   I150 @TIMECARD_LIB.TIMECARD(SCH_1):PAGE14

R392 RESISTOR-G155-133R0-01,33OHM,1%
     2 UNNAMED_14_LED4PV14_I267_4 @TIMECARD_LIB.TIMECARD(SCH_1):UNNAMED_14_LED4PV14_I267_4   I149 @TIMECARD_LIB.TIMECARD(SCH_1):PAGE14
     1 SMA3_LED_GREEN_N @TIMECARD_LIB.TIMECARD(SCH_1):SMA3_LED_GREEN_N   I149 @TIMECARD_LIB.TIMECARD(SCH_1):PAGE14

R393 RESISTOR-G155-133R0-01,33OHM,1%
     2 UNNAMED_14_LED4PV14_I267_3 @TIMECARD_LIB.TIMECARD(SCH_1):UNNAMED_14_LED4PV14_I267_3   I151 @TIMECARD_LIB.TIMECARD(SCH_1):PAGE14
     1 SMA3_LED_RED_N @TIMECARD_LIB.TIMECARD(SCH_1):SMA3_LED_RED_N   I151 @TIMECARD_LIB.TIMECARD(SCH_1):PAGE14

R394 RESISTOR-G155-133R0-01,33OHM,1%
     2 UNNAMED_14_LED4PV14_I268_1 @TIMECARD_LIB.TIMECARD(SCH_1):UNNAMED_14_LED4PV14_I268_1   I153 @TIMECARD_LIB.TIMECARD(SCH_1):PAGE14
     1 SMA4_LED_BLUE_N @TIMECARD_LIB.TIMECARD(SCH_1):SMA4_LED_BLUE_N   I153 @TIMECARD_LIB.TIMECARD(SCH_1):PAGE14

R395 RESISTOR-G155-133R0-01,33OHM,1%
     2 UNNAMED_14_LED4PV14_I268_4 @TIMECARD_LIB.TIMECARD(SCH_1):UNNAMED_14_LED4PV14_I268_4   I152 @TIMECARD_LIB.TIMECARD(SCH_1):PAGE14
     1 SMA4_LED_GREEN_N @TIMECARD_LIB.TIMECARD(SCH_1):SMA4_LED_GREEN_N   I152 @TIMECARD_LIB.TIMECARD(SCH_1):PAGE14

R396 RESISTOR-G155-133R0-01,33OHM,1%
     2 UNNAMED_14_LED4PV14_I268_3 @TIMECARD_LIB.TIMECARD(SCH_1):UNNAMED_14_LED4PV14_I268_3   I154 @TIMECARD_LIB.TIMECARD(SCH_1):PAGE14
     1 SMA4_LED_RED_N @TIMECARD_LIB.TIMECARD(SCH_1):SMA4_LED_RED_N   I154 @TIMECARD_LIB.TIMECARD(SCH_1):PAGE14

R397 RESISTOR-G155-133R0-01,33OHM,1%
     2 UNNAMED_14_LED4PV14_I269_1 @TIMECARD_LIB.TIMECARD(SCH_1):UNNAMED_14_LED4PV14_I269_1   I156 @TIMECARD_LIB.TIMECARD(SCH_1):PAGE14
     1 GPS_SMA_LED_BLUE_N @TIMECARD_LIB.TIMECARD(SCH_1):GPS_SMA_LED_BLUE_N   I156 @TIMECARD_LIB.TIMECARD(SCH_1):PAGE14

R398 RESISTOR-G155-133R0-01,33OHM,1%
     2 UNNAMED_14_LED4PV14_I269_4 @TIMECARD_LIB.TIMECARD(SCH_1):UNNAMED_14_LED4PV14_I269_4   I155 @TIMECARD_LIB.TIMECARD(SCH_1):PAGE14
     1 GPS_SMA_LED_GREEN_N @TIMECARD_LIB.TIMECARD(SCH_1):GPS_SMA_LED_GREEN_N   I155 @TIMECARD_LIB.TIMECARD(SCH_1):PAGE14

R399 RESISTOR-G155-133R0-01,33OHM,1%
     2 UNNAMED_14_LED4PV14_I269_3 @TIMECARD_LIB.TIMECARD(SCH_1):UNNAMED_14_LED4PV14_I269_3   I157 @TIMECARD_LIB.TIMECARD(SCH_1):PAGE14
     1 GPS_SMA_LED_RED_N @TIMECARD_LIB.TIMECARD(SCH_1):GPS_SMA_LED_RED_N   I157 @TIMECARD_LIB.TIMECARD(SCH_1):PAGE14

R400 RESISTOR-G155-11000-01,100OHM,A
     2 UNNAMED_14_LED4PV14_I268_1 @TIMECARD_LIB.TIMECARD(SCH_1):UNNAMED_14_LED4PV14_I268_1   I177 @TIMECARD_LIB.TIMECARD(SCH_1):PAGE14
     1 FPGA_OUT_SMA4_LED_BLUE_N @TIMECARD_LIB.TIMECARD(SCH_1):FPGA_OUT_SMA4_LED_BLUE_N   I177 @TIMECARD_LIB.TIMECARD(SCH_1):PAGE14

R401 RESISTOR-G155-11000-01,100OHM,A
     2 UNNAMED_14_LED4PV14_I268_4 @TIMECARD_LIB.TIMECARD(SCH_1):UNNAMED_14_LED4PV14_I268_4   I176 @TIMECARD_LIB.TIMECARD(SCH_1):PAGE14
     1 FPGA_OUT_SMA4_LED_GREEN_N @TIMECARD_LIB.TIMECARD(SCH_1):FPGA_OUT_SMA4_LED_GREEN_N   I176 @TIMECARD_LIB.TIMECARD(SCH_1):PAGE14

R402 RESISTOR-G155-12201-01,2.2KOHMA
     2     SG @TIMECARD_LIB.TIMECARD(SCH_1):SG   I440 @TIMECARD_LIB.TIMECARD(SCH_1):PAGE127
     1 FPGA_TCK @TIMECARD_LIB.TIMECARD(SCH_1):FPGA_TCK   I440 @TIMECARD_LIB.TIMECARD(SCH_1):PAGE127

R403 RESISTOR-G155-11002-01,10KOHM,A
     2 FPGA_TDO @TIMECARD_LIB.TIMECARD(SCH_1):FPGA_TDO   I435 @TIMECARD_LIB.TIMECARD(SCH_1):PAGE127
     1 XP3R3V_FPGA @TIMECARD_LIB.TIMECARD(SCH_1):XP3R3V_FPGA   I435 @TIMECARD_LIB.TIMECARD(SCH_1):PAGE127

R404 RESISTOR-G155-11002-01,10KOHM,A
     2 FPGA_TMS @TIMECARD_LIB.TIMECARD(SCH_1):FPGA_TMS   I434 @TIMECARD_LIB.TIMECARD(SCH_1):PAGE127
     1 XP3R3V_FPGA @TIMECARD_LIB.TIMECARD(SCH_1):XP3R3V_FPGA   I434 @TIMECARD_LIB.TIMECARD(SCH_1):PAGE127

R405 RESISTOR-G155-11002-01,10KOHM,A
     2 FPGA_TDI @TIMECARD_LIB.TIMECARD(SCH_1):FPGA_TDI   I432 @TIMECARD_LIB.TIMECARD(SCH_1):PAGE127
     1 XP3R3V_FPGA @TIMECARD_LIB.TIMECARD(SCH_1):XP3R3V_FPGA   I432 @TIMECARD_LIB.TIMECARD(SCH_1):PAGE127

R406 RESISTOR-G155-133R0-01,33OHM,1%
     2 R_LM75B_2_I2C_SDA @TIMECARD_LIB.TIMECARD(SCH_1):R_LM75B_2_I2C_SDA    I76 @TIMECARD_LIB.TIMECARD(SCH_1):PAGE6
     1 LM75B_I2C_SDA @TIMECARD_LIB.TIMECARD(SCH_1):LM75B_I2C_SDA    I76 @TIMECARD_LIB.TIMECARD(SCH_1):PAGE6

R407 RESISTOR-G155-133R0-01,33OHM,1%
     2 R_LM75B_3_I2C_SDA @TIMECARD_LIB.TIMECARD(SCH_1):R_LM75B_3_I2C_SDA   I100 @TIMECARD_LIB.TIMECARD(SCH_1):PAGE6
     1 LM75B_I2C_SDA @TIMECARD_LIB.TIMECARD(SCH_1):LM75B_I2C_SDA   I100 @TIMECARD_LIB.TIMECARD(SCH_1):PAGE6

R408 RESISTOR-G155-14701-01,4.7KOHMA
     2 UNNAMED_6_LM75BDPTSSOP8_I59_A2 @TIMECARD_LIB.TIMECARD(SCH_1):UNNAMED_6_LM75BDPTSSOP8_I59_A2    I71 @TIMECARD_LIB.TIMECARD(SCH_1):PAGE6
     1 XP3R3V_FPGA @TIMECARD_LIB.TIMECARD(SCH_1):XP3R3V_FPGA    I71 @TIMECARD_LIB.TIMECARD(SCH_1):PAGE6

R409 RESISTOR-G155-11001-01,1KOHM,1%
     2     SG @TIMECARD_LIB.TIMECARD(SCH_1):SG    I73 @TIMECARD_LIB.TIMECARD(SCH_1):PAGE6
     1 UNNAMED_6_LM75BDPTSSOP8_I59_A2 @TIMECARD_LIB.TIMECARD(SCH_1):UNNAMED_6_LM75BDPTSSOP8_I59_A2    I73 @TIMECARD_LIB.TIMECARD(SCH_1):PAGE6

R410 RESISTOR-G155-14701-01,4.7KOHMA
     2 UNNAMED_6_LM75BDPTSSOP8_I81_A2 @TIMECARD_LIB.TIMECARD(SCH_1):UNNAMED_6_LM75BDPTSSOP8_I81_A2    I86 @TIMECARD_LIB.TIMECARD(SCH_1):PAGE6
     1 XP3R3V_FPGA @TIMECARD_LIB.TIMECARD(SCH_1):XP3R3V_FPGA    I86 @TIMECARD_LIB.TIMECARD(SCH_1):PAGE6

R411 RESISTOR-G155-11001-01,1KOHM,1%
     2     SG @TIMECARD_LIB.TIMECARD(SCH_1):SG    I95 @TIMECARD_LIB.TIMECARD(SCH_1):PAGE6
     1 UNNAMED_6_LM75BDPTSSOP8_I81_A2 @TIMECARD_LIB.TIMECARD(SCH_1):UNNAMED_6_LM75BDPTSSOP8_I81_A2    I95 @TIMECARD_LIB.TIMECARD(SCH_1):PAGE6

R412 RESISTOR-G155-14701-01,4.7KOHMA
     2 UNNAMED_6_LM75BDPTSSOP8_I59_A1 @TIMECARD_LIB.TIMECARD(SCH_1):UNNAMED_6_LM75BDPTSSOP8_I59_A1    I70 @TIMECARD_LIB.TIMECARD(SCH_1):PAGE6
     1 XP3R3V_FPGA @TIMECARD_LIB.TIMECARD(SCH_1):XP3R3V_FPGA    I70 @TIMECARD_LIB.TIMECARD(SCH_1):PAGE6

R413 RESISTOR-G155-11001-01,1KOHM,1%
     2     SG @TIMECARD_LIB.TIMECARD(SCH_1):SG    I60 @TIMECARD_LIB.TIMECARD(SCH_1):PAGE6
     1 UNNAMED_6_LM75BDPTSSOP8_I59_A1 @TIMECARD_LIB.TIMECARD(SCH_1):UNNAMED_6_LM75BDPTSSOP8_I59_A1    I60 @TIMECARD_LIB.TIMECARD(SCH_1):PAGE6

R414 RESISTOR-G155-14701-01,4.7KOHMA
     2 UNNAMED_6_LM75BDPTSSOP8_I81_A1 @TIMECARD_LIB.TIMECARD(SCH_1):UNNAMED_6_LM75BDPTSSOP8_I81_A1    I85 @TIMECARD_LIB.TIMECARD(SCH_1):PAGE6
     1 XP3R3V_FPGA @TIMECARD_LIB.TIMECARD(SCH_1):XP3R3V_FPGA    I85 @TIMECARD_LIB.TIMECARD(SCH_1):PAGE6

R415 RESISTOR-G155-11001-01,1KOHM,1%
     2     SG @TIMECARD_LIB.TIMECARD(SCH_1):SG    I94 @TIMECARD_LIB.TIMECARD(SCH_1):PAGE6
     1 UNNAMED_6_LM75BDPTSSOP8_I81_A1 @TIMECARD_LIB.TIMECARD(SCH_1):UNNAMED_6_LM75BDPTSSOP8_I81_A1    I94 @TIMECARD_LIB.TIMECARD(SCH_1):PAGE6

R416 RESISTOR-G155-11001-01,1KOHM,1%
     2     SG @TIMECARD_LIB.TIMECARD(SCH_1):SG    I72 @TIMECARD_LIB.TIMECARD(SCH_1):PAGE6
     1 UNNAMED_6_LM75BDPTSSOP8_I59_A0 @TIMECARD_LIB.TIMECARD(SCH_1):UNNAMED_6_LM75BDPTSSOP8_I59_A0    I72 @TIMECARD_LIB.TIMECARD(SCH_1):PAGE6

R417 RESISTOR-G155-11001-01,1KOHM,1%
     2     SG @TIMECARD_LIB.TIMECARD(SCH_1):SG    I93 @TIMECARD_LIB.TIMECARD(SCH_1):PAGE6
     1 UNNAMED_6_LM75BDPTSSOP8_I81_A0 @TIMECARD_LIB.TIMECARD(SCH_1):UNNAMED_6_LM75BDPTSSOP8_I81_A0    I93 @TIMECARD_LIB.TIMECARD(SCH_1):PAGE6

R418 RESISTOR-G155-14701-01,4.7KOHMA
     2 UNNAMED_6_LM75BDPTSSOP8_I59_A0 @TIMECARD_LIB.TIMECARD(SCH_1):UNNAMED_6_LM75BDPTSSOP8_I59_A0    I69 @TIMECARD_LIB.TIMECARD(SCH_1):PAGE6
     1 XP3R3V_FPGA @TIMECARD_LIB.TIMECARD(SCH_1):XP3R3V_FPGA    I69 @TIMECARD_LIB.TIMECARD(SCH_1):PAGE6

R419 RESISTOR-G155-14701-01,4.7KOHMA
     2 UNNAMED_6_LM75BDPTSSOP8_I81_A0 @TIMECARD_LIB.TIMECARD(SCH_1):UNNAMED_6_LM75BDPTSSOP8_I81_A0    I84 @TIMECARD_LIB.TIMECARD(SCH_1):PAGE6
     1 XP3R3V_FPGA @TIMECARD_LIB.TIMECARD(SCH_1):XP3R3V_FPGA    I84 @TIMECARD_LIB.TIMECARD(SCH_1):PAGE6

R422 RESISTOR-G155-14701-01,4.7KOHMA
     2 FPGA_IN_LM75B_INT2_N @TIMECARD_LIB.TIMECARD(SCH_1):FPGA_IN_LM75B_INT2_N    I64 @TIMECARD_LIB.TIMECARD(SCH_1):PAGE6
     1 XP3R3V_FPGA @TIMECARD_LIB.TIMECARD(SCH_1):XP3R3V_FPGA    I64 @TIMECARD_LIB.TIMECARD(SCH_1):PAGE6

R423 RESISTOR-G155-14701-01,4.7KOHMA
     2 FPGA_IN_LM75B_INT3_N @TIMECARD_LIB.TIMECARD(SCH_1):FPGA_IN_LM75B_INT3_N    I88 @TIMECARD_LIB.TIMECARD(SCH_1):PAGE6
     1 XP3R3V_FPGA @TIMECARD_LIB.TIMECARD(SCH_1):XP3R3V_FPGA    I88 @TIMECARD_LIB.TIMECARD(SCH_1):PAGE6

R424 RESISTOR-G155-11000-01,100OHM,A
     2 UNNAMED_14_LED4PV14_I268_3 @TIMECARD_LIB.TIMECARD(SCH_1):UNNAMED_14_LED4PV14_I268_3   I186 @TIMECARD_LIB.TIMECARD(SCH_1):PAGE14
     1 FPGA_OUT_SMA4_LED_RED_N @TIMECARD_LIB.TIMECARD(SCH_1):FPGA_OUT_SMA4_LED_RED_N   I186 @TIMECARD_LIB.TIMECARD(SCH_1):PAGE14

R425 RESISTOR-G155-11000-01,100OHM,A
     2 UNNAMED_14_LED4PV14_I269_1 @TIMECARD_LIB.TIMECARD(SCH_1):UNNAMED_14_LED4PV14_I269_1   I170 @TIMECARD_LIB.TIMECARD(SCH_1):PAGE14
     1 FPGA_OUT_GPS_LED_BLUE_N @TIMECARD_LIB.TIMECARD(SCH_1):FPGA_OUT_GPS_LED_BLUE_N   I170 @TIMECARD_LIB.TIMECARD(SCH_1):PAGE14

R426 RESISTOR-G155-11000-01,100OHM,A
     2 UNNAMED_14_LED4PV14_I269_4 @TIMECARD_LIB.TIMECARD(SCH_1):UNNAMED_14_LED4PV14_I269_4   I179 @TIMECARD_LIB.TIMECARD(SCH_1):PAGE14
     1 FPGA_OUT_GPS_LED_GREEN_N @TIMECARD_LIB.TIMECARD(SCH_1):FPGA_OUT_GPS_LED_GREEN_N   I179 @TIMECARD_LIB.TIMECARD(SCH_1):PAGE14

R427 RESISTOR-G155-11000-01,100OHM,A
     2 UNNAMED_14_LED4PV14_I269_3 @TIMECARD_LIB.TIMECARD(SCH_1):UNNAMED_14_LED4PV14_I269_3   I188 @TIMECARD_LIB.TIMECARD(SCH_1):PAGE14
     1 FPGA_OUT_GPS_LED_RED_N @TIMECARD_LIB.TIMECARD(SCH_1):FPGA_OUT_GPS_LED_RED_N   I188 @TIMECARD_LIB.TIMECARD(SCH_1):PAGE14

R428 RESISTOR-G155-133R0-01,33OHM,1%
     2 UNNAMED_16_CONNHDR2X6FSSMT_I1_6 @TIMECARD_LIB.TIMECARD(SCH_1):UNNAMED_16_CONNHDR2X6FSSMT_I1614_5  I1708 @TIMECARD_LIB.TIMECARD(SCH_1):PAGE16
     1 FPGA_IO_6 @TIMECARD_LIB.TIMECARD(SCH_1):FPGA_IO_6  I1708 @TIMECARD_LIB.TIMECARD(SCH_1):PAGE16

R429 RESISTOR-G155-133R0-01,33OHM,1%
     2 UNNAMED_16_CONNHDR2X6FSSMT_I1_2 @TIMECARD_LIB.TIMECARD(SCH_1):UNNAMED_16_CONNHDR2X6FSSMT_I1614_3  I1709 @TIMECARD_LIB.TIMECARD(SCH_1):PAGE16
     1 FPGA_IO_5 @TIMECARD_LIB.TIMECARD(SCH_1):FPGA_IO_5  I1709 @TIMECARD_LIB.TIMECARD(SCH_1):PAGE16

R430 RESISTOR-G155-133R0-01,33OHM,1%
     2 UNNAMED_16_CONNHDR2X6FSSMT_I161 @TIMECARD_LIB.TIMECARD(SCH_1):UNNAMED_16_CONNHDR2X6FSSMT_I1614_1  I1706 @TIMECARD_LIB.TIMECARD(SCH_1):PAGE16
     1 FPGA_IO_4 @TIMECARD_LIB.TIMECARD(SCH_1):FPGA_IO_4  I1706 @TIMECARD_LIB.TIMECARD(SCH_1):PAGE16

R431 RESISTOR-G155-133R0-01,33OHM,1%
     2 FPGA_IO_3 @TIMECARD_LIB.TIMECARD(SCH_1):FPGA_IO_3  I1718 @TIMECARD_LIB.TIMECARD(SCH_1):PAGE16
     1 UNNAMED_16_CONNHDR2X6FSSMT_I1_5 @TIMECARD_LIB.TIMECARD(SCH_1):UNNAMED_16_CONNHDR2X6FSSMT_I1614_8  I1718 @TIMECARD_LIB.TIMECARD(SCH_1):PAGE16

R432 RESISTOR-G155-133R0-01,33OHM,1%
     2 FPGA_IO_2 @TIMECARD_LIB.TIMECARD(SCH_1):FPGA_IO_2  I1719 @TIMECARD_LIB.TIMECARD(SCH_1):PAGE16
     1 UNNAMED_16_CONNHDR2X6FSSMT_I1_7 @TIMECARD_LIB.TIMECARD(SCH_1):UNNAMED_16_CONNHDR2X6FSSMT_I1614_6  I1719 @TIMECARD_LIB.TIMECARD(SCH_1):PAGE16

R433 RESISTOR-G155-133R0-01,33OHM,1%
     2 FPGA_IO_1 @TIMECARD_LIB.TIMECARD(SCH_1):FPGA_IO_1  I1720 @TIMECARD_LIB.TIMECARD(SCH_1):PAGE16
     1 UNNAMED_16_CONNHDR2X6FSSMT_I1_3 @TIMECARD_LIB.TIMECARD(SCH_1):UNNAMED_16_CONNHDR2X6FSSMT_I1614_4  I1720 @TIMECARD_LIB.TIMECARD(SCH_1):PAGE16

R434 RESISTOR-G155-133R0-01,33OHM,1%
     2 FPGA_IO_0 @TIMECARD_LIB.TIMECARD(SCH_1):FPGA_IO_0  I1721 @TIMECARD_LIB.TIMECARD(SCH_1):PAGE16
     1 UNNAMED_16_CONNHDR2X6FSSMT_I1_1 @TIMECARD_LIB.TIMECARD(SCH_1):UNNAMED_16_CONNHDR2X6FSSMT_I1614_2  I1721 @TIMECARD_LIB.TIMECARD(SCH_1):PAGE16

R435 RESISTOR-G155-11003-01,100KOHMA
     2 XP3R3V_FPGA @TIMECARD_LIB.TIMECARD(SCH_1):XP3R3V_FPGA   I251 @TIMECARD_LIB.TIMECARD(SCH_1):PAGE161
     1 FPGA_FLASH_DQ1_MISO @TIMECARD_LIB.TIMECARD(SCH_1):FPGA_FLASH_DQ1_MISO   I251 @TIMECARD_LIB.TIMECARD(SCH_1):PAGE161

R436 RESISTOR-G155-11502-01,15KOHM,A
     2 MAC_USB_DP @TIMECARD_LIB.TIMECARD(SCH_1):MAC_USB_DP   I240 @TIMECARD_LIB.TIMECARD(SCH_1):PAGE161
     1     SG @TIMECARD_LIB.TIMECARD(SCH_1):SG   I240 @TIMECARD_LIB.TIMECARD(SCH_1):PAGE161

R437 RESISTOR-G155-11502-01,15KOHM,A
     2 MAC_USB_DM @TIMECARD_LIB.TIMECARD(SCH_1):MAC_USB_DM   I239 @TIMECARD_LIB.TIMECARD(SCH_1):PAGE161
     1     SG @TIMECARD_LIB.TIMECARD(SCH_1):SG   I239 @TIMECARD_LIB.TIMECARD(SCH_1):PAGE161

R438 RESISTOR-G155-11002-01,10KOHM,A
     2 XP2R5V_FPGA @TIMECARD_LIB.TIMECARD(SCH_1):XP2R5V_FPGA   I132 @TIMECARD_LIB.TIMECARD(SCH_1):PAGE163
     1 FPGA_IN_MAC_PPS_OUTN @TIMECARD_LIB.TIMECARD(SCH_1):FPGA_IN_MAC_PPS_OUTN   I132 @TIMECARD_LIB.TIMECARD(SCH_1):PAGE163

R439 RESISTOR-G155-11002-01,10KOHM,A
     2 XP2R5V_FPGA @TIMECARD_LIB.TIMECARD(SCH_1):XP2R5V_FPGA   I133 @TIMECARD_LIB.TIMECARD(SCH_1):PAGE163
     1 FPGA_IN_MAC_PPS_OUTP @TIMECARD_LIB.TIMECARD(SCH_1):FPGA_IN_MAC_PPS_OUTP   I133 @TIMECARD_LIB.TIMECARD(SCH_1):PAGE163

R440 RESISTOR-G155-11002-01,10KOHM,A
     2     SG @TIMECARD_LIB.TIMECARD(SCH_1):SG   I135 @TIMECARD_LIB.TIMECARD(SCH_1):PAGE163
     1 FPGA_IN_MAC_PPS_OUTP @TIMECARD_LIB.TIMECARD(SCH_1):FPGA_IN_MAC_PPS_OUTP   I135 @TIMECARD_LIB.TIMECARD(SCH_1):PAGE163

R441 RESISTOR-G155-11002-01,10KOHM,A
     2     SG @TIMECARD_LIB.TIMECARD(SCH_1):SG   I134 @TIMECARD_LIB.TIMECARD(SCH_1):PAGE163
     1 FPGA_IN_MAC_PPS_OUTN @TIMECARD_LIB.TIMECARD(SCH_1):FPGA_IN_MAC_PPS_OUTN   I134 @TIMECARD_LIB.TIMECARD(SCH_1):PAGE163

R442 RESISTOR-G155-05101-01,5.1KOHMA
     2     SG @TIMECARD_LIB.TIMECARD(SCH_1):SG   I497 @TIMECARD_LIB.TIMECARD(SCH_1):PAGE524
     1 UNNAMED_524_CONNUSB14PGH4FRATH_ @TIMECARD_LIB.TIMECARD(SCH_1):UNNAMED_524_CONNUSB14PGH4FRATH_I495_CC1   I497 @TIMECARD_LIB.TIMECARD(SCH_1):PAGE524

R443 RESISTOR-G155-11000-01,100OHM,A
     2 FPGA_IO_FT_USBDET_RST_N @TIMECARD_LIB.TIMECARD(SCH_1):FPGA_IO_FT_USBDET_RST_N   I446 @TIMECARD_LIB.TIMECARD(SCH_1):PAGE524
     1 FT_USB_DETECT @TIMECARD_LIB.TIMECARD(SCH_1):FT_USB_DETECT   I446 @TIMECARD_LIB.TIMECARD(SCH_1):PAGE524

R444 RESISTOR-G155-11002-01,10KOHM,A
     2 FTDI_EE_DO @TIMECARD_LIB.TIMECARD(SCH_1):FTDI_EE_DO   I208 @TIMECARD_LIB.TIMECARD(SCH_1):PAGE524
     1 XP3R3V_FT4232 @TIMECARD_LIB.TIMECARD(SCH_1):XP3R3V_FT4232   I208 @TIMECARD_LIB.TIMECARD(SCH_1):PAGE524

R445 RESISTOR-G155-05101-01,5.1KOHMA
     2     SG @TIMECARD_LIB.TIMECARD(SCH_1):SG   I395 @TIMECARD_LIB.TIMECARD(SCH_1):PAGE524
     1 UNNAMED_524_CONNUSB14PGH4FRAT_1 @TIMECARD_LIB.TIMECARD(SCH_1):UNNAMED_524_CONNUSB14PGH4FRATH_I495_CC2   I395 @TIMECARD_LIB.TIMECARD(SCH_1):PAGE524

R446 RESISTOR-G155-11002-01,10KOHM,A
     2 FTDI_EE_CS @TIMECARD_LIB.TIMECARD(SCH_1):FTDI_EE_CS   I207 @TIMECARD_LIB.TIMECARD(SCH_1):PAGE524
     1 XP3R3V_FT4232 @TIMECARD_LIB.TIMECARD(SCH_1):XP3R3V_FT4232   I207 @TIMECARD_LIB.TIMECARD(SCH_1):PAGE524

R447 RESISTOR-G155-11002-01,10KOHM,A
     2 FTDI_EE_CLK @TIMECARD_LIB.TIMECARD(SCH_1):FTDI_EE_CLK   I206 @TIMECARD_LIB.TIMECARD(SCH_1):PAGE524
     1 XP3R3V_FT4232 @TIMECARD_LIB.TIMECARD(SCH_1):XP3R3V_FT4232   I206 @TIMECARD_LIB.TIMECARD(SCH_1):PAGE524

R448 RESISTOR-G155-133R0-01,33OHM,1%
     2 FPGA_OUT_MUX1_SEL @TIMECARD_LIB.TIMECARD(SCH_1):FPGA_OUT_MUX1_SEL   I423 @TIMECARD_LIB.TIMECARD(SCH_1):PAGE524
     1 MUX1_SEL @TIMECARD_LIB.TIMECARD(SCH_1):MUX1_SEL   I423 @TIMECARD_LIB.TIMECARD(SCH_1):PAGE524

R449 RESISTOR-G155-133R0-01,33OHM,1%
     2 FT4232_MUX1_SEL @TIMECARD_LIB.TIMECARD(SCH_1):FT4232_MUX1_SEL   I424 @TIMECARD_LIB.TIMECARD(SCH_1):PAGE524
     1 MUX1_SEL @TIMECARD_LIB.TIMECARD(SCH_1):MUX1_SEL   I424 @TIMECARD_LIB.TIMECARD(SCH_1):PAGE524

R450 RESISTOR-G155-14701-01,4.7KOHMA
     2 XP3R3V_FPGA @TIMECARD_LIB.TIMECARD(SCH_1):XP3R3V_FPGA   I440 @TIMECARD_LIB.TIMECARD(SCH_1):PAGE524
     1 MUX1_SEL @TIMECARD_LIB.TIMECARD(SCH_1):MUX1_SEL   I440 @TIMECARD_LIB.TIMECARD(SCH_1):PAGE524

R451 RESISTOR-G155-11001-01,1KOHM,1%
     2     SG @TIMECARD_LIB.TIMECARD(SCH_1):SG   I441 @TIMECARD_LIB.TIMECARD(SCH_1):PAGE524
     1 MUX1_SEL @TIMECARD_LIB.TIMECARD(SCH_1):MUX1_SEL   I441 @TIMECARD_LIB.TIMECARD(SCH_1):PAGE524

R452 RESISTOR-G155-14701-01,4.7KOHMA
     2 XP3R3V_FPGA @TIMECARD_LIB.TIMECARD(SCH_1):XP3R3V_FPGA   I443 @TIMECARD_LIB.TIMECARD(SCH_1):PAGE524
     1 UNNAMED_524_POWERMOS3PNCHV1_I44 @TIMECARD_LIB.TIMECARD(SCH_1):UNNAMED_524_POWERMOS3PNCHV1_I445_D   I443 @TIMECARD_LIB.TIMECARD(SCH_1):PAGE524

R453 RESISTOR-G155-11001-01,1KOHM,1%
     2     SG @TIMECARD_LIB.TIMECARD(SCH_1):SG   I442 @TIMECARD_LIB.TIMECARD(SCH_1):PAGE524
     1 UNNAMED_524_POWERMOS3PNCHV1_I44 @TIMECARD_LIB.TIMECARD(SCH_1):UNNAMED_524_POWERMOS3PNCHV1_I445_D   I442 @TIMECARD_LIB.TIMECARD(SCH_1):PAGE524

R454 RESISTOR-G155-12201-01,2.2KOHMA
     2 FTDI_EE_DO @TIMECARD_LIB.TIMECARD(SCH_1):FTDI_EE_DO   I310 @TIMECARD_LIB.TIMECARD(SCH_1):PAGE524
     1 FTDI_EE_DAT @TIMECARD_LIB.TIMECARD(SCH_1):FTDI_EE_DAT   I310 @TIMECARD_LIB.TIMECARD(SCH_1):PAGE524

R455 RESISTOR-G155-11004-01,1MOHM,1%
     2 UNNAMED_524_CAPACITOR_I10_2 @TIMECARD_LIB.TIMECARD(SCH_1):UNNAMED_524_CAPACITOR_I10_2   I287 @TIMECARD_LIB.TIMECARD(SCH_1):PAGE524
     1 UNNAMED_524_CAPACITOR_I7_2 @TIMECARD_LIB.TIMECARD(SCH_1):UNNAMED_524_CAPACITOR_I7_2   I287 @TIMECARD_LIB.TIMECARD(SCH_1):PAGE524

R456 RESISTOR-G155-11000-01,100OHM,A
     2 FT_USB_DETECT @TIMECARD_LIB.TIMECARD(SCH_1):FT_USB_DETECT   I368 @TIMECARD_LIB.TIMECARD(SCH_1):PAGE524
     1 XP3R3V_FT_PG @TIMECARD_LIB.TIMECARD(SCH_1):XP3R3V_FT_PG   I368 @TIMECARD_LIB.TIMECARD(SCH_1):PAGE524

R457 RESISTOR-G155-14701-01,4.7KOHMA
     2 MUX2_SEL @TIMECARD_LIB.TIMECARD(SCH_1):MUX2_SEL   I431 @TIMECARD_LIB.TIMECARD(SCH_1):PAGE524
     1 XP3R3V_FPGA @TIMECARD_LIB.TIMECARD(SCH_1):XP3R3V_FPGA   I431 @TIMECARD_LIB.TIMECARD(SCH_1):PAGE524

R458 RESISTOR-G155-11001-01,1KOHM,1%
     2 MUX2_SEL @TIMECARD_LIB.TIMECARD(SCH_1):MUX2_SEL   I430 @TIMECARD_LIB.TIMECARD(SCH_1):PAGE524
     1     SG @TIMECARD_LIB.TIMECARD(SCH_1):SG   I430 @TIMECARD_LIB.TIMECARD(SCH_1):PAGE524

R459 RESISTOR-G155-11001-01,1KOHM,1%
     2 UNNAMED_524_RESISTOR_I432_2 @TIMECARD_LIB.TIMECARD(SCH_1):UNNAMED_524_RESISTOR_I432_2   I432 @TIMECARD_LIB.TIMECARD(SCH_1):PAGE524
     1     SG @TIMECARD_LIB.TIMECARD(SCH_1):SG   I432 @TIMECARD_LIB.TIMECARD(SCH_1):PAGE524

R460 RESISTOR-G155-11001-01,1KOHM,1%
     2 UNNAMED_524_FT4232HLREELQFP64_7 @TIMECARD_LIB.TIMECARD(SCH_1):UNNAMED_524_FT4232HLREELQFP64_I64_RESET   I121 @TIMECARD_LIB.TIMECARD(SCH_1):PAGE524
     1 FT_USB_DETECT @TIMECARD_LIB.TIMECARD(SCH_1):FT_USB_DETECT   I121 @TIMECARD_LIB.TIMECARD(SCH_1):PAGE524

R461 RESISTOR-G155-133R0-01,33OHM,1%
     2 MUX2_SEL @TIMECARD_LIB.TIMECARD(SCH_1):MUX2_SEL   I411 @TIMECARD_LIB.TIMECARD(SCH_1):PAGE524
     1 FPGA_OUT_MUX2_SEL @TIMECARD_LIB.TIMECARD(SCH_1):FPGA_OUT_MUX2_SEL   I411 @TIMECARD_LIB.TIMECARD(SCH_1):PAGE524

R462 RESISTOR-G155-133R0-01,33OHM,1%
     2 MUX2_SEL @TIMECARD_LIB.TIMECARD(SCH_1):MUX2_SEL   I412 @TIMECARD_LIB.TIMECARD(SCH_1):PAGE524
     1 FT4232_MUX2_SEL @TIMECARD_LIB.TIMECARD(SCH_1):FT4232_MUX2_SEL   I412 @TIMECARD_LIB.TIMECARD(SCH_1):PAGE524

R463 RESISTOR-G155-01202-01,12KOHM,A
     2     SG @TIMECARD_LIB.TIMECARD(SCH_1):SG   I106 @TIMECARD_LIB.TIMECARD(SCH_1):PAGE524
     1 UNNAMED_524_FT4232HLREELQFP64_6 @TIMECARD_LIB.TIMECARD(SCH_1):UNNAMED_524_FT4232HLREELQFP64_I64_REF   I106 @TIMECARD_LIB.TIMECARD(SCH_1):PAGE524

R464 RESISTOR-G155-100R0-J0,0OHM,-
     2 FLASH_DQ2 @TIMECARD_LIB.TIMECARD(SCH_1):FLASH_DQ2   I493 @TIMECARD_LIB.TIMECARD(SCH_1):PAGE524
     1 FPGA_FLASH_DQ2 @TIMECARD_LIB.TIMECARD(SCH_1):FPGA_FLASH_DQ2   I493 @TIMECARD_LIB.TIMECARD(SCH_1):PAGE524

R465 RESISTOR-G155-100R0-J0,0OHM,-
     2 FLASH_DQ3 @TIMECARD_LIB.TIMECARD(SCH_1):FLASH_DQ3   I494 @TIMECARD_LIB.TIMECARD(SCH_1):PAGE524
     1 FPGA_FLASH_DQ3 @TIMECARD_LIB.TIMECARD(SCH_1):FPGA_FLASH_DQ3   I494 @TIMECARD_LIB.TIMECARD(SCH_1):PAGE524

R466 RESISTOR-G155-11003-01,100KOHMA
     2 XP3R3V_FT4232 @TIMECARD_LIB.TIMECARD(SCH_1):XP3R3V_FT4232   I198 @TIMECARD_LIB.TIMECARD(SCH_1):PAGE524
     1 R_FT4232_TDO @TIMECARD_LIB.TIMECARD(SCH_1):R_FT4232_TDO   I198 @TIMECARD_LIB.TIMECARD(SCH_1):PAGE524

R467 RESISTOR-G155-133R0-01,33OHM,1%
     2 FT4232_TCK_SCLK @TIMECARD_LIB.TIMECARD(SCH_1):FT4232_TCK_SCLK   I141 @TIMECARD_LIB.TIMECARD(SCH_1):PAGE524
     1 R_FT4232_TCK @TIMECARD_LIB.TIMECARD(SCH_1):R_FT4232_TCK   I141 @TIMECARD_LIB.TIMECARD(SCH_1):PAGE524

R468 RESISTOR-G155-133R0-01,33OHM,1%
     2 FT4232_TDI_MOSI @TIMECARD_LIB.TIMECARD(SCH_1):FT4232_TDI_MOSI   I140 @TIMECARD_LIB.TIMECARD(SCH_1):PAGE524
     1 R_FT4232_TDI @TIMECARD_LIB.TIMECARD(SCH_1):R_FT4232_TDI   I140 @TIMECARD_LIB.TIMECARD(SCH_1):PAGE524

R469 RESISTOR-G155-133R0-01,33OHM,1%
     2 FT4232_TDO_MISO @TIMECARD_LIB.TIMECARD(SCH_1):FT4232_TDO_MISO   I142 @TIMECARD_LIB.TIMECARD(SCH_1):PAGE524
     1 R_FT4232_TDO @TIMECARD_LIB.TIMECARD(SCH_1):R_FT4232_TDO   I142 @TIMECARD_LIB.TIMECARD(SCH_1):PAGE524

R470 RESISTOR-G155-133R0-01,33OHM,1%
     2 FT4232_TMS_SPICS_N @TIMECARD_LIB.TIMECARD(SCH_1):FT4232_TMS_SPICS_N   I139 @TIMECARD_LIB.TIMECARD(SCH_1):PAGE524
     1 R_FT4232_TMS @TIMECARD_LIB.TIMECARD(SCH_1):R_FT4232_TMS   I139 @TIMECARD_LIB.TIMECARD(SCH_1):PAGE524

R471 RESISTOR-G155-100R0-J0,0OHM,-
     2 FT4232_I2C_SCL @TIMECARD_LIB.TIMECARD(SCH_1):FT4232_I2C_SCL   I169 @TIMECARD_LIB.TIMECARD(SCH_1):PAGE524
     1 R_FT4232_I2C_SCL @TIMECARD_LIB.TIMECARD(SCH_1):R_FT4232_I2C_SCL   I169 @TIMECARD_LIB.TIMECARD(SCH_1):PAGE524

R472 RESISTOR-G155-100R0-J0,0OHM,-
     2 FT4232_I2C_SDA @TIMECARD_LIB.TIMECARD(SCH_1):FT4232_I2C_SDA   I166 @TIMECARD_LIB.TIMECARD(SCH_1):PAGE524
     1 R_FT4232_I2C_SDA_OUT @TIMECARD_LIB.TIMECARD(SCH_1):R_FT4232_I2C_SDA_OUT   I166 @TIMECARD_LIB.TIMECARD(SCH_1):PAGE524

R473 RESISTOR-G155-100R0-J0,0OHM,-
     2 FT4232_I2C_SDA @TIMECARD_LIB.TIMECARD(SCH_1):FT4232_I2C_SDA   I170 @TIMECARD_LIB.TIMECARD(SCH_1):PAGE524
     1 R_FT4232_I2C_SDA_IN @TIMECARD_LIB.TIMECARD(SCH_1):R_FT4232_I2C_SDA_IN   I170 @TIMECARD_LIB.TIMECARD(SCH_1):PAGE524

R474 RESISTOR-G155-11003-01,100KOHMA
     2 FPGA_PCA9546_I2C_SDA @TIMECARD_LIB.TIMECARD(SCH_1):FPGA_PCA9546_I2C_SDA   I466 @TIMECARD_LIB.TIMECARD(SCH_1):PAGE524
     1 XP3R3V_FPGA @TIMECARD_LIB.TIMECARD(SCH_1):XP3R3V_FPGA   I466 @TIMECARD_LIB.TIMECARD(SCH_1):PAGE524

R475 RESISTOR-G155-11003-01,100KOHMA
     2 FPGA_PCA9546_I2C_SCL @TIMECARD_LIB.TIMECARD(SCH_1):FPGA_PCA9546_I2C_SCL   I467 @TIMECARD_LIB.TIMECARD(SCH_1):PAGE524
     1 XP3R3V_FPGA @TIMECARD_LIB.TIMECARD(SCH_1):XP3R3V_FPGA   I467 @TIMECARD_LIB.TIMECARD(SCH_1):PAGE524

R476 RESISTOR-G155-11003-01,100KOHMA
     2 FPGA_EEPROM_I2C_SDA @TIMECARD_LIB.TIMECARD(SCH_1):FPGA_EEPROM_I2C_SDA   I468 @TIMECARD_LIB.TIMECARD(SCH_1):PAGE524
     1 XP3R3V_FPGA @TIMECARD_LIB.TIMECARD(SCH_1):XP3R3V_FPGA   I468 @TIMECARD_LIB.TIMECARD(SCH_1):PAGE524

R477 RESISTOR-G155-11003-01,100KOHMA
     2 FPGA_EEPROM_I2C_SCL @TIMECARD_LIB.TIMECARD(SCH_1):FPGA_EEPROM_I2C_SCL   I469 @TIMECARD_LIB.TIMECARD(SCH_1):PAGE524
     1 XP3R3V_FPGA @TIMECARD_LIB.TIMECARD(SCH_1):XP3R3V_FPGA   I469 @TIMECARD_LIB.TIMECARD(SCH_1):PAGE524

R478 RESISTOR-G155-11003-01,100KOHMA
     2 XP3R3V_FT4232 @TIMECARD_LIB.TIMECARD(SCH_1):XP3R3V_FT4232   I190 @TIMECARD_LIB.TIMECARD(SCH_1):PAGE524
     1 FT4232_I2C_SCL @TIMECARD_LIB.TIMECARD(SCH_1):FT4232_I2C_SCL   I190 @TIMECARD_LIB.TIMECARD(SCH_1):PAGE524

R479 RESISTOR-G155-11003-01,100KOHMA
     2 XP3R3V_FT4232 @TIMECARD_LIB.TIMECARD(SCH_1):XP3R3V_FT4232   I191 @TIMECARD_LIB.TIMECARD(SCH_1):PAGE524
     1 FT4232_I2C_SDA @TIMECARD_LIB.TIMECARD(SCH_1):FT4232_I2C_SDA   I191 @TIMECARD_LIB.TIMECARD(SCH_1):PAGE524

R480 RESISTOR-G155-11003-01,100KOHMA
     2 XP3R3V_FT4232 @TIMECARD_LIB.TIMECARD(SCH_1):XP3R3V_FT4232   I149 @TIMECARD_LIB.TIMECARD(SCH_1):PAGE524
     1 UART_FT4232_TX_FPGA_RX @TIMECARD_LIB.TIMECARD(SCH_1):UART_FT4232_TX_FPGA_RX   I149 @TIMECARD_LIB.TIMECARD(SCH_1):PAGE524

R481 RESISTOR-G155-11003-01,100KOHMA
     2 XP3R3V_FT4232 @TIMECARD_LIB.TIMECARD(SCH_1):XP3R3V_FT4232   I150 @TIMECARD_LIB.TIMECARD(SCH_1):PAGE524
     1 R_FT4232_CHC_RX @TIMECARD_LIB.TIMECARD(SCH_1):R_FT4232_CHC_RX   I150 @TIMECARD_LIB.TIMECARD(SCH_1):PAGE524

R482 RESISTOR-G155-14701-01,4.7KOHMA
     2 MUX3_SEL @TIMECARD_LIB.TIMECARD(SCH_1):MUX3_SEL   I464 @TIMECARD_LIB.TIMECARD(SCH_1):PAGE524
     1 XP3R3V_FPGA @TIMECARD_LIB.TIMECARD(SCH_1):XP3R3V_FPGA   I464 @TIMECARD_LIB.TIMECARD(SCH_1):PAGE524

R483 RESISTOR-G155-11001-01,1KOHM,1%
     2 MUX3_SEL @TIMECARD_LIB.TIMECARD(SCH_1):MUX3_SEL   I462 @TIMECARD_LIB.TIMECARD(SCH_1):PAGE524
     1     SG @TIMECARD_LIB.TIMECARD(SCH_1):SG   I462 @TIMECARD_LIB.TIMECARD(SCH_1):PAGE524

R484 RESISTOR-G155-11001-01,1KOHM,1%
     2 UNNAMED_524_RESISTOR_I463_2 @TIMECARD_LIB.TIMECARD(SCH_1):UNNAMED_524_RESISTOR_I463_2   I463 @TIMECARD_LIB.TIMECARD(SCH_1):PAGE524
     1     SG @TIMECARD_LIB.TIMECARD(SCH_1):SG   I463 @TIMECARD_LIB.TIMECARD(SCH_1):PAGE524

R485 RESISTOR-G155-133R0-01,33OHM,1%
     2 MUX3_SEL @TIMECARD_LIB.TIMECARD(SCH_1):MUX3_SEL   I459 @TIMECARD_LIB.TIMECARD(SCH_1):PAGE524
     1 FPGA_OUT_MUX3_SEL @TIMECARD_LIB.TIMECARD(SCH_1):FPGA_OUT_MUX3_SEL   I459 @TIMECARD_LIB.TIMECARD(SCH_1):PAGE524

R486 RESISTOR-G155-133R0-01,33OHM,1%
     2 MUX3_SEL @TIMECARD_LIB.TIMECARD(SCH_1):MUX3_SEL   I460 @TIMECARD_LIB.TIMECARD(SCH_1):PAGE524
     1 FT4232_MUX3_SEL @TIMECARD_LIB.TIMECARD(SCH_1):FT4232_MUX3_SEL   I460 @TIMECARD_LIB.TIMECARD(SCH_1):PAGE524

R487 RESISTOR-G155-14701-01,4.7KOHMA
     2 UNNAMED_525_CAPACITOR_I14_1 @TIMECARD_LIB.TIMECARD(SCH_1):UNNAMED_525_CAPACITOR_I14_1    I65 @TIMECARD_LIB.TIMECARD(SCH_1):PAGE525
     1 UNNAMED_525_CAPACITOR_I16_1 @TIMECARD_LIB.TIMECARD(SCH_1):UNNAMED_525_CAPACITOR_I16_1    I65 @TIMECARD_LIB.TIMECARD(SCH_1):PAGE525

R488 RESISTOR-G155-11002-01,10KOHM,A
     2     SG @TIMECARD_LIB.TIMECARD(SCH_1):SG    I13 @TIMECARD_LIB.TIMECARD(SCH_1):PAGE525
     1 UNNAMED_525_CAPACITOR_I14_1 @TIMECARD_LIB.TIMECARD(SCH_1):UNNAMED_525_CAPACITOR_I14_1    I13 @TIMECARD_LIB.TIMECARD(SCH_1):PAGE525

R489 RESISTOR-G155-03921-01,3.92KOHA
     2     SG @TIMECARD_LIB.TIMECARD(SCH_1):SG    I68 @TIMECARD_LIB.TIMECARD(SCH_1):PAGE525
     1 UNNAMED_525_ISL80101IRAJZDFN10_ @TIMECARD_LIB.TIMECARD(SCH_1):UNNAMED_525_ISL80101IRAJZDFN10_I29_SENSE    I68 @TIMECARD_LIB.TIMECARD(SCH_1):PAGE525

R490 RESISTOR-G155-11002-01,10KOHM,A
     2 UNNAMED_525_ISL80101IRAJZDFN10_ @TIMECARD_LIB.TIMECARD(SCH_1):UNNAMED_525_ISL80101IRAJZDFN10_I29_SENSE    I66 @TIMECARD_LIB.TIMECARD(SCH_1):PAGE525
     1 XP3R3V_FT4232 @TIMECARD_LIB.TIMECARD(SCH_1):XP3R3V_FT4232    I66 @TIMECARD_LIB.TIMECARD(SCH_1):PAGE525

R491 RESISTOR-G155-03241-01,3.24KOHA
     2     SG @TIMECARD_LIB.TIMECARD(SCH_1):SG    I67 @TIMECARD_LIB.TIMECARD(SCH_1):PAGE525
     1 UNNAMED_525_ISL80101IRAJZDFN10_ @TIMECARD_LIB.TIMECARD(SCH_1):UNNAMED_525_ISL80101IRAJZDFN10_I29_SENSE    I67 @TIMECARD_LIB.TIMECARD(SCH_1):PAGE525

R492 RESISTOR-G155-100R0-J0,0OHM,-
     2 UNNAMED_12_74HCT2G125DPTSSOP8_I @TIMECARD_LIB.TIMECARD(SCH_1):UNNAMED_12_74HCT2G125DPTSSOP8_I204_1A   I319 @TIMECARD_LIB.TIMECARD(SCH_1):PAGE12
     1 UNNAMED_12_CAPACITOR_I318_2 @TIMECARD_LIB.TIMECARD(SCH_1):UNNAMED_12_CAPACITOR_I318_2   I319 @TIMECARD_LIB.TIMECARD(SCH_1):PAGE12

R493 RESISTOR-G155-100R0-J0,0OHM,-
     2 UNNAMED_12_74HCT2G125DPTSSOP8_3 @TIMECARD_LIB.TIMECARD(SCH_1):UNNAMED_12_74HCT2G125DPTSSOP8_I226_1A   I323 @TIMECARD_LIB.TIMECARD(SCH_1):PAGE12
     1 UNNAMED_12_CAPACITOR_I321_2 @TIMECARD_LIB.TIMECARD(SCH_1):UNNAMED_12_CAPACITOR_I321_2   I323 @TIMECARD_LIB.TIMECARD(SCH_1):PAGE12

R494 RESISTOR-G155-100R0-J0,0OHM,-
     2 UNNAMED_12_74HCT2G125DPTSSOP8_6 @TIMECARD_LIB.TIMECARD(SCH_1):UNNAMED_12_74HCT2G125DPTSSOP8_I255_1A   I326 @TIMECARD_LIB.TIMECARD(SCH_1):PAGE12
     1 UNNAMED_12_CAPACITOR_I328_2 @TIMECARD_LIB.TIMECARD(SCH_1):UNNAMED_12_CAPACITOR_I328_2   I326 @TIMECARD_LIB.TIMECARD(SCH_1):PAGE12

R495 RESISTOR-G155-100R0-J0,0OHM,-
     2 UNNAMED_12_74HCT2G125DPTSSOP8_9 @TIMECARD_LIB.TIMECARD(SCH_1):UNNAMED_12_74HCT2G125DPTSSOP8_I273_1A   I330 @TIMECARD_LIB.TIMECARD(SCH_1):PAGE12
     1 UNNAMED_12_CAPACITOR_I332_2 @TIMECARD_LIB.TIMECARD(SCH_1):UNNAMED_12_CAPACITOR_I332_2   I330 @TIMECARD_LIB.TIMECARD(SCH_1):PAGE12

R496 RESISTOR-G155-11004-01,1MOHM,1%
     2 BF_SMA3_SIG_IO_CONN @TIMECARD_LIB.TIMECARD(SCH_1):BF_SMA3_SIG_IO_CONN   I320 @TIMECARD_LIB.TIMECARD(SCH_1):PAGE12
     1     SG @TIMECARD_LIB.TIMECARD(SCH_1):SG   I320 @TIMECARD_LIB.TIMECARD(SCH_1):PAGE12

R497 RESISTOR-G155-11004-01,1MOHM,1%
     2 BF_SMA4_SIG_IO_CONN @TIMECARD_LIB.TIMECARD(SCH_1):BF_SMA4_SIG_IO_CONN   I322 @TIMECARD_LIB.TIMECARD(SCH_1):PAGE12
     1     SG @TIMECARD_LIB.TIMECARD(SCH_1):SG   I322 @TIMECARD_LIB.TIMECARD(SCH_1):PAGE12

R498 RESISTOR-G155-11004-01,1MOHM,1%
     2 BF_SMA1_SIG_IO_CONN @TIMECARD_LIB.TIMECARD(SCH_1):BF_SMA1_SIG_IO_CONN   I327 @TIMECARD_LIB.TIMECARD(SCH_1):PAGE12
     1     SG @TIMECARD_LIB.TIMECARD(SCH_1):SG   I327 @TIMECARD_LIB.TIMECARD(SCH_1):PAGE12

R499 RESISTOR-G155-11004-01,1MOHM,1%
     2 BF_SMA2_SIG_IO_CONN @TIMECARD_LIB.TIMECARD(SCH_1):BF_SMA2_SIG_IO_CONN   I331 @TIMECARD_LIB.TIMECARD(SCH_1):PAGE12
     1     SG @TIMECARD_LIB.TIMECARD(SCH_1):SG   I331 @TIMECARD_LIB.TIMECARD(SCH_1):PAGE12

R500 RESISTOR-G155-14701-01,4.7KOHMA
     2 ANT3_IN @TIMECARD_LIB.TIMECARD(SCH_1):ANT3_IN   I242 @TIMECARD_LIB.TIMECARD(SCH_1):PAGE161
     1     SG @TIMECARD_LIB.TIMECARD(SCH_1):SG   I242 @TIMECARD_LIB.TIMECARD(SCH_1):PAGE161

R501 RESISTOR-G155-14701-01,4.7KOHMA
     2 ANT4_IN @TIMECARD_LIB.TIMECARD(SCH_1):ANT4_IN   I241 @TIMECARD_LIB.TIMECARD(SCH_1):PAGE161
     1     SG @TIMECARD_LIB.TIMECARD(SCH_1):SG   I241 @TIMECARD_LIB.TIMECARD(SCH_1):PAGE161

R502 RESISTOR-G155-14701-01,4.7KOHMA
     2 FPGA_IN_MAC_10MHZ_OUT @TIMECARD_LIB.TIMECARD(SCH_1):FPGA_IN_MAC_10MHZ_OUT   I247 @TIMECARD_LIB.TIMECARD(SCH_1):PAGE161
     1 XP3R3V_FPGA @TIMECARD_LIB.TIMECARD(SCH_1):XP3R3V_FPGA   I247 @TIMECARD_LIB.TIMECARD(SCH_1):PAGE161

R503 RESISTOR-G155-14701-01,4.7KOHMA
     2     SG @TIMECARD_LIB.TIMECARD(SCH_1):SG   I246 @TIMECARD_LIB.TIMECARD(SCH_1):PAGE161
     1 ANT2_IN @TIMECARD_LIB.TIMECARD(SCH_1):ANT2_IN   I246 @TIMECARD_LIB.TIMECARD(SCH_1):PAGE161

R504 RESISTOR-G155-14701-01,4.7KOHMA
     2     SG @TIMECARD_LIB.TIMECARD(SCH_1):SG   I244 @TIMECARD_LIB.TIMECARD(SCH_1):PAGE161
     1 ANT1_IN @TIMECARD_LIB.TIMECARD(SCH_1):ANT1_IN   I244 @TIMECARD_LIB.TIMECARD(SCH_1):PAGE161

R1991 RESISTOR-G155-11002-01,10KOHM,A
     2 EEPROM_SDA @TIMECARD_LIB.TIMECARD(SCH_1):EEPROM_SDA    I96 @TIMECARD_LIB.TIMECARD(SCH_1):PAGE5
     1 XP3R3V_FPGA @TIMECARD_LIB.TIMECARD(SCH_1):XP3R3V_FPGA    I96 @TIMECARD_LIB.TIMECARD(SCH_1):PAGE5

R1992 RESISTOR-G155-14701-01,4.7KOHMA
     2 SN_EEPROM_WP @TIMECARD_LIB.TIMECARD(SCH_1):SN_EEPROM_WP    I94 @TIMECARD_LIB.TIMECARD(SCH_1):PAGE5
     1 XP3R3V_FPGA @TIMECARD_LIB.TIMECARD(SCH_1):XP3R3V_FPGA    I94 @TIMECARD_LIB.TIMECARD(SCH_1):PAGE5

 SP1 SOLDER_PREFORM-G380-10015-01
     1     SG @TIMECARD_LIB.TIMECARD(SCH_1):SG    I24 @TIMECARD_LIB.TIMECARD(SCH_1):PAGE516
     2 XP5R0V_AGND @TIMECARD_LIB.TIMECARD(SCH_1):XP5R0V_AGND    I24 @TIMECARD_LIB.TIMECARD(SCH_1):PAGE516

 SP2 SOLDER_PREFORM-G380-10015-01
     1     SG @TIMECARD_LIB.TIMECARD(SCH_1):SG    I24 @TIMECARD_LIB.TIMECARD(SCH_1):PAGE517
     2 XP3R3V_AGND @TIMECARD_LIB.TIMECARD(SCH_1):XP3R3V_AGND    I24 @TIMECARD_LIB.TIMECARD(SCH_1):PAGE517

 SP3 SOLDER_PREFORM-G380-10015-01
     1     SG @TIMECARD_LIB.TIMECARD(SCH_1):SG    I39 @TIMECARD_LIB.TIMECARD(SCH_1):PAGE523
     2 XP1R0V_AGND @TIMECARD_LIB.TIMECARD(SCH_1):XP1R0V_AGND    I39 @TIMECARD_LIB.TIMECARD(SCH_1):PAGE523

 SP4 SOLDER_PREFORM-G380-10015-01
     1     NC     NC   I130 @TIMECARD_LIB.TIMECARD(SCH_1):PAGE33
     2     NC     NC   I130 @TIMECARD_LIB.TIMECARD(SCH_1):PAGE33

 SP5 SOLDER_PREFORM-G380-10015-01
     1     NC     NC   I131 @TIMECARD_LIB.TIMECARD(SCH_1):PAGE33
     2     NC     NC   I131 @TIMECARD_LIB.TIMECARD(SCH_1):PAGE33

 SP6 SOLDER_PREFORM-G380-10015-01
     1     NC     NC   I133 @TIMECARD_LIB.TIMECARD(SCH_1):PAGE33
     2     NC     NC   I133 @TIMECARD_LIB.TIMECARD(SCH_1):PAGE33

 SP7 SOLDER_PREFORM-G380-10015-01
     1     NC     NC   I132 @TIMECARD_LIB.TIMECARD(SCH_1):PAGE33
     2     NC     NC   I132 @TIMECARD_LIB.TIMECARD(SCH_1):PAGE33

 SP8 SOLDER_PREFORM-G380-10015-01
     1     NC     NC   I134 @TIMECARD_LIB.TIMECARD(SCH_1):PAGE33
     2     NC     NC   I134 @TIMECARD_LIB.TIMECARD(SCH_1):PAGE33

 SP9 SOLDER_PREFORM-G380-10015-01
     1     NC     NC   I135 @TIMECARD_LIB.TIMECARD(SCH_1):PAGE33
     2     NC     NC   I135 @TIMECARD_LIB.TIMECARD(SCH_1):PAGE33

SP10 SOLDER_PREFORM-G380-10015-01
     1     NC     NC   I137 @TIMECARD_LIB.TIMECARD(SCH_1):PAGE33
     2     NC     NC   I137 @TIMECARD_LIB.TIMECARD(SCH_1):PAGE33

SP11 SOLDER_PREFORM-G380-10015-01
     1     NC     NC   I136 @TIMECARD_LIB.TIMECARD(SCH_1):PAGE33
     2     NC     NC   I136 @TIMECARD_LIB.TIMECARD(SCH_1):PAGE33

SP12 SOLDER_PREFORM-G380-10015-01
     1     NC     NC   I141 @TIMECARD_LIB.TIMECARD(SCH_1):PAGE33
     2     NC     NC   I141 @TIMECARD_LIB.TIMECARD(SCH_1):PAGE33

SP13 SOLDER_PREFORM-G380-10015-01
     1     NC     NC   I140 @TIMECARD_LIB.TIMECARD(SCH_1):PAGE33
     2     NC     NC   I140 @TIMECARD_LIB.TIMECARD(SCH_1):PAGE33

SP14 SOLDER_PREFORM-G380-10015-01
     1     NC     NC   I139 @TIMECARD_LIB.TIMECARD(SCH_1):PAGE33
     2     NC     NC   I139 @TIMECARD_LIB.TIMECARD(SCH_1):PAGE33

SP15 SOLDER_PREFORM-G380-10015-01
     1     NC     NC   I138 @TIMECARD_LIB.TIMECARD(SCH_1):PAGE33
     2     NC     NC   I138 @TIMECARD_LIB.TIMECARD(SCH_1):PAGE33

SP16 SOLDER_PREFORM-G380-10015-01
     1     NC     NC   I153 @TIMECARD_LIB.TIMECARD(SCH_1):PAGE33
     2     NC     NC   I153 @TIMECARD_LIB.TIMECARD(SCH_1):PAGE33

SP17 SOLDER_PREFORM-G380-10015-01
     1     NC     NC   I142 @TIMECARD_LIB.TIMECARD(SCH_1):PAGE33
     2     NC     NC   I142 @TIMECARD_LIB.TIMECARD(SCH_1):PAGE33

SP18 SOLDER_PREFORM-G380-10015-01
     1     NC     NC   I152 @TIMECARD_LIB.TIMECARD(SCH_1):PAGE33
     2     NC     NC   I152 @TIMECARD_LIB.TIMECARD(SCH_1):PAGE33

SP19 SOLDER_PREFORM-G380-10015-01
     1     NC     NC   I151 @TIMECARD_LIB.TIMECARD(SCH_1):PAGE33
     2     NC     NC   I151 @TIMECARD_LIB.TIMECARD(SCH_1):PAGE33

SP20 SOLDER_PREFORM-G380-10015-01
     1     NC     NC   I149 @TIMECARD_LIB.TIMECARD(SCH_1):PAGE33
     2     NC     NC   I149 @TIMECARD_LIB.TIMECARD(SCH_1):PAGE33

SP21 SOLDER_PREFORM-G380-10015-01
     1     NC     NC   I150 @TIMECARD_LIB.TIMECARD(SCH_1):PAGE33
     2     NC     NC   I150 @TIMECARD_LIB.TIMECARD(SCH_1):PAGE33

SP22 SOLDER_PREFORM-G380-10015-01
     1     NC     NC   I148 @TIMECARD_LIB.TIMECARD(SCH_1):PAGE33
     2     NC     NC   I148 @TIMECARD_LIB.TIMECARD(SCH_1):PAGE33

SP23 SOLDER_PREFORM-G380-10015-01
     1     NC     NC   I147 @TIMECARD_LIB.TIMECARD(SCH_1):PAGE33
     2     NC     NC   I147 @TIMECARD_LIB.TIMECARD(SCH_1):PAGE33

SP24 SOLDER_PREFORM-G380-10015-01
     1     NC     NC   I146 @TIMECARD_LIB.TIMECARD(SCH_1):PAGE33
     2     NC     NC   I146 @TIMECARD_LIB.TIMECARD(SCH_1):PAGE33

SP25 SOLDER_PREFORM-G380-10015-01
     1     NC     NC   I145 @TIMECARD_LIB.TIMECARD(SCH_1):PAGE33
     2     NC     NC   I145 @TIMECARD_LIB.TIMECARD(SCH_1):PAGE33

SP26 SOLDER_PREFORM-G380-10015-01
     1     NC     NC   I144 @TIMECARD_LIB.TIMECARD(SCH_1):PAGE33
     2     NC     NC   I144 @TIMECARD_LIB.TIMECARD(SCH_1):PAGE33

SP27 SOLDER_PREFORM-G380-10015-01
     1     NC     NC   I143 @TIMECARD_LIB.TIMECARD(SCH_1):PAGE33
     2     NC     NC   I143 @TIMECARD_LIB.TIMECARD(SCH_1):PAGE33

SP28 SOLDER_PREFORM-G380-10015-01
     1     NC     NC   I175 @TIMECARD_LIB.TIMECARD(SCH_1):PAGE33
     2     NC     NC   I175 @TIMECARD_LIB.TIMECARD(SCH_1):PAGE33

SP29 SOLDER_PREFORM-G380-10015-01
     1     NC     NC   I174 @TIMECARD_LIB.TIMECARD(SCH_1):PAGE33
     2     NC     NC   I174 @TIMECARD_LIB.TIMECARD(SCH_1):PAGE33

SP30 SOLDER_PREFORM-G380-10015-01
     1     NC     NC   I173 @TIMECARD_LIB.TIMECARD(SCH_1):PAGE33
     2     NC     NC   I173 @TIMECARD_LIB.TIMECARD(SCH_1):PAGE33

SP31 SOLDER_PREFORM-G380-10015-01
     1     NC     NC   I172 @TIMECARD_LIB.TIMECARD(SCH_1):PAGE33
     2     NC     NC   I172 @TIMECARD_LIB.TIMECARD(SCH_1):PAGE33

SP32 SOLDER_PREFORM-G380-10015-01
     1     NC     NC   I171 @TIMECARD_LIB.TIMECARD(SCH_1):PAGE33
     2     NC     NC   I171 @TIMECARD_LIB.TIMECARD(SCH_1):PAGE33

SP33 SOLDER_PREFORM-G380-10015-01
     1     NC     NC   I169 @TIMECARD_LIB.TIMECARD(SCH_1):PAGE33
     2     NC     NC   I169 @TIMECARD_LIB.TIMECARD(SCH_1):PAGE33

SP34 SOLDER_PREFORM-G380-10015-01
     1     NC     NC   I167 @TIMECARD_LIB.TIMECARD(SCH_1):PAGE33
     2     NC     NC   I167 @TIMECARD_LIB.TIMECARD(SCH_1):PAGE33

SP35 SOLDER_PREFORM-G380-10015-01
     1     NC     NC   I165 @TIMECARD_LIB.TIMECARD(SCH_1):PAGE33
     2     NC     NC   I165 @TIMECARD_LIB.TIMECARD(SCH_1):PAGE33

SP36 SOLDER_PREFORM-G380-10015-01
     1     NC     NC   I163 @TIMECARD_LIB.TIMECARD(SCH_1):PAGE33
     2     NC     NC   I163 @TIMECARD_LIB.TIMECARD(SCH_1):PAGE33

SP37 SOLDER_PREFORM-G380-10015-01
     1     NC     NC   I161 @TIMECARD_LIB.TIMECARD(SCH_1):PAGE33
     2     NC     NC   I161 @TIMECARD_LIB.TIMECARD(SCH_1):PAGE33

SP38 SOLDER_PREFORM-G380-10015-01
     1     NC     NC   I159 @TIMECARD_LIB.TIMECARD(SCH_1):PAGE33
     2     NC     NC   I159 @TIMECARD_LIB.TIMECARD(SCH_1):PAGE33

SP39 SOLDER_PREFORM-G380-10015-01
     1     NC     NC   I177 @TIMECARD_LIB.TIMECARD(SCH_1):PAGE33
     2     NC     NC   I177 @TIMECARD_LIB.TIMECARD(SCH_1):PAGE33

SP40 SOLDER_PREFORM-G380-10015-01
     1     NC     NC   I176 @TIMECARD_LIB.TIMECARD(SCH_1):PAGE33
     2     NC     NC   I176 @TIMECARD_LIB.TIMECARD(SCH_1):PAGE33

SP41 SOLDER_PREFORM-G380-10015-01
     1     NC     NC   I155 @TIMECARD_LIB.TIMECARD(SCH_1):PAGE33
     2     NC     NC   I155 @TIMECARD_LIB.TIMECARD(SCH_1):PAGE33

SP42 NULL-G380-10013-01

SP43 NULL-G380-10013-01

SP44 NULL-G380-10013-01

SP45 NULL-G380-10013-01

SP46 NULL-G380-10013-01

SP47 NULL-G380-10013-01

SP48 NULL-G380-10013-01

SP49 NULL-G380-10013-01

SP50 NULL-G380-10013-01

SP51 NULL-G380-10013-01

SP52 NULL-G380-10013-01

SP53 NULL-G380-10013-01

SP54 NULL-G380-10013-01

SP55 NULL-G380-10013-01

SP56 NULL-G380-10013-01

SP57 NULL-G380-10013-01

SP58 NULL-G380-10013-01

SP59 NULL-G380-10013-01

SP60 NULL-G380-10013-01

SP61 NULL-G380-10013-01

SP62 NULL-G380-10013-01

SP63 NULL-G380-10013-01

SP64 NULL-G380-10013-01

SP65 NULL-G380-10013-01

SP66 NULL-G380-10013-01

SP67 NULL-G380-10013-01

SP68 NULL-G380-10013-01

SP69 NULL-G380-10013-01

SP70 NULL-G380-10013-01

SP71 NULL-G380-10013-01

 TP1 TP_PIONT-TP010CT020B030_PTH-TPA
     1 BNO080_EVN_SDA @TIMECARD_LIB.TIMECARD(SCH_1):BNO080_EVN_SDA    I71 @TIMECARD_LIB.TIMECARD(SCH_1):PAGE9

 TP2 TP_PIONT-TP010CT020B030_PTH-TPA
     1 BNO080_EVN_SCL @TIMECARD_LIB.TIMECARD(SCH_1):BNO080_EVN_SCL    I72 @TIMECARD_LIB.TIMECARD(SCH_1):PAGE9

 TP3 TP_PIONT-TP010CT020B030_PTH-TPA
     1 XP3R3V_FT4232 @TIMECARD_LIB.TIMECARD(SCH_1):XP3R3V_FT4232  I1610 @TIMECARD_LIB.TIMECARD(SCH_1):PAGE16

 TP4 TP_PIONT-TP010CT020B030_PTH-TPA
     1 XP5R0V_FT4232 @TIMECARD_LIB.TIMECARD(SCH_1):XP5R0V_FT4232  I1612 @TIMECARD_LIB.TIMECARD(SCH_1):PAGE16

 TP5 TP_PIONT-TP010CT020B030_PTH-TPA
     1 UNNAMED_524_FT4232HLREELQFP64_I @TIMECARD_LIB.TIMECARD(SCH_1):UNNAMED_524_FT4232HLREELQFP64_I64_ADBUS7   I311 @TIMECARD_LIB.TIMECARD(SCH_1):PAGE524

 TP6 TP_PIONT-TP010CT020B030_PTH-TPA
     1 UNNAMED_524_FT4232HLREELQFP64_1 @TIMECARD_LIB.TIMECARD(SCH_1):UNNAMED_524_FT4232HLREELQFP64_I64_BDBUS3   I312 @TIMECARD_LIB.TIMECARD(SCH_1):PAGE524

 TP7 TP_PIONT-TP010CT020B030_PTH-TPA
     1 UNNAMED_524_FT4232HLREELQFP64_2 @TIMECARD_LIB.TIMECARD(SCH_1):UNNAMED_524_FT4232HLREELQFP64_I64_BDBUS4   I313 @TIMECARD_LIB.TIMECARD(SCH_1):PAGE524

 TP8 TP_PIONT-TP010CT020B030_PTH-TPA
     1 UNNAMED_524_FT4232HLREELQFP64_3 @TIMECARD_LIB.TIMECARD(SCH_1):UNNAMED_524_FT4232HLREELQFP64_I64_BDBUS5   I315 @TIMECARD_LIB.TIMECARD(SCH_1):PAGE524

 TP9 TP_PIONT-TP010CT020B030_PTH-TPA
     1 UNNAMED_524_FT4232HLREELQFP64_4 @TIMECARD_LIB.TIMECARD(SCH_1):UNNAMED_524_FT4232HLREELQFP64_I64_BDBUS6   I314 @TIMECARD_LIB.TIMECARD(SCH_1):PAGE524

TP10 TP_PIONT-TP010CT020B030_PTH-TPA
     1 UNNAMED_524_FT4232HLREELQFP64_5 @TIMECARD_LIB.TIMECARD(SCH_1):UNNAMED_524_FT4232HLREELQFP64_I64_BDBUS7   I316 @TIMECARD_LIB.TIMECARD(SCH_1):PAGE524

TP11 TP_PIONT-TP010CT020B030_PTH-TPA
     1 FT_USB_DETECT @TIMECARD_LIB.TIMECARD(SCH_1):FT_USB_DETECT  I1626 @TIMECARD_LIB.TIMECARD(SCH_1):PAGE16

TP12 TP_PIONT-TP010CT020B030_PTH-TPA
     1 MUX3_SEL @TIMECARD_LIB.TIMECARD(SCH_1):MUX3_SEL  I1627 @TIMECARD_LIB.TIMECARD(SCH_1):PAGE16

TP13 TP_PIONT-TP010CT020B030_PTH-TPA
     1 MUX2_SEL @TIMECARD_LIB.TIMECARD(SCH_1):MUX2_SEL  I1628 @TIMECARD_LIB.TIMECARD(SCH_1):PAGE16

TP14 TP_PIONT-TP010CT020B030_PTH-TPA
     1 MUX1_SEL @TIMECARD_LIB.TIMECARD(SCH_1):MUX1_SEL  I1629 @TIMECARD_LIB.TIMECARD(SCH_1):PAGE16

TP15 TP_PIONT-TP010CT020B030_PTH-TPA
     1 GPS_RST_N @TIMECARD_LIB.TIMECARD(SCH_1):GPS_RST_N  I1630 @TIMECARD_LIB.TIMECARD(SCH_1):PAGE16

TP16 TP_PIONT-TP010CT020B030_PTH-TPA
     1 R_BNO080_RST_N @TIMECARD_LIB.TIMECARD(SCH_1):R_BNO080_RST_N  I1631 @TIMECARD_LIB.TIMECARD(SCH_1):PAGE16

TP17 TP_PIONT-TP010CT020B030_PTH-TPA
     1 R_BNO080_INT_N @TIMECARD_LIB.TIMECARD(SCH_1):R_BNO080_INT_N  I1632 @TIMECARD_LIB.TIMECARD(SCH_1):PAGE16

TP18 TP_PIONT-TP010CT020B030_PTH-TPA
     1 R_BNO080_BOOT_N @TIMECARD_LIB.TIMECARD(SCH_1):R_BNO080_BOOT_N  I1633 @TIMECARD_LIB.TIMECARD(SCH_1):PAGE16

TP19 TP_PIONT-TP010CT020B030_PTH-TPA
     1 SN_EEPROM_WP @TIMECARD_LIB.TIMECARD(SCH_1):SN_EEPROM_WP  I1634 @TIMECARD_LIB.TIMECARD(SCH_1):PAGE16

TP20 TP_PIONT-TP010CT020B030_PTH-TPA
     1 SEC_EEPROM_WP @TIMECARD_LIB.TIMECARD(SCH_1):SEC_EEPROM_WP  I1615 @TIMECARD_LIB.TIMECARD(SCH_1):PAGE16

TP21 TP_PIONT-TP010CT020B030_PTH-TPA
     1 PCA9546_RST_N @TIMECARD_LIB.TIMECARD(SCH_1):PCA9546_RST_N  I1645 @TIMECARD_LIB.TIMECARD(SCH_1):PAGE16

TP22 TP_PIONT-TP010CT020B030_PTH-TPA
     1 FPGA_IN_LM75B_INT3_N @TIMECARD_LIB.TIMECARD(SCH_1):FPGA_IN_LM75B_INT3_N  I1646 @TIMECARD_LIB.TIMECARD(SCH_1):PAGE16

TP23 TP_PIONT-TP010CT020B030_PTH-TPA
     1 FPGA_IN_LM75B_INT2_N @TIMECARD_LIB.TIMECARD(SCH_1):FPGA_IN_LM75B_INT2_N  I1647 @TIMECARD_LIB.TIMECARD(SCH_1):PAGE16

TP24 TP_PIONT-TP010CT020B030_PTH-TPA
     1 FPGA_IN_LM75B_INT1_N @TIMECARD_LIB.TIMECARD(SCH_1):FPGA_IN_LM75B_INT1_N  I1648 @TIMECARD_LIB.TIMECARD(SCH_1):PAGE16

TP25 TP_PIONT-TP010CT020B030_PTH-TPA
     1 RGB_LED_SHUTDOWN_N @TIMECARD_LIB.TIMECARD(SCH_1):RGB_LED_SHUTDOWN_N  I1649 @TIMECARD_LIB.TIMECARD(SCH_1):PAGE16

TP26 TP_PIONT-TP010CT020B030_PTH-TPA
     1 R_SHT3X_RST_N @TIMECARD_LIB.TIMECARD(SCH_1):R_SHT3X_RST_N  I1660 @TIMECARD_LIB.TIMECARD(SCH_1):PAGE16

TP27 TP_PIONT-TP010CT020B030_PTH-TPA
     1 R_SHT3X_ALERT_N @TIMECARD_LIB.TIMECARD(SCH_1):R_SHT3X_ALERT_N  I1661 @TIMECARD_LIB.TIMECARD(SCH_1):PAGE16

TP28 TP_PIONT-TP010CT020B030_PTH-TPA
     1 SMA1_SIG_IN_BF_EN_N @TIMECARD_LIB.TIMECARD(SCH_1):SMA1_SIG_IN_BF_EN_N  I1667 @TIMECARD_LIB.TIMECARD(SCH_1):PAGE16

TP29 TP_PIONT-TP010CT020B030_PTH-TPA
     1 SMA2_SIG_IN_BF_EN_N @TIMECARD_LIB.TIMECARD(SCH_1):SMA2_SIG_IN_BF_EN_N  I1672 @TIMECARD_LIB.TIMECARD(SCH_1):PAGE16

TP30 TP_PIONT-TP010CT020B030_PTH-TPA
     1 SMA3_SIG_IN_BF_EN_N @TIMECARD_LIB.TIMECARD(SCH_1):SMA3_SIG_IN_BF_EN_N  I1678 @TIMECARD_LIB.TIMECARD(SCH_1):PAGE16

TP31 TP_PIONT-TP010CT020B030_PTH-TPA
     1 SMA4_SIG_IN_BF_EN_N @TIMECARD_LIB.TIMECARD(SCH_1):SMA4_SIG_IN_BF_EN_N  I1679 @TIMECARD_LIB.TIMECARD(SCH_1):PAGE16

TP32 TP_PIONT-TP010CT020B030_PTH-TPA
     1 SMA1_SIG_OUT_BF_EN_N @TIMECARD_LIB.TIMECARD(SCH_1):SMA1_SIG_OUT_BF_EN_N  I1662 @TIMECARD_LIB.TIMECARD(SCH_1):PAGE16

TP33 TP_PIONT-TP010CT020B030_PTH-TPA
     1 SMA2_SIG_OUT_BF_EN_N @TIMECARD_LIB.TIMECARD(SCH_1):SMA2_SIG_OUT_BF_EN_N  I1669 @TIMECARD_LIB.TIMECARD(SCH_1):PAGE16

TP34 TP_PIONT-TP010CT020B030_PTH-TPA
     1 SMA3_SIG_OUT_BF_EN_N @TIMECARD_LIB.TIMECARD(SCH_1):SMA3_SIG_OUT_BF_EN_N  I1673 @TIMECARD_LIB.TIMECARD(SCH_1):PAGE16

TP35 TP_PIONT-TP010CT020B030_PTH-TPA
     1 SMA4_SIG_OUT_BF_EN_N @TIMECARD_LIB.TIMECARD(SCH_1):SMA4_SIG_OUT_BF_EN_N  I1675 @TIMECARD_LIB.TIMECARD(SCH_1):PAGE16

TP36 TP_PIONT-TP010CT020B030_PTH-TPA
     1 XP12R0V_A_PG @TIMECARD_LIB.TIMECARD(SCH_1):XP12R0V_A_PG  I1650 @TIMECARD_LIB.TIMECARD(SCH_1):PAGE16

TP37 TP_PIONT-TP010CT020B030_PTH-TPA
     1 XP12R0V_A_FLTB @TIMECARD_LIB.TIMECARD(SCH_1):XP12R0V_A_FLTB  I1682 @TIMECARD_LIB.TIMECARD(SCH_1):PAGE16

TP38 TP_PIONT-TP010CT020B030_PTH-TPA
     1 XP3R3V_PG @TIMECARD_LIB.TIMECARD(SCH_1):XP3R3V_PG  I1651 @TIMECARD_LIB.TIMECARD(SCH_1):PAGE16

TP39 TP_PIONT-TP010CT020B030_PTH-TPA
     1 XP1R0V_FPGA_PG @TIMECARD_LIB.TIMECARD(SCH_1):XP1R0V_FPGA_PG  I1652 @TIMECARD_LIB.TIMECARD(SCH_1):PAGE16

TP40 TP_PIONT-TP010CT020B030_PTH-TPA
     1 XP1R2V_FPGA_PG @TIMECARD_LIB.TIMECARD(SCH_1):XP1R2V_FPGA_PG  I1653 @TIMECARD_LIB.TIMECARD(SCH_1):PAGE16

TP41 TP_PIONT-TP010CT020B030_PTH-TPA
     1 XP1R8V_FPGA_PG @TIMECARD_LIB.TIMECARD(SCH_1):XP1R8V_FPGA_PG  I1654 @TIMECARD_LIB.TIMECARD(SCH_1):PAGE16

TP42 TP_PIONT-TP010CT020B030_PTH-TPA
     1 XP12R0V_IN @TIMECARD_LIB.TIMECARD(SCH_1):XP12R0V_IN  I1665 @TIMECARD_LIB.TIMECARD(SCH_1):PAGE16

TP43 TP_PIONT-TP010CT020B030_PTH-TPA
     1 XP12R0V_A_EN @TIMECARD_LIB.TIMECARD(SCH_1):XP12R0V_A_EN  I1691 @TIMECARD_LIB.TIMECARD(SCH_1):PAGE16

TP44 TP_PIONT-TP010CT020B030_PTH-TPA
     1 FPGA_DONE @TIMECARD_LIB.TIMECARD(SCH_1):FPGA_DONE  I1689 @TIMECARD_LIB.TIMECARD(SCH_1):PAGE16

TP45 TP_PIONT-TP010CT020B030_PTH-TPA
     1 FPGA_PROGRAM_N @TIMECARD_LIB.TIMECARD(SCH_1):FPGA_PROGRAM_N  I1690 @TIMECARD_LIB.TIMECARD(SCH_1):PAGE16

TP46 TP_PIONT-TP010CT020B030_PTH-TPA
     1 FPGA_CFG_INIT_N @TIMECARD_LIB.TIMECARD(SCH_1):FPGA_CFG_INIT_N  I1684 @TIMECARD_LIB.TIMECARD(SCH_1):PAGE16

TP47 TP_PIONT-TP010CT020B030_PTH-TPA
     1 FPGA_MGTRREF @TIMECARD_LIB.TIMECARD(SCH_1):FPGA_MGTRREF  I1693 @TIMECARD_LIB.TIMECARD(SCH_1):PAGE16

TP48 TP_PIONT-TP010CT020B030_PTH-TPA
     1 PCIE_CONN_PERST_N @TIMECARD_LIB.TIMECARD(SCH_1):PCIE_CONN_PERST_N  I1695 @TIMECARD_LIB.TIMECARD(SCH_1):PAGE16

TP49 TP_PIONT-TP010CT020B030_PTH-TPA
     1 CLK_200M_OE @TIMECARD_LIB.TIMECARD(SCH_1):CLK_200M_OE  I1699 @TIMECARD_LIB.TIMECARD(SCH_1):PAGE16

TP50 TP_PIONT-TP010CT020B030_PTH-TPA
     1 CLK_125M_OE @TIMECARD_LIB.TIMECARD(SCH_1):CLK_125M_OE  I1701 @TIMECARD_LIB.TIMECARD(SCH_1):PAGE16

TP51 TP_PIONT-TP010CT020B030_PTH-TPA
     1 MAC_ALARM @TIMECARD_LIB.TIMECARD(SCH_1):MAC_ALARM  I1704 @TIMECARD_LIB.TIMECARD(SCH_1):PAGE16

TP52 TP_PIONT-TP010CT020B030_PTH-TPA
     1 XP12R0V @TIMECARD_LIB.TIMECARD(SCH_1):XP12R0V  I1206 @TIMECARD_LIB.TIMECARD(SCH_1):PAGE16

TP53 TP_PIONT-TP010CT020B030_PTH-TPA
     1 XP3R3V @TIMECARD_LIB.TIMECARD(SCH_1):XP3R3V  I1208 @TIMECARD_LIB.TIMECARD(SCH_1):PAGE16

TP54 TP_PIONT-TP010CT020B030_PTH-TPA
     1 XP1R0V_FPGA @TIMECARD_LIB.TIMECARD(SCH_1):XP1R0V_FPGA  I1210 @TIMECARD_LIB.TIMECARD(SCH_1):PAGE16

TP55 TP_PIONT-TP010CT020B030_PTH-TPA
     1 XP1R2V_FPGA @TIMECARD_LIB.TIMECARD(SCH_1):XP1R2V_FPGA  I1212 @TIMECARD_LIB.TIMECARD(SCH_1):PAGE16

TP56 TP_PIONT-TP010CT020B030_PTH-TPA
     1 XP1R8V_FPGA @TIMECARD_LIB.TIMECARD(SCH_1):XP1R8V_FPGA  I1215 @TIMECARD_LIB.TIMECARD(SCH_1):PAGE16

TP57 TP_PIONT-TP010CT020B030_PTH-TPA
     1 XP2R5V_FPGA @TIMECARD_LIB.TIMECARD(SCH_1):XP2R5V_FPGA  I1217 @TIMECARD_LIB.TIMECARD(SCH_1):PAGE16

TP58 TP_PIONT-TP010CT020B030_PTH-TPA
     1 XP3R3V_FPGA @TIMECARD_LIB.TIMECARD(SCH_1):XP3R3V_FPGA  I1219 @TIMECARD_LIB.TIMECARD(SCH_1):PAGE16

TP59 TP_PIONT-TP010CT020B030_PTH-TPA
     1 XP3R3V_EN @TIMECARD_LIB.TIMECARD(SCH_1):XP3R3V_EN  I1663 @TIMECARD_LIB.TIMECARD(SCH_1):PAGE16

TP60 TP_PIONT-TP010CT020B030_PTH-TPA
     1 XP5R0V @TIMECARD_LIB.TIMECARD(SCH_1):XP5R0V  I1233 @TIMECARD_LIB.TIMECARD(SCH_1):PAGE16

TP61 TP_PIONT-TP010CT020B030_PTH-TPA
     1 UNNAMED_9_BNO080LGA28_I29_HCS @TIMECARD_LIB.TIMECARD(SCH_1):UNNAMED_9_BNO080LGA28_I29_HCS    I63 @TIMECARD_LIB.TIMECARD(SCH_1):PAGE9

TP62 TP_PIONT-TP010CT020B030_PTH-TPA
     1 R_MAC_BITEOUT @TIMECARD_LIB.TIMECARD(SCH_1):R_MAC_BITE OUT  I1705 @TIMECARD_LIB.TIMECARD(SCH_1):PAGE16

TP78 TP_PIONT-TP010CT020B030_PTH-TPA
     1 IO_L20P_16 @TIMECARD_LIB.TIMECARD(SCH_1):IO_L20P_16  I1516 @TIMECARD_LIB.TIMECARD(SCH_1):PAGE16

TP132 TP_PIONT-TP010CT020B030_PTH-TPA
     1 IO_L20P_34 @TIMECARD_LIB.TIMECARD(SCH_1):IO_L20P_34  I1014 @TIMECARD_LIB.TIMECARD(SCH_1):PAGE16

TP133 TP_PIONT-TP010CT020B030_PTH-TPA
     1 IO_L20N_34 @TIMECARD_LIB.TIMECARD(SCH_1):IO_L20N_34  I1015 @TIMECARD_LIB.TIMECARD(SCH_1):PAGE16

TP134 TP_PIONT-TP010CT020B030_PTH-TPA
     1 IO_L21P_34 @TIMECARD_LIB.TIMECARD(SCH_1):IO_L21P_34  I1016 @TIMECARD_LIB.TIMECARD(SCH_1):PAGE16

TP135 TP_PIONT-TP010CT020B030_PTH-TPA
     1 IO_L21N_34 @TIMECARD_LIB.TIMECARD(SCH_1):IO_L21N_34  I1017 @TIMECARD_LIB.TIMECARD(SCH_1):PAGE16

TP136 TP_PIONT-TP010CT020B030_PTH-TPA
     1 IO_L22P_34 @TIMECARD_LIB.TIMECARD(SCH_1):IO_L22P_34  I1018 @TIMECARD_LIB.TIMECARD(SCH_1):PAGE16

TP137 TP_PIONT-TP010CT020B030_PTH-TPA
     1 IO_L22N_34 @TIMECARD_LIB.TIMECARD(SCH_1):IO_L22N_34  I1019 @TIMECARD_LIB.TIMECARD(SCH_1):PAGE16

TP138 TP_PIONT-TP010CT020B030_PTH-TPA
     1 IO_L23P_34 @TIMECARD_LIB.TIMECARD(SCH_1):IO_L23P_34  I1020 @TIMECARD_LIB.TIMECARD(SCH_1):PAGE16

TP139 TP_PIONT-TP010CT020B030_PTH-TPA
     1 IO_L23N_34 @TIMECARD_LIB.TIMECARD(SCH_1):IO_L23N_34  I1021 @TIMECARD_LIB.TIMECARD(SCH_1):PAGE16

TP140 TP_PIONT-TP010CT020B030_PTH-TPA
     1 IO_L24P_34 @TIMECARD_LIB.TIMECARD(SCH_1):IO_L24P_34  I1022 @TIMECARD_LIB.TIMECARD(SCH_1):PAGE16

TP141 TP_PIONT-TP010CT020B030_PTH-TPA
     1 IO_L24N_34 @TIMECARD_LIB.TIMECARD(SCH_1):IO_L24N_34  I1023 @TIMECARD_LIB.TIMECARD(SCH_1):PAGE16

TP180 TP_PIONT-TP010CT020B030_PTH-TPA
     1 IO_L20N_16 @TIMECARD_LIB.TIMECARD(SCH_1):IO_L20N_16  I1511 @TIMECARD_LIB.TIMECARD(SCH_1):PAGE16

TP181 TP_PIONT-TP010CT020B030_PTH-TPA
     1 IO_L21P_16 @TIMECARD_LIB.TIMECARD(SCH_1):IO_L21P_16  I1512 @TIMECARD_LIB.TIMECARD(SCH_1):PAGE16

TP182 TP_PIONT-TP010CT020B030_PTH-TPA
     1 IO_L21N_16 @TIMECARD_LIB.TIMECARD(SCH_1):IO_L21N_16  I1513 @TIMECARD_LIB.TIMECARD(SCH_1):PAGE16

TP183 TP_PIONT-TP010CT020B030_PTH-TPA
     1 IO_L22P_16 @TIMECARD_LIB.TIMECARD(SCH_1):IO_L22P_16  I1505 @TIMECARD_LIB.TIMECARD(SCH_1):PAGE16

TP184 TP_PIONT-TP010CT020B030_PTH-TPA
     1 IO_L22N_16 @TIMECARD_LIB.TIMECARD(SCH_1):IO_L22N_16  I1506 @TIMECARD_LIB.TIMECARD(SCH_1):PAGE16

TP185 TP_PIONT-TP010CT020B030_PTH-TPA
     1 IO_L23P_16 @TIMECARD_LIB.TIMECARD(SCH_1):IO_L23P_16  I1507 @TIMECARD_LIB.TIMECARD(SCH_1):PAGE16

TP186 TP_PIONT-TP010CT020B030_PTH-TPA
     1 IO_L23N_16 @TIMECARD_LIB.TIMECARD(SCH_1):IO_L23N_16  I1508 @TIMECARD_LIB.TIMECARD(SCH_1):PAGE16

TP187 TP_PIONT-TP010CT020B030_PTH-TPA
     1 IO_L24P_16 @TIMECARD_LIB.TIMECARD(SCH_1):IO_L24P_16  I1509 @TIMECARD_LIB.TIMECARD(SCH_1):PAGE16

TP188 TP_PIONT-TP010CT020B030_PTH-TPA
     1 IO_L24N_16 @TIMECARD_LIB.TIMECARD(SCH_1):IO_L24N_16  I1510 @TIMECARD_LIB.TIMECARD(SCH_1):PAGE16

TP193 TP_PIONT-TP010CT020B030_PTH-TPA
     1 IO_L21P_35 @TIMECARD_LIB.TIMECARD(SCH_1):IO_L21P_35  I1487 @TIMECARD_LIB.TIMECARD(SCH_1):PAGE16

TP194 TP_PIONT-TP010CT020B030_PTH-TPA
     1 IO_L21N_35 @TIMECARD_LIB.TIMECARD(SCH_1):IO_L21N_35  I1488 @TIMECARD_LIB.TIMECARD(SCH_1):PAGE16

TP195 TP_PIONT-TP010CT020B030_PTH-TPA
     1 IO_L23P_35 @TIMECARD_LIB.TIMECARD(SCH_1):IO_L23P_35  I1489 @TIMECARD_LIB.TIMECARD(SCH_1):PAGE16

TP196 TP_PIONT-TP010CT020B030_PTH-TPA
     1 IO_L23N_35 @TIMECARD_LIB.TIMECARD(SCH_1):IO_L23N_35  I1490 @TIMECARD_LIB.TIMECARD(SCH_1):PAGE16

TP199 TP_PIONT-TP010CT020B030_PTH-TPA
     1 IO_L20P_35 @TIMECARD_LIB.TIMECARD(SCH_1):IO_L20P_35  I1527 @TIMECARD_LIB.TIMECARD(SCH_1):PAGE16

TP200 TP_PIONT-TP010CT020B030_PTH-TPA
     1 IO_L20N_35 @TIMECARD_LIB.TIMECARD(SCH_1):IO_L20N_35  I1528 @TIMECARD_LIB.TIMECARD(SCH_1):PAGE16

TP201 TP_PIONT-TP010CT020B030_PTH-TPA
     1 IO_L22P_35 @TIMECARD_LIB.TIMECARD(SCH_1):IO_L22P_35  I1529 @TIMECARD_LIB.TIMECARD(SCH_1):PAGE16

TP202 TP_PIONT-TP010CT020B030_PTH-TPA
     1 IO_L22N_35 @TIMECARD_LIB.TIMECARD(SCH_1):IO_L22N_35  I1530 @TIMECARD_LIB.TIMECARD(SCH_1):PAGE16

TP203 TP_PIONT-TP010CT020B030_PTH-TPA
     1 IO_L24P_35 @TIMECARD_LIB.TIMECARD(SCH_1):IO_L24P_35  I1523 @TIMECARD_LIB.TIMECARD(SCH_1):PAGE16

TP204 TP_PIONT-TP010CT020B030_PTH-TPA
     1 IO_L24N_35 @TIMECARD_LIB.TIMECARD(SCH_1):IO_L24N_35  I1524 @TIMECARD_LIB.TIMECARD(SCH_1):PAGE16

  U1 MP5022CGQV_Z_QFN22-G220-10510-A
     1 XP12R0V_A_EN @TIMECARD_LIB.TIMECARD(SCH_1):XP12R0V_A_EN   I212 @TIMECARD_LIB.TIMECARD(SCH_1):PAGE15
     2 UNNAMED_15_MP5022CGQVZQFN22_I_2 @TIMECARD_LIB.TIMECARD(SCH_1):UNNAMED_15_MP5022CGQVZQFN22_I212_LOADEN   I212 @TIMECARD_LIB.TIMECARD(SCH_1):PAGE15
     3 UNNAMED_15_MP5022CGQVZQFN22_I21 @TIMECARD_LIB.TIMECARD(SCH_1):UNNAMED_15_MP5022CGQVZQFN22_I212_ENTM   I212 @TIMECARD_LIB.TIMECARD(SCH_1):PAGE15
     4 XP12R0V_A_TIMER @TIMECARD_LIB.TIMECARD(SCH_1):XP12R0V_A_TIMER   I212 @TIMECARD_LIB.TIMECARD(SCH_1):PAGE15
     5 XP12R0V_A_ISET @TIMECARD_LIB.TIMECARD(SCH_1):XP12R0V_A_ISET   I212 @TIMECARD_LIB.TIMECARD(SCH_1):PAGE15
     6 XP12R0V_A_SS @TIMECARD_LIB.TIMECARD(SCH_1):XP12R0V_A_SS   I212 @TIMECARD_LIB.TIMECARD(SCH_1):PAGE15
     7     SG @TIMECARD_LIB.TIMECARD(SCH_1):SG   I212 @TIMECARD_LIB.TIMECARD(SCH_1):PAGE15
     8 XP12R0V_A_IMON @TIMECARD_LIB.TIMECARD(SCH_1):XP12R0V_A_IMON   I212 @TIMECARD_LIB.TIMECARD(SCH_1):PAGE15
     9 XP12R0V_A_FLTB @TIMECARD_LIB.TIMECARD(SCH_1):XP12R0V_A_FLTB   I212 @TIMECARD_LIB.TIMECARD(SCH_1):PAGE15
    10 XP12R0V_A_PG @TIMECARD_LIB.TIMECARD(SCH_1):XP12R0V_A_PG   I212 @TIMECARD_LIB.TIMECARD(SCH_1):PAGE15
    11 XP12R0V_A_OV @TIMECARD_LIB.TIMECARD(SCH_1):XP12R0V_A_OV   I212 @TIMECARD_LIB.TIMECARD(SCH_1):PAGE15
    12 XP12R0V_A_AVIN @TIMECARD_LIB.TIMECARD(SCH_1):XP12R0V_A_AVIN   I212 @TIMECARD_LIB.TIMECARD(SCH_1):PAGE15
    13 XP12R0V @TIMECARD_LIB.TIMECARD(SCH_1):XP12R0V   I212 @TIMECARD_LIB.TIMECARD(SCH_1):PAGE15
    14 XP12R0V @TIMECARD_LIB.TIMECARD(SCH_1):XP12R0V   I212 @TIMECARD_LIB.TIMECARD(SCH_1):PAGE15
    15 XP12R0V @TIMECARD_LIB.TIMECARD(SCH_1):XP12R0V   I212 @TIMECARD_LIB.TIMECARD(SCH_1):PAGE15
    16 XP12R0V @TIMECARD_LIB.TIMECARD(SCH_1):XP12R0V   I212 @TIMECARD_LIB.TIMECARD(SCH_1):PAGE15
    17 XP12R0V @TIMECARD_LIB.TIMECARD(SCH_1):XP12R0V   I212 @TIMECARD_LIB.TIMECARD(SCH_1):PAGE15
    18 XP12R0V @TIMECARD_LIB.TIMECARD(SCH_1):XP12R0V   I212 @TIMECARD_LIB.TIMECARD(SCH_1):PAGE15
    19 XP12R0V @TIMECARD_LIB.TIMECARD(SCH_1):XP12R0V   I212 @TIMECARD_LIB.TIMECARD(SCH_1):PAGE15
    20 XP12R0V @TIMECARD_LIB.TIMECARD(SCH_1):XP12R0V   I212 @TIMECARD_LIB.TIMECARD(SCH_1):PAGE15
    21 XP12R0V_IN @TIMECARD_LIB.TIMECARD(SCH_1):XP12R0V_IN   I212 @TIMECARD_LIB.TIMECARD(SCH_1):PAGE15
    22 XP12R0V_IN @TIMECARD_LIB.TIMECARD(SCH_1):XP12R0V_IN   I212 @TIMECARD_LIB.TIMECARD(SCH_1):PAGE15
    23 XP12R0V_IN @TIMECARD_LIB.TIMECARD(SCH_1):XP12R0V_IN   I212 @TIMECARD_LIB.TIMECARD(SCH_1):PAGE15
    24 XP12R0V_IN @TIMECARD_LIB.TIMECARD(SCH_1):XP12R0V_IN   I212 @TIMECARD_LIB.TIMECARD(SCH_1):PAGE15
    25 XP12R0V_IN @TIMECARD_LIB.TIMECARD(SCH_1):XP12R0V_IN   I212 @TIMECARD_LIB.TIMECARD(SCH_1):PAGE15
    26 XP12R0V_IN @TIMECARD_LIB.TIMECARD(SCH_1):XP12R0V_IN   I212 @TIMECARD_LIB.TIMECARD(SCH_1):PAGE15

  U2 G220_10198_01-G223-10197-01
     1 UNNAMED_3_G2201019801_I100_EN @TIMECARD_LIB.TIMECARD(SCH_1):UNNAMED_3_G2201019801_I100_EN   I100 @TIMECARD_LIB.TIMECARD(SCH_1):PAGE3
     2 PCIE_SMCLK @TIMECARD_LIB.TIMECARD(SCH_1):PCIE_SMCLK   I100 @TIMECARD_LIB.TIMECARD(SCH_1):PAGE3
     3 PCIE_CONN_SMCLK @TIMECARD_LIB.TIMECARD(SCH_1):PCIE_CONN_SMCLK   I100 @TIMECARD_LIB.TIMECARD(SCH_1):PAGE3
     4     SG @TIMECARD_LIB.TIMECARD(SCH_1):SG   I100 @TIMECARD_LIB.TIMECARD(SCH_1):PAGE3
     5     NC     NC   I100 @TIMECARD_LIB.TIMECARD(SCH_1):PAGE3
     6 PCIE_CONN_SMDAT @TIMECARD_LIB.TIMECARD(SCH_1):PCIE_CONN_SMDAT   I100 @TIMECARD_LIB.TIMECARD(SCH_1):PAGE3
     7 PCIE_SMDAT @TIMECARD_LIB.TIMECARD(SCH_1):PCIE_SMDAT   I100 @TIMECARD_LIB.TIMECARD(SCH_1):PAGE3
     8 XP3R3V_FPGA @TIMECARD_LIB.TIMECARD(SCH_1):XP3R3V_FPGA   I100 @TIMECARD_LIB.TIMECARD(SCH_1):PAGE3

  U3 74LVC1G07_SC70_5-G220-10017-01
     2 PCIE_CONN_PERST_N @TIMECARD_LIB.TIMECARD(SCH_1):PCIE_CONN_PERST_N   I134 @TIMECARD_LIB.TIMECARD(SCH_1):PAGE3
     1     NC     NC   I134 @TIMECARD_LIB.TIMECARD(SCH_1):PAGE3
     4 BF_PCIE_PERST_N @TIMECARD_LIB.TIMECARD(SCH_1):BF_PCIE_PERST_N   I134 @TIMECARD_LIB.TIMECARD(SCH_1):PAGE3
     3     SG @TIMECARD_LIB.TIMECARD(SCH_1):SG   I135 @TIMECARD_LIB.TIMECARD(SCH_1):PAGE3
     5 XP3R3V_FPGA @TIMECARD_LIB.TIMECARD(SCH_1):XP3R3V_FPGA   I135 @TIMECARD_LIB.TIMECARD(SCH_1):PAGE3

  U4 PCA9546APW_TSSOP16-G223-10280-A
     1 UNNAMED_5_PCA9546APWTSSOP16_I33 @TIMECARD_LIB.TIMECARD(SCH_1):UNNAMED_5_PCA9546APWTSSOP16_I33_A0    I33 @TIMECARD_LIB.TIMECARD(SCH_1):PAGE5
     2 UNNAMED_5_PCA9546APWTSSOP16_I_1 @TIMECARD_LIB.TIMECARD(SCH_1):UNNAMED_5_PCA9546APWTSSOP16_I33_A1    I33 @TIMECARD_LIB.TIMECARD(SCH_1):PAGE5
     3 PCA9546_RST_N @TIMECARD_LIB.TIMECARD(SCH_1):PCA9546_RST_N    I33 @TIMECARD_LIB.TIMECARD(SCH_1):PAGE5
     4 LM75B_I2C_SDA @TIMECARD_LIB.TIMECARD(SCH_1):LM75B_I2C_SDA    I33 @TIMECARD_LIB.TIMECARD(SCH_1):PAGE5
     5 LM75B_I2C_SCL @TIMECARD_LIB.TIMECARD(SCH_1):LM75B_I2C_SCL    I33 @TIMECARD_LIB.TIMECARD(SCH_1):PAGE5
     6 SHT3X_I2C_SDA @TIMECARD_LIB.TIMECARD(SCH_1):SHT3X_I2C_SDA    I33 @TIMECARD_LIB.TIMECARD(SCH_1):PAGE5
     7 SHT3X_I2C_SCL @TIMECARD_LIB.TIMECARD(SCH_1):SHT3X_I2C_SCL    I33 @TIMECARD_LIB.TIMECARD(SCH_1):PAGE5
     9 ICP10100_I2C_SDA @TIMECARD_LIB.TIMECARD(SCH_1):ICP10100_I2C_SDA    I33 @TIMECARD_LIB.TIMECARD(SCH_1):PAGE5
    10 ICP10100_I2C_SCL @TIMECARD_LIB.TIMECARD(SCH_1):ICP10100_I2C_SCL    I33 @TIMECARD_LIB.TIMECARD(SCH_1):PAGE5
    11 BNO080_I2C_SDA @TIMECARD_LIB.TIMECARD(SCH_1):BNO080_I2C_SDA    I33 @TIMECARD_LIB.TIMECARD(SCH_1):PAGE5
    12 BNO080_I2C_SCL @TIMECARD_LIB.TIMECARD(SCH_1):BNO080_I2C_SCL    I33 @TIMECARD_LIB.TIMECARD(SCH_1):PAGE5
    13 UNNAMED_5_PCA9546APWTSSOP16_I_2 @TIMECARD_LIB.TIMECARD(SCH_1):UNNAMED_5_PCA9546APWTSSOP16_I33_A2    I33 @TIMECARD_LIB.TIMECARD(SCH_1):PAGE5
    14 R_PCA9546_I2C_SCL @TIMECARD_LIB.TIMECARD(SCH_1):R_PCA9546_I2C_SCL    I33 @TIMECARD_LIB.TIMECARD(SCH_1):PAGE5
    15 R_PCA9546_I2C_SDA @TIMECARD_LIB.TIMECARD(SCH_1):R_PCA9546_I2C_SDA    I33 @TIMECARD_LIB.TIMECARD(SCH_1):PAGE5
     8     SG @TIMECARD_LIB.TIMECARD(SCH_1):SG    I54 @TIMECARD_LIB.TIMECARD(SCH_1):PAGE5
    16 VDD_PCA9546A @TIMECARD_LIB.TIMECARD(SCH_1):VDD_PCA9546A    I54 @TIMECARD_LIB.TIMECARD(SCH_1):PAGE5

  U5 TPS54824RNVR_VQFN18-G220-10657A
     1 XP5R0V_BT @TIMECARD_LIB.TIMECARD(SCH_1):XP5R0V_BT    I42 @TIMECARD_LIB.TIMECARD(SCH_1):PAGE516
     2 VIN_XP5R0V @TIMECARD_LIB.TIMECARD(SCH_1):VIN_XP5R0V    I42 @TIMECARD_LIB.TIMECARD(SCH_1):PAGE516
     3     SG @TIMECARD_LIB.TIMECARD(SCH_1):SG    I42 @TIMECARD_LIB.TIMECARD(SCH_1):PAGE516
     4     SG @TIMECARD_LIB.TIMECARD(SCH_1):SG    I42 @TIMECARD_LIB.TIMECARD(SCH_1):PAGE516
     5     SG @TIMECARD_LIB.TIMECARD(SCH_1):SG    I42 @TIMECARD_LIB.TIMECARD(SCH_1):PAGE516
     6 XP5R0V_SW @TIMECARD_LIB.TIMECARD(SCH_1):XP5R0V_SW    I42 @TIMECARD_LIB.TIMECARD(SCH_1):PAGE516
     7 XP5R0V_SW @TIMECARD_LIB.TIMECARD(SCH_1):XP5R0V_SW    I42 @TIMECARD_LIB.TIMECARD(SCH_1):PAGE516
     8     SG @TIMECARD_LIB.TIMECARD(SCH_1):SG    I42 @TIMECARD_LIB.TIMECARD(SCH_1):PAGE516
     9     SG @TIMECARD_LIB.TIMECARD(SCH_1):SG    I42 @TIMECARD_LIB.TIMECARD(SCH_1):PAGE516
    10     SG @TIMECARD_LIB.TIMECARD(SCH_1):SG    I42 @TIMECARD_LIB.TIMECARD(SCH_1):PAGE516
    11 VIN_XP5R0V @TIMECARD_LIB.TIMECARD(SCH_1):VIN_XP5R0V    I42 @TIMECARD_LIB.TIMECARD(SCH_1):PAGE516
    12 XP5R0V_AGND @TIMECARD_LIB.TIMECARD(SCH_1):XP5R0V_AGND    I42 @TIMECARD_LIB.TIMECARD(SCH_1):PAGE516
    13 XP5R0V_RT @TIMECARD_LIB.TIMECARD(SCH_1):XP5R0V_RT    I42 @TIMECARD_LIB.TIMECARD(SCH_1):PAGE516
    14 XP5R0V_FB_R_TO_AGND @TIMECARD_LIB.TIMECARD(SCH_1):XP5R0V_FB_R_TO_AGND    I42 @TIMECARD_LIB.TIMECARD(SCH_1):PAGE516
    15 XP5R0V_COMP @TIMECARD_LIB.TIMECARD(SCH_1):XP5R0V_COMP    I42 @TIMECARD_LIB.TIMECARD(SCH_1):PAGE516
    16 XP5R0V_SS @TIMECARD_LIB.TIMECARD(SCH_1):XP5R0V_SS    I42 @TIMECARD_LIB.TIMECARD(SCH_1):PAGE516
    17 R_XP5R0V_EN @TIMECARD_LIB.TIMECARD(SCH_1):R_XP5R0V_EN    I42 @TIMECARD_LIB.TIMECARD(SCH_1):PAGE516
    18 XP5R0V_PG @TIMECARD_LIB.TIMECARD(SCH_1):XP5R0V_PG    I42 @TIMECARD_LIB.TIMECARD(SCH_1):PAGE516

  U6 TPS54824RNVR_VQFN18-G220-10657A
     1 XP3R3V_BT @TIMECARD_LIB.TIMECARD(SCH_1):XP3R3V_BT    I42 @TIMECARD_LIB.TIMECARD(SCH_1):PAGE517
     2 VIN_XP3R3 @TIMECARD_LIB.TIMECARD(SCH_1):VIN_XP3R3    I42 @TIMECARD_LIB.TIMECARD(SCH_1):PAGE517
     3     SG @TIMECARD_LIB.TIMECARD(SCH_1):SG    I42 @TIMECARD_LIB.TIMECARD(SCH_1):PAGE517
     4     SG @TIMECARD_LIB.TIMECARD(SCH_1):SG    I42 @TIMECARD_LIB.TIMECARD(SCH_1):PAGE517
     5     SG @TIMECARD_LIB.TIMECARD(SCH_1):SG    I42 @TIMECARD_LIB.TIMECARD(SCH_1):PAGE517
     6 XP3R3V_SW @TIMECARD_LIB.TIMECARD(SCH_1):XP3R3V_SW    I42 @TIMECARD_LIB.TIMECARD(SCH_1):PAGE517
     7 XP3R3V_SW @TIMECARD_LIB.TIMECARD(SCH_1):XP3R3V_SW    I42 @TIMECARD_LIB.TIMECARD(SCH_1):PAGE517
     8     SG @TIMECARD_LIB.TIMECARD(SCH_1):SG    I42 @TIMECARD_LIB.TIMECARD(SCH_1):PAGE517
     9     SG @TIMECARD_LIB.TIMECARD(SCH_1):SG    I42 @TIMECARD_LIB.TIMECARD(SCH_1):PAGE517
    10     SG @TIMECARD_LIB.TIMECARD(SCH_1):SG    I42 @TIMECARD_LIB.TIMECARD(SCH_1):PAGE517
    11 VIN_XP3R3 @TIMECARD_LIB.TIMECARD(SCH_1):VIN_XP3R3    I42 @TIMECARD_LIB.TIMECARD(SCH_1):PAGE517
    12 XP3R3V_AGND @TIMECARD_LIB.TIMECARD(SCH_1):XP3R3V_AGND    I42 @TIMECARD_LIB.TIMECARD(SCH_1):PAGE517
    13 XP3R3V_RT @TIMECARD_LIB.TIMECARD(SCH_1):XP3R3V_RT    I42 @TIMECARD_LIB.TIMECARD(SCH_1):PAGE517
    14 XP3R3V_FB_R_TO_AGND @TIMECARD_LIB.TIMECARD(SCH_1):XP3R3V_FB_R_TO_AGND    I42 @TIMECARD_LIB.TIMECARD(SCH_1):PAGE517
    15 XP3R3V_COMP @TIMECARD_LIB.TIMECARD(SCH_1):XP3R3V_COMP    I42 @TIMECARD_LIB.TIMECARD(SCH_1):PAGE517
    16 XP3R3V_SS @TIMECARD_LIB.TIMECARD(SCH_1):XP3R3V_SS    I42 @TIMECARD_LIB.TIMECARD(SCH_1):PAGE517
    17 XP3R3V_EN @TIMECARD_LIB.TIMECARD(SCH_1):XP3R3V_EN    I42 @TIMECARD_LIB.TIMECARD(SCH_1):PAGE517
    18 R_XP3R3V_PG @TIMECARD_LIB.TIMECARD(SCH_1):R_XP3R3V_PG    I42 @TIMECARD_LIB.TIMECARD(SCH_1):PAGE517

  U7 AT24MAC402_SOT23_5-A221-00002-A
     1 EEPROM_SCL @TIMECARD_LIB.TIMECARD(SCH_1):EEPROM_SCL    I89 @TIMECARD_LIB.TIMECARD(SCH_1):PAGE5
     2     SG @TIMECARD_LIB.TIMECARD(SCH_1):SG    I89 @TIMECARD_LIB.TIMECARD(SCH_1):PAGE5
     3 PRI_EEPROM_SDA @TIMECARD_LIB.TIMECARD(SCH_1):PRI_EEPROM_SDA    I89 @TIMECARD_LIB.TIMECARD(SCH_1):PAGE5
     4 XP3R3V_FPGA @TIMECARD_LIB.TIMECARD(SCH_1):XP3R3V_FPGA    I89 @TIMECARD_LIB.TIMECARD(SCH_1):PAGE5
     5 SN_EEPROM_WP @TIMECARD_LIB.TIMECARD(SCH_1):SN_EEPROM_WP    I89 @TIMECARD_LIB.TIMECARD(SCH_1):PAGE5

  U8 LM75BDP_TSSOP8-G220-10215-01
     1 R_LM75B_1_I2C_SDA @TIMECARD_LIB.TIMECARD(SCH_1):R_LM75B_1_I2C_SDA    I34 @TIMECARD_LIB.TIMECARD(SCH_1):PAGE6
     2 LM75B_I2C_SCL @TIMECARD_LIB.TIMECARD(SCH_1):LM75B_I2C_SCL    I34 @TIMECARD_LIB.TIMECARD(SCH_1):PAGE6
     3 FPGA_IN_LM75B_INT1_N @TIMECARD_LIB.TIMECARD(SCH_1):FPGA_IN_LM75B_INT1_N    I34 @TIMECARD_LIB.TIMECARD(SCH_1):PAGE6
     5 UNNAMED_6_LM75BDPTSSOP8_I34_A2 @TIMECARD_LIB.TIMECARD(SCH_1):UNNAMED_6_LM75BDPTSSOP8_I34_A2    I34 @TIMECARD_LIB.TIMECARD(SCH_1):PAGE6
     6 UNNAMED_6_LM75BDPTSSOP8_I34_A1 @TIMECARD_LIB.TIMECARD(SCH_1):UNNAMED_6_LM75BDPTSSOP8_I34_A1    I34 @TIMECARD_LIB.TIMECARD(SCH_1):PAGE6
     7 UNNAMED_6_LM75BDPTSSOP8_I34_A0 @TIMECARD_LIB.TIMECARD(SCH_1):UNNAMED_6_LM75BDPTSSOP8_I34_A0    I34 @TIMECARD_LIB.TIMECARD(SCH_1):PAGE6
     8 XP3R3V_FPGA @TIMECARD_LIB.TIMECARD(SCH_1):XP3R3V_FPGA    I38 @TIMECARD_LIB.TIMECARD(SCH_1):PAGE6
     4     SG @TIMECARD_LIB.TIMECARD(SCH_1):SG    I38 @TIMECARD_LIB.TIMECARD(SCH_1):PAGE6

  U9 CL1001485A-G122-00019-01
     1     NC     NC     I4 @TIMECARD_LIB.TIMECARD(SCH_1):PAGE527
     2     SG @TIMECARD_LIB.TIMECARD(SCH_1):SG     I4 @TIMECARD_LIB.TIMECARD(SCH_1):PAGE527
     3     NC     NC     I4 @TIMECARD_LIB.TIMECARD(SCH_1):PAGE527
     4 CONN_MICRO_USB_DM @TIMECARD_LIB.TIMECARD(SCH_1):CONN_MICRO_USB_DM     I4 @TIMECARD_LIB.TIMECARD(SCH_1):PAGE527
     5 XP5R0V_USB_CONN @TIMECARD_LIB.TIMECARD(SCH_1):XP5R0V_USB_CONN     I4 @TIMECARD_LIB.TIMECARD(SCH_1):PAGE527
     6 CONN_MICRO_USB_DP @TIMECARD_LIB.TIMECARD(SCH_1):CONN_MICRO_USB_DP     I4 @TIMECARD_LIB.TIMECARD(SCH_1):PAGE527

 U10 CL5003148A-G220-10019-01
     1 FPGA_OUT_MACUSBPOWER_EN @TIMECARD_LIB.TIMECARD(SCH_1):FPGA_OUT_MACUSBPOWER_EN   I147 @TIMECARD_LIB.TIMECARD(SCH_1):PAGE527
     2 XP5R0V_USB_CONN_DET @TIMECARD_LIB.TIMECARD(SCH_1):XP5R0V_USB_CONN_DET   I147 @TIMECARD_LIB.TIMECARD(SCH_1):PAGE527
     4 USB_PWR_EN @TIMECARD_LIB.TIMECARD(SCH_1):USB_PWR_EN   I147 @TIMECARD_LIB.TIMECARD(SCH_1):PAGE527
     3     SG @TIMECARD_LIB.TIMECARD(SCH_1):SG   I146 @TIMECARD_LIB.TIMECARD(SCH_1):PAGE527
     5 XP3R3V_FPGA @TIMECARD_LIB.TIMECARD(SCH_1):XP3R3V_FPGA   I146 @TIMECARD_LIB.TIMECARD(SCH_1):PAGE527

 U11 TS3USB3031RMGR_WQFN12-G220-103A
    12 XP3R3V_FPGA @TIMECARD_LIB.TIMECARD(SCH_1):XP3R3V_FPGA   I108 @TIMECARD_LIB.TIMECARD(SCH_1):PAGE527
    11 MUX_USB_DP @TIMECARD_LIB.TIMECARD(SCH_1):MUX_USB_DP   I108 @TIMECARD_LIB.TIMECARD(SCH_1):PAGE527
    10 MUX_USB_DM @TIMECARD_LIB.TIMECARD(SCH_1):MUX_USB_DM   I108 @TIMECARD_LIB.TIMECARD(SCH_1):PAGE527
     1 XP5R0V_USB_CONN_DET @TIMECARD_LIB.TIMECARD(SCH_1):XP5R0V_USB_CONN_DET   I108 @TIMECARD_LIB.TIMECARD(SCH_1):PAGE527
     2 UNNAMED_527_RESISTOR_I126_1 @TIMECARD_LIB.TIMECARD(SCH_1):UNNAMED_527_RESISTOR_I126_1   I108 @TIMECARD_LIB.TIMECARD(SCH_1):PAGE527
     3 MAC_USB_DP @TIMECARD_LIB.TIMECARD(SCH_1):MAC_USB_DP   I108 @TIMECARD_LIB.TIMECARD(SCH_1):PAGE527
     4 MAC_USB_DM @TIMECARD_LIB.TIMECARD(SCH_1):MAC_USB_DM   I108 @TIMECARD_LIB.TIMECARD(SCH_1):PAGE527
     5 CONN_MICRO_USB_DP @TIMECARD_LIB.TIMECARD(SCH_1):CONN_MICRO_USB_DP   I108 @TIMECARD_LIB.TIMECARD(SCH_1):PAGE527
     6 CONN_MICRO_USB_DM @TIMECARD_LIB.TIMECARD(SCH_1):CONN_MICRO_USB_DM   I108 @TIMECARD_LIB.TIMECARD(SCH_1):PAGE527
     7     NC     NC   I108 @TIMECARD_LIB.TIMECARD(SCH_1):PAGE527
     8     NC     NC   I108 @TIMECARD_LIB.TIMECARD(SCH_1):PAGE527
     9     SG @TIMECARD_LIB.TIMECARD(SCH_1):SG   I108 @TIMECARD_LIB.TIMECARD(SCH_1):PAGE527

 U12 TPS2051BDBVT_SOT23_5-G220-1033A
     1 XP5R0V_MAC_USB @TIMECARD_LIB.TIMECARD(SCH_1):XP5R0V_MAC_USB    I79 @TIMECARD_LIB.TIMECARD(SCH_1):PAGE527
     3 UNNAMED_527_RESISTOR_I206_1 @TIMECARD_LIB.TIMECARD(SCH_1):UNNAMED_527_RESISTOR_I206_1    I79 @TIMECARD_LIB.TIMECARD(SCH_1):PAGE527
     5 XP5R0V_MAC @TIMECARD_LIB.TIMECARD(SCH_1):XP5R0V_MAC    I79 @TIMECARD_LIB.TIMECARD(SCH_1):PAGE527
     4 USB_PWR_EN @TIMECARD_LIB.TIMECARD(SCH_1):USB_PWR_EN    I79 @TIMECARD_LIB.TIMECARD(SCH_1):PAGE527
     2     SG @TIMECARD_LIB.TIMECARD(SCH_1):SG    I78 @TIMECARD_LIB.TIMECARD(SCH_1):PAGE527

 U13 74HCT2G125DP_TSSOP8-G220-00055A
     1 SMA3_SIG_OUT_BF_EN_N @TIMECARD_LIB.TIMECARD(SCH_1):SMA3_SIG_OUT_BF_EN_N   I204 @TIMECARD_LIB.TIMECARD(SCH_1):PAGE12
     2 UNNAMED_12_74HCT2G125DPTSSOP8_I @TIMECARD_LIB.TIMECARD(SCH_1):UNNAMED_12_74HCT2G125DPTSSOP8_I204_1A   I204 @TIMECARD_LIB.TIMECARD(SCH_1):PAGE12
     3 BF_ANT3_IN @TIMECARD_LIB.TIMECARD(SCH_1):BF_ANT3_IN   I204 @TIMECARD_LIB.TIMECARD(SCH_1):PAGE12
     4     SG @TIMECARD_LIB.TIMECARD(SCH_1):SG   I204 @TIMECARD_LIB.TIMECARD(SCH_1):PAGE12
     5 BF_SMA3_SIG_IO_CONN @TIMECARD_LIB.TIMECARD(SCH_1):BF_SMA3_SIG_IO_CONN   I204 @TIMECARD_LIB.TIMECARD(SCH_1):PAGE12
     6 BF_SMA3_SIG_IO_CONN @TIMECARD_LIB.TIMECARD(SCH_1):BF_SMA3_SIG_IO_CONN   I204 @TIMECARD_LIB.TIMECARD(SCH_1):PAGE12
     7 SMA3_SIG_IN_BF_EN_N @TIMECARD_LIB.TIMECARD(SCH_1):SMA3_SIG_IN_BF_EN_N   I204 @TIMECARD_LIB.TIMECARD(SCH_1):PAGE12
     8 XP3R3V_FPGA @TIMECARD_LIB.TIMECARD(SCH_1):XP3R3V_FPGA   I204 @TIMECARD_LIB.TIMECARD(SCH_1):PAGE12

 U14 74HCT2G125DP_TSSOP8-G220-00055A
     1 SMA4_SIG_OUT_BF_EN_N @TIMECARD_LIB.TIMECARD(SCH_1):SMA4_SIG_OUT_BF_EN_N   I226 @TIMECARD_LIB.TIMECARD(SCH_1):PAGE12
     2 UNNAMED_12_74HCT2G125DPTSSOP8_3 @TIMECARD_LIB.TIMECARD(SCH_1):UNNAMED_12_74HCT2G125DPTSSOP8_I226_1A   I226 @TIMECARD_LIB.TIMECARD(SCH_1):PAGE12
     3 BF_ANT4_IN @TIMECARD_LIB.TIMECARD(SCH_1):BF_ANT4_IN   I226 @TIMECARD_LIB.TIMECARD(SCH_1):PAGE12
     4     SG @TIMECARD_LIB.TIMECARD(SCH_1):SG   I226 @TIMECARD_LIB.TIMECARD(SCH_1):PAGE12
     5 BF_SMA4_SIG_IO_CONN @TIMECARD_LIB.TIMECARD(SCH_1):BF_SMA4_SIG_IO_CONN   I226 @TIMECARD_LIB.TIMECARD(SCH_1):PAGE12
     6 BF_SMA4_SIG_IO_CONN @TIMECARD_LIB.TIMECARD(SCH_1):BF_SMA4_SIG_IO_CONN   I226 @TIMECARD_LIB.TIMECARD(SCH_1):PAGE12
     7 SMA4_SIG_IN_BF_EN_N @TIMECARD_LIB.TIMECARD(SCH_1):SMA4_SIG_IN_BF_EN_N   I226 @TIMECARD_LIB.TIMECARD(SCH_1):PAGE12
     8 XP3R3V_FPGA @TIMECARD_LIB.TIMECARD(SCH_1):XP3R3V_FPGA   I226 @TIMECARD_LIB.TIMECARD(SCH_1):PAGE12

 U15 74HCT2G125DP_TSSOP8-G220-00055A
     1 SMA1_SIG_OUT_BF_EN_N @TIMECARD_LIB.TIMECARD(SCH_1):SMA1_SIG_OUT_BF_EN_N   I255 @TIMECARD_LIB.TIMECARD(SCH_1):PAGE12
     2 UNNAMED_12_74HCT2G125DPTSSOP8_6 @TIMECARD_LIB.TIMECARD(SCH_1):UNNAMED_12_74HCT2G125DPTSSOP8_I255_1A   I255 @TIMECARD_LIB.TIMECARD(SCH_1):PAGE12
     3 BF_ANT1_IN @TIMECARD_LIB.TIMECARD(SCH_1):BF_ANT1_IN   I255 @TIMECARD_LIB.TIMECARD(SCH_1):PAGE12
     4     SG @TIMECARD_LIB.TIMECARD(SCH_1):SG   I255 @TIMECARD_LIB.TIMECARD(SCH_1):PAGE12
     5 BF_SMA1_SIG_IO_CONN @TIMECARD_LIB.TIMECARD(SCH_1):BF_SMA1_SIG_IO_CONN   I255 @TIMECARD_LIB.TIMECARD(SCH_1):PAGE12
     6 BF_SMA1_SIG_IO_CONN @TIMECARD_LIB.TIMECARD(SCH_1):BF_SMA1_SIG_IO_CONN   I255 @TIMECARD_LIB.TIMECARD(SCH_1):PAGE12
     7 SMA1_SIG_IN_BF_EN_N @TIMECARD_LIB.TIMECARD(SCH_1):SMA1_SIG_IN_BF_EN_N   I255 @TIMECARD_LIB.TIMECARD(SCH_1):PAGE12
     8 XP3R3V_FPGA @TIMECARD_LIB.TIMECARD(SCH_1):XP3R3V_FPGA   I255 @TIMECARD_LIB.TIMECARD(SCH_1):PAGE12

 U16 74HCT2G125DP_TSSOP8-G220-00055A
     1 SMA2_SIG_OUT_BF_EN_N @TIMECARD_LIB.TIMECARD(SCH_1):SMA2_SIG_OUT_BF_EN_N   I273 @TIMECARD_LIB.TIMECARD(SCH_1):PAGE12
     2 UNNAMED_12_74HCT2G125DPTSSOP8_9 @TIMECARD_LIB.TIMECARD(SCH_1):UNNAMED_12_74HCT2G125DPTSSOP8_I273_1A   I273 @TIMECARD_LIB.TIMECARD(SCH_1):PAGE12
     3 BF_ANT2_IN @TIMECARD_LIB.TIMECARD(SCH_1):BF_ANT2_IN   I273 @TIMECARD_LIB.TIMECARD(SCH_1):PAGE12
     4     SG @TIMECARD_LIB.TIMECARD(SCH_1):SG   I273 @TIMECARD_LIB.TIMECARD(SCH_1):PAGE12
     5 BF_SMA2_SIG_IO_CONN @TIMECARD_LIB.TIMECARD(SCH_1):BF_SMA2_SIG_IO_CONN   I273 @TIMECARD_LIB.TIMECARD(SCH_1):PAGE12
     6 BF_SMA2_SIG_IO_CONN @TIMECARD_LIB.TIMECARD(SCH_1):BF_SMA2_SIG_IO_CONN   I273 @TIMECARD_LIB.TIMECARD(SCH_1):PAGE12
     7 SMA2_SIG_IN_BF_EN_N @TIMECARD_LIB.TIMECARD(SCH_1):SMA2_SIG_IN_BF_EN_N   I273 @TIMECARD_LIB.TIMECARD(SCH_1):PAGE12
     8 XP3R3V_FPGA @TIMECARD_LIB.TIMECARD(SCH_1):XP3R3V_FPGA   I273 @TIMECARD_LIB.TIMECARD(SCH_1):PAGE12

 U17 CL1001485A-G122-00019-01
     1     NC     NC     I3 @TIMECARD_LIB.TIMECARD(SCH_1):PAGE524
     2     SG @TIMECARD_LIB.TIMECARD(SCH_1):SG     I3 @TIMECARD_LIB.TIMECARD(SCH_1):PAGE524
     3     NC     NC     I3 @TIMECARD_LIB.TIMECARD(SCH_1):PAGE524
     4 FT_USB_DM @TIMECARD_LIB.TIMECARD(SCH_1):FT_USB_DM     I3 @TIMECARD_LIB.TIMECARD(SCH_1):PAGE524
     5 XP5R0V_FT4232 @TIMECARD_LIB.TIMECARD(SCH_1):XP5R0V_FT4232     I3 @TIMECARD_LIB.TIMECARD(SCH_1):PAGE524
     6 FT_USB_DP @TIMECARD_LIB.TIMECARD(SCH_1):FT_USB_DP     I3 @TIMECARD_LIB.TIMECARD(SCH_1):PAGE524

 U18 FT4232HL_REEL_QFP64-G223-10282A
    16 R_FT4232_TCK @TIMECARD_LIB.TIMECARD(SCH_1):R_FT4232_TCK    I64 @TIMECARD_LIB.TIMECARD(SCH_1):PAGE524
    17 R_FT4232_TDI @TIMECARD_LIB.TIMECARD(SCH_1):R_FT4232_TDI    I64 @TIMECARD_LIB.TIMECARD(SCH_1):PAGE524
    18 R_FT4232_TDO @TIMECARD_LIB.TIMECARD(SCH_1):R_FT4232_TDO    I64 @TIMECARD_LIB.TIMECARD(SCH_1):PAGE524
    19 R_FT4232_TMS @TIMECARD_LIB.TIMECARD(SCH_1):R_FT4232_TMS    I64 @TIMECARD_LIB.TIMECARD(SCH_1):PAGE524
    21 FT4232_MUX1_SEL @TIMECARD_LIB.TIMECARD(SCH_1):FT4232_MUX1_SEL    I64 @TIMECARD_LIB.TIMECARD(SCH_1):PAGE524
    22 FT4232_MUX2_SEL @TIMECARD_LIB.TIMECARD(SCH_1):FT4232_MUX2_SEL    I64 @TIMECARD_LIB.TIMECARD(SCH_1):PAGE524
    23 FT4232_MUX3_SEL @TIMECARD_LIB.TIMECARD(SCH_1):FT4232_MUX3_SEL    I64 @TIMECARD_LIB.TIMECARD(SCH_1):PAGE524
    24 UNNAMED_524_FT4232HLREELQFP64_I @TIMECARD_LIB.TIMECARD(SCH_1):UNNAMED_524_FT4232HLREELQFP64_I64_ADBUS7    I64 @TIMECARD_LIB.TIMECARD(SCH_1):PAGE524
    26 R_FT4232_I2C_SCL @TIMECARD_LIB.TIMECARD(SCH_1):R_FT4232_I2C_SCL    I64 @TIMECARD_LIB.TIMECARD(SCH_1):PAGE524
    27 R_FT4232_I2C_SDA_OUT @TIMECARD_LIB.TIMECARD(SCH_1):R_FT4232_I2C_SDA_OUT    I64 @TIMECARD_LIB.TIMECARD(SCH_1):PAGE524
    28 R_FT4232_I2C_SDA_IN @TIMECARD_LIB.TIMECARD(SCH_1):R_FT4232_I2C_SDA_IN    I64 @TIMECARD_LIB.TIMECARD(SCH_1):PAGE524
    29 UNNAMED_524_FT4232HLREELQFP64_1 @TIMECARD_LIB.TIMECARD(SCH_1):UNNAMED_524_FT4232HLREELQFP64_I64_BDBUS3    I64 @TIMECARD_LIB.TIMECARD(SCH_1):PAGE524
    30 UNNAMED_524_FT4232HLREELQFP64_2 @TIMECARD_LIB.TIMECARD(SCH_1):UNNAMED_524_FT4232HLREELQFP64_I64_BDBUS4    I64 @TIMECARD_LIB.TIMECARD(SCH_1):PAGE524
    32 UNNAMED_524_FT4232HLREELQFP64_3 @TIMECARD_LIB.TIMECARD(SCH_1):UNNAMED_524_FT4232HLREELQFP64_I64_BDBUS5    I64 @TIMECARD_LIB.TIMECARD(SCH_1):PAGE524
    33 UNNAMED_524_FT4232HLREELQFP64_4 @TIMECARD_LIB.TIMECARD(SCH_1):UNNAMED_524_FT4232HLREELQFP64_I64_BDBUS6    I64 @TIMECARD_LIB.TIMECARD(SCH_1):PAGE524
    34 UNNAMED_524_FT4232HLREELQFP64_5 @TIMECARD_LIB.TIMECARD(SCH_1):UNNAMED_524_FT4232HLREELQFP64_I64_BDBUS7    I64 @TIMECARD_LIB.TIMECARD(SCH_1):PAGE524
    38 R_FT4232_CHC_TX @TIMECARD_LIB.TIMECARD(SCH_1):R_FT4232_CHC_TX    I64 @TIMECARD_LIB.TIMECARD(SCH_1):PAGE524
    39 R_FT4232_CHC_RX @TIMECARD_LIB.TIMECARD(SCH_1):R_FT4232_CHC_RX    I64 @TIMECARD_LIB.TIMECARD(SCH_1):PAGE524
    40     NC     NC    I64 @TIMECARD_LIB.TIMECARD(SCH_1):PAGE524
    41     NC     NC    I64 @TIMECARD_LIB.TIMECARD(SCH_1):PAGE524
    43     NC     NC    I64 @TIMECARD_LIB.TIMECARD(SCH_1):PAGE524
    44     NC     NC    I64 @TIMECARD_LIB.TIMECARD(SCH_1):PAGE524
    45     NC     NC    I64 @TIMECARD_LIB.TIMECARD(SCH_1):PAGE524
    46     NC     NC    I64 @TIMECARD_LIB.TIMECARD(SCH_1):PAGE524
    48 R_FT4232_CHD_TX @TIMECARD_LIB.TIMECARD(SCH_1):R_FT4232_CHD_TX    I64 @TIMECARD_LIB.TIMECARD(SCH_1):PAGE524
    52 R_FT4232_CHD_RX @TIMECARD_LIB.TIMECARD(SCH_1):R_FT4232_CHD_RX    I64 @TIMECARD_LIB.TIMECARD(SCH_1):PAGE524
    53     NC     NC    I64 @TIMECARD_LIB.TIMECARD(SCH_1):PAGE524
    54     NC     NC    I64 @TIMECARD_LIB.TIMECARD(SCH_1):PAGE524
    55     NC     NC    I64 @TIMECARD_LIB.TIMECARD(SCH_1):PAGE524
    57     NC     NC    I64 @TIMECARD_LIB.TIMECARD(SCH_1):PAGE524
    58     NC     NC    I64 @TIMECARD_LIB.TIMECARD(SCH_1):PAGE524
    59     NC     NC    I64 @TIMECARD_LIB.TIMECARD(SCH_1):PAGE524
    60     NC     NC    I64 @TIMECARD_LIB.TIMECARD(SCH_1):PAGE524
    36     NC     NC    I64 @TIMECARD_LIB.TIMECARD(SCH_1):PAGE524
    50 XP3R3V_FT4232 @TIMECARD_LIB.TIMECARD(SCH_1):XP3R3V_FT4232    I64 @TIMECARD_LIB.TIMECARD(SCH_1):PAGE524
    49 FT4232_VREGOUT @TIMECARD_LIB.TIMECARD(SCH_1):FT4232_VREGOUT    I64 @TIMECARD_LIB.TIMECARD(SCH_1):PAGE524
    56 XP3R3V_FT4232 @TIMECARD_LIB.TIMECARD(SCH_1):XP3R3V_FT4232    I64 @TIMECARD_LIB.TIMECARD(SCH_1):PAGE524
    42 XP3R3V_FT4232 @TIMECARD_LIB.TIMECARD(SCH_1):XP3R3V_FT4232    I64 @TIMECARD_LIB.TIMECARD(SCH_1):PAGE524
    31 XP3R3V_FT4232 @TIMECARD_LIB.TIMECARD(SCH_1):XP3R3V_FT4232    I64 @TIMECARD_LIB.TIMECARD(SCH_1):PAGE524
    20 XP3R3V_FT4232 @TIMECARD_LIB.TIMECARD(SCH_1):XP3R3V_FT4232    I64 @TIMECARD_LIB.TIMECARD(SCH_1):PAGE524
    64 FT4232_VREGOUT @TIMECARD_LIB.TIMECARD(SCH_1):FT4232_VREGOUT    I64 @TIMECARD_LIB.TIMECARD(SCH_1):PAGE524
    37 FT4232_VREGOUT @TIMECARD_LIB.TIMECARD(SCH_1):FT4232_VREGOUT    I64 @TIMECARD_LIB.TIMECARD(SCH_1):PAGE524
    12 FT4232_VREGOUT @TIMECARD_LIB.TIMECARD(SCH_1):FT4232_VREGOUT    I64 @TIMECARD_LIB.TIMECARD(SCH_1):PAGE524
     9 XP3R3V_VPLL @TIMECARD_LIB.TIMECARD(SCH_1):XP3R3V_VPLL    I64 @TIMECARD_LIB.TIMECARD(SCH_1):PAGE524
     4 XP3R3V_VPHY @TIMECARD_LIB.TIMECARD(SCH_1):XP3R3V_VPHY    I64 @TIMECARD_LIB.TIMECARD(SCH_1):PAGE524
    10     SG @TIMECARD_LIB.TIMECARD(SCH_1):SG    I64 @TIMECARD_LIB.TIMECARD(SCH_1):PAGE524
    51     SG @TIMECARD_LIB.TIMECARD(SCH_1):SG    I64 @TIMECARD_LIB.TIMECARD(SCH_1):PAGE524
    47     SG @TIMECARD_LIB.TIMECARD(SCH_1):SG    I64 @TIMECARD_LIB.TIMECARD(SCH_1):PAGE524
    35     SG @TIMECARD_LIB.TIMECARD(SCH_1):SG    I64 @TIMECARD_LIB.TIMECARD(SCH_1):PAGE524
    25     SG @TIMECARD_LIB.TIMECARD(SCH_1):SG    I64 @TIMECARD_LIB.TIMECARD(SCH_1):PAGE524
    15     SG @TIMECARD_LIB.TIMECARD(SCH_1):SG    I64 @TIMECARD_LIB.TIMECARD(SCH_1):PAGE524
    11     SG @TIMECARD_LIB.TIMECARD(SCH_1):SG    I64 @TIMECARD_LIB.TIMECARD(SCH_1):PAGE524
     5     SG @TIMECARD_LIB.TIMECARD(SCH_1):SG    I64 @TIMECARD_LIB.TIMECARD(SCH_1):PAGE524
     1     SG @TIMECARD_LIB.TIMECARD(SCH_1):SG    I64 @TIMECARD_LIB.TIMECARD(SCH_1):PAGE524
     7 R_FT_USB_DM @TIMECARD_LIB.TIMECARD(SCH_1):R_FT_USB_DM    I64 @TIMECARD_LIB.TIMECARD(SCH_1):PAGE524
     8 R_FT_USB_DP @TIMECARD_LIB.TIMECARD(SCH_1):R_FT_USB_DP    I64 @TIMECARD_LIB.TIMECARD(SCH_1):PAGE524
     6 UNNAMED_524_FT4232HLREELQFP64_6 @TIMECARD_LIB.TIMECARD(SCH_1):UNNAMED_524_FT4232HLREELQFP64_I64_REF    I64 @TIMECARD_LIB.TIMECARD(SCH_1):PAGE524
    14 UNNAMED_524_FT4232HLREELQFP64_7 @TIMECARD_LIB.TIMECARD(SCH_1):UNNAMED_524_FT4232HLREELQFP64_I64_RESET    I64 @TIMECARD_LIB.TIMECARD(SCH_1):PAGE524
    63 FTDI_EE_CS @TIMECARD_LIB.TIMECARD(SCH_1):FTDI_EE_CS    I64 @TIMECARD_LIB.TIMECARD(SCH_1):PAGE524
    62 FTDI_EE_CLK @TIMECARD_LIB.TIMECARD(SCH_1):FTDI_EE_CLK    I64 @TIMECARD_LIB.TIMECARD(SCH_1):PAGE524
    61 FTDI_EE_DAT @TIMECARD_LIB.TIMECARD(SCH_1):FTDI_EE_DAT    I64 @TIMECARD_LIB.TIMECARD(SCH_1):PAGE524
     2 UNNAMED_524_CAPACITOR_I7_2 @TIMECARD_LIB.TIMECARD(SCH_1):UNNAMED_524_CAPACITOR_I7_2    I64 @TIMECARD_LIB.TIMECARD(SCH_1):PAGE524
     3 UNNAMED_524_CAPACITOR_I10_2 @TIMECARD_LIB.TIMECARD(SCH_1):UNNAMED_524_CAPACITOR_I10_2    I64 @TIMECARD_LIB.TIMECARD(SCH_1):PAGE524
    13     SG @TIMECARD_LIB.TIMECARD(SCH_1):SG    I64 @TIMECARD_LIB.TIMECARD(SCH_1):PAGE524

 U19 24LC16BT_I_ST_TSSOP8-G221-1017A
     1 UNNAMED_5_24LC16BTISTTSSOP8_I15 @TIMECARD_LIB.TIMECARD(SCH_1):UNNAMED_5_24LC16BTISTTSSOP8_I151_A0   I151 @TIMECARD_LIB.TIMECARD(SCH_1):PAGE5
     2 UNNAMED_5_24LC16BTISTTSSOP8_I_1 @TIMECARD_LIB.TIMECARD(SCH_1):UNNAMED_5_24LC16BTISTTSSOP8_I151_A1   I151 @TIMECARD_LIB.TIMECARD(SCH_1):PAGE5
     3 UNNAMED_5_24LC16BTISTTSSOP8_I_2 @TIMECARD_LIB.TIMECARD(SCH_1):UNNAMED_5_24LC16BTISTTSSOP8_I151_A2   I151 @TIMECARD_LIB.TIMECARD(SCH_1):PAGE5
     7 SEC_EEPROM_WP @TIMECARD_LIB.TIMECARD(SCH_1):SEC_EEPROM_WP   I151 @TIMECARD_LIB.TIMECARD(SCH_1):PAGE5
     6 EEPROM_SCL @TIMECARD_LIB.TIMECARD(SCH_1):EEPROM_SCL   I151 @TIMECARD_LIB.TIMECARD(SCH_1):PAGE5
     5 SEC_EEPROM_SDA @TIMECARD_LIB.TIMECARD(SCH_1):SEC_EEPROM_SDA   I151 @TIMECARD_LIB.TIMECARD(SCH_1):PAGE5
     4     SG @TIMECARD_LIB.TIMECARD(SCH_1):SG   I148 @TIMECARD_LIB.TIMECARD(SCH_1):PAGE5
     8 XP3R3V_FPGA @TIMECARD_LIB.TIMECARD(SCH_1):XP3R3V_FPGA   I148 @TIMECARD_LIB.TIMECARD(SCH_1):PAGE5

 U20 ISL80101IRAJZ_DFN10-G222-10136A
     1 XP1R2V_FPGA @TIMECARD_LIB.TIMECARD(SCH_1):XP1R2V_FPGA     I6 @TIMECARD_LIB.TIMECARD(SCH_1):PAGE68
     2 XP1R2V_FPGA @TIMECARD_LIB.TIMECARD(SCH_1):XP1R2V_FPGA     I6 @TIMECARD_LIB.TIMECARD(SCH_1):PAGE68
     3 XP1R2V_FB @TIMECARD_LIB.TIMECARD(SCH_1):XP1R2V_FB     I6 @TIMECARD_LIB.TIMECARD(SCH_1):PAGE68
     4 XP1R2V_PG_R @TIMECARD_LIB.TIMECARD(SCH_1):XP1R2V_PG_R     I6 @TIMECARD_LIB.TIMECARD(SCH_1):PAGE68
     5     SG @TIMECARD_LIB.TIMECARD(SCH_1):SG     I6 @TIMECARD_LIB.TIMECARD(SCH_1):PAGE68
     6 XP1R2V_SS @TIMECARD_LIB.TIMECARD(SCH_1):XP1R2V_SS     I6 @TIMECARD_LIB.TIMECARD(SCH_1):PAGE68
     7 XP1R2V_EN_R @TIMECARD_LIB.TIMECARD(SCH_1):XP1R2V_EN_R     I6 @TIMECARD_LIB.TIMECARD(SCH_1):PAGE68
     8     NC     NC     I6 @TIMECARD_LIB.TIMECARD(SCH_1):PAGE68
     9 XP1R2V_VIN @TIMECARD_LIB.TIMECARD(SCH_1):XP1R2V_VIN     I6 @TIMECARD_LIB.TIMECARD(SCH_1):PAGE68
    10 XP1R2V_VIN @TIMECARD_LIB.TIMECARD(SCH_1):XP1R2V_VIN     I6 @TIMECARD_LIB.TIMECARD(SCH_1):PAGE68
    11     SG @TIMECARD_LIB.TIMECARD(SCH_1):SG     I6 @TIMECARD_LIB.TIMECARD(SCH_1):PAGE68

 U21 ISL80101IRAJZ_DFN10-G222-10136A
     1 XP1R8V_FPGA @TIMECARD_LIB.TIMECARD(SCH_1):XP1R8V_FPGA    I52 @TIMECARD_LIB.TIMECARD(SCH_1):PAGE68
     2 XP1R8V_FPGA @TIMECARD_LIB.TIMECARD(SCH_1):XP1R8V_FPGA    I52 @TIMECARD_LIB.TIMECARD(SCH_1):PAGE68
     3 XP1R8V_FB @TIMECARD_LIB.TIMECARD(SCH_1):XP1R8V_FB    I52 @TIMECARD_LIB.TIMECARD(SCH_1):PAGE68
     4 XP1R8V_PG_R @TIMECARD_LIB.TIMECARD(SCH_1):XP1R8V_PG_R    I52 @TIMECARD_LIB.TIMECARD(SCH_1):PAGE68
     5     SG @TIMECARD_LIB.TIMECARD(SCH_1):SG    I52 @TIMECARD_LIB.TIMECARD(SCH_1):PAGE68
     6 XP1R8V_SS @TIMECARD_LIB.TIMECARD(SCH_1):XP1R8V_SS    I52 @TIMECARD_LIB.TIMECARD(SCH_1):PAGE68
     7 XP1R8V_EN_R @TIMECARD_LIB.TIMECARD(SCH_1):XP1R8V_EN_R    I52 @TIMECARD_LIB.TIMECARD(SCH_1):PAGE68
     8     NC     NC    I52 @TIMECARD_LIB.TIMECARD(SCH_1):PAGE68
     9 XP1R8V_VIN @TIMECARD_LIB.TIMECARD(SCH_1):XP1R8V_VIN    I52 @TIMECARD_LIB.TIMECARD(SCH_1):PAGE68
    10 XP1R8V_VIN @TIMECARD_LIB.TIMECARD(SCH_1):XP1R8V_VIN    I52 @TIMECARD_LIB.TIMECARD(SCH_1):PAGE68
    11     SG @TIMECARD_LIB.TIMECARD(SCH_1):SG    I52 @TIMECARD_LIB.TIMECARD(SCH_1):PAGE68

 U22 NCP45560IMNTWG_H_DFN12-G222-10A
     1 XP3R3V @TIMECARD_LIB.TIMECARD(SCH_1):XP3R3V    I82 @TIMECARD_LIB.TIMECARD(SCH_1):PAGE515
     2 XP3R3V_FPGA_EN_R @TIMECARD_LIB.TIMECARD(SCH_1):XP3R3V_FPGA_EN_R    I82 @TIMECARD_LIB.TIMECARD(SCH_1):PAGE515
     5 XP3R3V_FPGA_SR @TIMECARD_LIB.TIMECARD(SCH_1):XP3R3V_FPGA_SR    I82 @TIMECARD_LIB.TIMECARD(SCH_1):PAGE515
     6 UNNAMED_515_NCP45560IMNTWGHDFN1 @TIMECARD_LIB.TIMECARD(SCH_1):UNNAMED_515_NCP45560IMNTWGHDFN12_I82_PG    I82 @TIMECARD_LIB.TIMECARD(SCH_1):PAGE515
     7 XP3R3V_FPGA @TIMECARD_LIB.TIMECARD(SCH_1):XP3R3V_FPGA    I82 @TIMECARD_LIB.TIMECARD(SCH_1):PAGE515
     8 XP3R3V_FPGA @TIMECARD_LIB.TIMECARD(SCH_1):XP3R3V_FPGA    I82 @TIMECARD_LIB.TIMECARD(SCH_1):PAGE515
     9 XP3R3V_FPGA @TIMECARD_LIB.TIMECARD(SCH_1):XP3R3V_FPGA    I82 @TIMECARD_LIB.TIMECARD(SCH_1):PAGE515
    10 XP3R3V_FPGA @TIMECARD_LIB.TIMECARD(SCH_1):XP3R3V_FPGA    I82 @TIMECARD_LIB.TIMECARD(SCH_1):PAGE515
    11 XP3R3V_FPGA @TIMECARD_LIB.TIMECARD(SCH_1):XP3R3V_FPGA    I82 @TIMECARD_LIB.TIMECARD(SCH_1):PAGE515
    12 XP3R3V_FPGA @TIMECARD_LIB.TIMECARD(SCH_1):XP3R3V_FPGA    I82 @TIMECARD_LIB.TIMECARD(SCH_1):PAGE515
    13 XP3R3V @TIMECARD_LIB.TIMECARD(SCH_1):XP3R3V    I82 @TIMECARD_LIB.TIMECARD(SCH_1):PAGE515
     3 XP3R3V @TIMECARD_LIB.TIMECARD(SCH_1):XP3R3V    I76 @TIMECARD_LIB.TIMECARD(SCH_1):PAGE515
     4     SG @TIMECARD_LIB.TIMECARD(SCH_1):SG    I76 @TIMECARD_LIB.TIMECARD(SCH_1):PAGE515

 U23 MT25QL128ABA1ESE_SOP8-G221-102A
     1 FLASH_CS_N @TIMECARD_LIB.TIMECARD(SCH_1):FLASH_CS_N   I456 @TIMECARD_LIB.TIMECARD(SCH_1):PAGE127
     2 UNNAMED_127_MT25QL128ABA1ESES_1 @TIMECARD_LIB.TIMECARD(SCH_1):UNNAMED_127_MT25QL128ABA1ESESOP8_I456_DQ1   I456 @TIMECARD_LIB.TIMECARD(SCH_1):PAGE127
     3 UNNAMED_127_MT25QL128ABA1ESES_3 @TIMECARD_LIB.TIMECARD(SCH_1):UNNAMED_127_MT25QL128ABA1ESESOP8_I456_W   I456 @TIMECARD_LIB.TIMECARD(SCH_1):PAGE127
     4     SG @TIMECARD_LIB.TIMECARD(SCH_1):SG   I456 @TIMECARD_LIB.TIMECARD(SCH_1):PAGE127
     5 UNNAMED_127_MT25QL128ABA1ESESOP @TIMECARD_LIB.TIMECARD(SCH_1):UNNAMED_127_MT25QL128ABA1ESESOP8_I456_DQ0   I456 @TIMECARD_LIB.TIMECARD(SCH_1):PAGE127
     6 FLASH_CLK @TIMECARD_LIB.TIMECARD(SCH_1):FLASH_CLK   I456 @TIMECARD_LIB.TIMECARD(SCH_1):PAGE127
     7 UNNAMED_127_MT25QL128ABA1ESES_2 @TIMECARD_LIB.TIMECARD(SCH_1):UNNAMED_127_MT25QL128ABA1ESESOP8_I456_HOLD   I456 @TIMECARD_LIB.TIMECARD(SCH_1):PAGE127
     8 XP3R3V_FPGA @TIMECARD_LIB.TIMECARD(SCH_1):XP3R3V_FPGA   I456 @TIMECARD_LIB.TIMECARD(SCH_1):PAGE127

 U24 XC7A200T_2FBG484C_FBG484-G240-A
   L12 CCLK_0 @TIMECARD_LIB.TIMECARD(SCH_1):CCLK_0   I232 @TIMECARD_LIB.TIMECARD(SCH_1):PAGE127
    U8 CFGBVS @TIMECARD_LIB.TIMECARD(SCH_1):CFGBVS   I232 @TIMECARD_LIB.TIMECARD(SCH_1):PAGE127
   G11 FPGA_DONE @TIMECARD_LIB.TIMECARD(SCH_1):FPGA_DONE   I232 @TIMECARD_LIB.TIMECARD(SCH_1):PAGE127
    N9     SG @TIMECARD_LIB.TIMECARD(SCH_1):SG   I232 @TIMECARD_LIB.TIMECARD(SCH_1):PAGE127
   N10     SG @TIMECARD_LIB.TIMECARD(SCH_1):SG   I232 @TIMECARD_LIB.TIMECARD(SCH_1):PAGE127
   U12 FPGA_CFG_INIT_N @TIMECARD_LIB.TIMECARD(SCH_1):FPGA_CFG_INIT_N   I232 @TIMECARD_LIB.TIMECARD(SCH_1):PAGE127
   U11 FPGA_M0 @TIMECARD_LIB.TIMECARD(SCH_1):FPGA_M0   I232 @TIMECARD_LIB.TIMECARD(SCH_1):PAGE127
   U10 FPGA_M1 @TIMECARD_LIB.TIMECARD(SCH_1):FPGA_M1   I232 @TIMECARD_LIB.TIMECARD(SCH_1):PAGE127
    U9 FPGA_M2 @TIMECARD_LIB.TIMECARD(SCH_1):FPGA_M2   I232 @TIMECARD_LIB.TIMECARD(SCH_1):PAGE127
    A8 CPU_TX_PCIE_MGT_0_RXN @TIMECARD_LIB.TIMECARD(SCH_1):CPU_TX_PCIE_MGT_0_RXN   I232 @TIMECARD_LIB.TIMECARD(SCH_1):PAGE127
   C11 CPU_TX_PCIE_MGT_1_RXN @TIMECARD_LIB.TIMECARD(SCH_1):CPU_TX_PCIE_MGT_1_RXN   I232 @TIMECARD_LIB.TIMECARD(SCH_1):PAGE127
   A10 CPU_TX_PCIE_MGT_2_RXN @TIMECARD_LIB.TIMECARD(SCH_1):CPU_TX_PCIE_MGT_2_RXN   I232 @TIMECARD_LIB.TIMECARD(SCH_1):PAGE127
    C9 CPU_TX_PCIE_MGT_3_RXN @TIMECARD_LIB.TIMECARD(SCH_1):CPU_TX_PCIE_MGT_3_RXN   I232 @TIMECARD_LIB.TIMECARD(SCH_1):PAGE127
    B8 CPU_TX_PCIE_MGT_0_RXP @TIMECARD_LIB.TIMECARD(SCH_1):CPU_TX_PCIE_MGT_0_RXP   I232 @TIMECARD_LIB.TIMECARD(SCH_1):PAGE127
   D11 CPU_TX_PCIE_MGT_1_RXP @TIMECARD_LIB.TIMECARD(SCH_1):CPU_TX_PCIE_MGT_1_RXP   I232 @TIMECARD_LIB.TIMECARD(SCH_1):PAGE127
   B10 CPU_TX_PCIE_MGT_2_RXP @TIMECARD_LIB.TIMECARD(SCH_1):CPU_TX_PCIE_MGT_2_RXP   I232 @TIMECARD_LIB.TIMECARD(SCH_1):PAGE127
    D9 CPU_TX_PCIE_MGT_3_RXP @TIMECARD_LIB.TIMECARD(SCH_1):CPU_TX_PCIE_MGT_3_RXP   I232 @TIMECARD_LIB.TIMECARD(SCH_1):PAGE127
    A4 CPU_RX_PCIE_MGT0_TXN @TIMECARD_LIB.TIMECARD(SCH_1):CPU_RX_PCIE_MGT0_TXN   I232 @TIMECARD_LIB.TIMECARD(SCH_1):PAGE127
    C5 CPU_RX_PCIE_MGT1_TXN @TIMECARD_LIB.TIMECARD(SCH_1):CPU_RX_PCIE_MGT1_TXN   I232 @TIMECARD_LIB.TIMECARD(SCH_1):PAGE127
    A6 CPU_RX_PCIE_MGT2_TXN @TIMECARD_LIB.TIMECARD(SCH_1):CPU_RX_PCIE_MGT2_TXN   I232 @TIMECARD_LIB.TIMECARD(SCH_1):PAGE127
    C7 CPU_RX_PCIE_MGT3_TXN @TIMECARD_LIB.TIMECARD(SCH_1):CPU_RX_PCIE_MGT3_TXN   I232 @TIMECARD_LIB.TIMECARD(SCH_1):PAGE127
    B4 CPU_RX_PCIE_MGT0_TXP @TIMECARD_LIB.TIMECARD(SCH_1):CPU_RX_PCIE_MGT0_TXP   I232 @TIMECARD_LIB.TIMECARD(SCH_1):PAGE127
    D5 CPU_RX_PCIE_MGT1_TXP @TIMECARD_LIB.TIMECARD(SCH_1):CPU_RX_PCIE_MGT1_TXP   I232 @TIMECARD_LIB.TIMECARD(SCH_1):PAGE127
    B6 CPU_RX_PCIE_MGT2_TXP @TIMECARD_LIB.TIMECARD(SCH_1):CPU_RX_PCIE_MGT2_TXP   I232 @TIMECARD_LIB.TIMECARD(SCH_1):PAGE127
    D7 CPU_RX_PCIE_MGT3_TXP @TIMECARD_LIB.TIMECARD(SCH_1):CPU_RX_PCIE_MGT3_TXP   I232 @TIMECARD_LIB.TIMECARD(SCH_1):PAGE127
    E6 MHZ125CLKN_CLKIN @TIMECARD_LIB.TIMECARD(SCH_1):MHZ125CLKN_CLKIN   I232 @TIMECARD_LIB.TIMECARD(SCH_1):PAGE127
    F6 MHZ125CLKP_CLKIN @TIMECARD_LIB.TIMECARD(SCH_1):MHZ125CLKP_CLKIN   I232 @TIMECARD_LIB.TIMECARD(SCH_1):PAGE127
   E10 PCIE_REFCLKN @TIMECARD_LIB.TIMECARD(SCH_1):PCIE_REFCLKN   I232 @TIMECARD_LIB.TIMECARD(SCH_1):PAGE127
   F10 PCIE_REFCLKP @TIMECARD_LIB.TIMECARD(SCH_1):PCIE_REFCLKP   I232 @TIMECARD_LIB.TIMECARD(SCH_1):PAGE127
    F8 FPGA_MGTRREF @TIMECARD_LIB.TIMECARD(SCH_1):FPGA_MGTRREF   I232 @TIMECARD_LIB.TIMECARD(SCH_1):PAGE127
   N12 FPGA_PROGRAM_N @TIMECARD_LIB.TIMECARD(SCH_1):FPGA_PROGRAM_N   I232 @TIMECARD_LIB.TIMECARD(SCH_1):PAGE127
   V12 FPGA_TCK @TIMECARD_LIB.TIMECARD(SCH_1):FPGA_TCK   I232 @TIMECARD_LIB.TIMECARD(SCH_1):PAGE127
   R13 FPGA_TDI @TIMECARD_LIB.TIMECARD(SCH_1):FPGA_TDI   I232 @TIMECARD_LIB.TIMECARD(SCH_1):PAGE127
   U13 R_FPGA_TDO @TIMECARD_LIB.TIMECARD(SCH_1):R_FPGA_TDO   I232 @TIMECARD_LIB.TIMECARD(SCH_1):PAGE127
   T13 FPGA_TMS @TIMECARD_LIB.TIMECARD(SCH_1):FPGA_TMS   I232 @TIMECARD_LIB.TIMECARD(SCH_1):PAGE127
    M9     SG @TIMECARD_LIB.TIMECARD(SCH_1):SG   I232 @TIMECARD_LIB.TIMECARD(SCH_1):PAGE127
   L10     SG @TIMECARD_LIB.TIMECARD(SCH_1):SG   I232 @TIMECARD_LIB.TIMECARD(SCH_1):PAGE127
    L9     SG @TIMECARD_LIB.TIMECARD(SCH_1):SG   I232 @TIMECARD_LIB.TIMECARD(SCH_1):PAGE127
   M10     SG @TIMECARD_LIB.TIMECARD(SCH_1):SG   I232 @TIMECARD_LIB.TIMECARD(SCH_1):PAGE127
   Y17     NC     NC     I2 @TIMECARD_LIB.TIMECARD(SCH_1):PAGE161
   P20 UART_GPS_RX_FPGA_TX @TIMECARD_LIB.TIMECARD(SCH_1):UART_GPS_RX_FPGA_TX     I2 @TIMECARD_LIB.TIMECARD(SCH_1):PAGE161
   N15 UART_GPS_TX_FPGA_RX @TIMECARD_LIB.TIMECARD(SCH_1):UART_GPS_TX_FPGA_RX     I2 @TIMECARD_LIB.TIMECARD(SCH_1):PAGE161
  AA16     NC     NC     I2 @TIMECARD_LIB.TIMECARD(SCH_1):PAGE161
   R22 FPGA_D01 @TIMECARD_LIB.TIMECARD(SCH_1):FPGA_D01     I2 @TIMECARD_LIB.TIMECARD(SCH_1):PAGE161
   Y16 FPGA_OUT_GPS_RST_N @TIMECARD_LIB.TIMECARD(SCH_1):FPGA_OUT_GPS_RST_N     I2 @TIMECARD_LIB.TIMECARD(SCH_1):PAGE161
   P22 FPGA_D00_MOSI @TIMECARD_LIB.TIMECARD(SCH_1):FPGA_D00_MOSI     I2 @TIMECARD_LIB.TIMECARD(SCH_1):PAGE161
  AB17 FPGA_EEPROM_I2C_SDA @TIMECARD_LIB.TIMECARD(SCH_1):FPGA_EEPROM_I2C_SDA     I2 @TIMECARD_LIB.TIMECARD(SCH_1):PAGE161
   R21 FPGA_D03 @TIMECARD_LIB.TIMECARD(SCH_1):FPGA_D03     I2 @TIMECARD_LIB.TIMECARD(SCH_1):PAGE161
  AB16 FPGA_EEPROM_I2C_SCL @TIMECARD_LIB.TIMECARD(SCH_1):FPGA_EEPROM_I2C_SCL     I2 @TIMECARD_LIB.TIMECARD(SCH_1):PAGE161
   P21 FPGA_D02 @TIMECARD_LIB.TIMECARD(SCH_1):FPGA_D02     I2 @TIMECARD_LIB.TIMECARD(SCH_1):PAGE161
  AB13 FPGA_OUT_SEC_EEPROM_WP @TIMECARD_LIB.TIMECARD(SCH_1):FPGA_OUT_SEC_EEPROM_WP     I2 @TIMECARD_LIB.TIMECARD(SCH_1):PAGE161
   V22     NC     NC     I2 @TIMECARD_LIB.TIMECARD(SCH_1):PAGE161
  AA13 FPGA_OUT_SN_EEPROM_WP @TIMECARD_LIB.TIMECARD(SCH_1):FPGA_OUT_SN_EEPROM_WP     I2 @TIMECARD_LIB.TIMECARD(SCH_1):PAGE161
   U22   PUDC @TIMECARD_LIB.TIMECARD(SCH_1):PUDC     I2 @TIMECARD_LIB.TIMECARD(SCH_1):PAGE161
  AB15     NC     NC     I2 @TIMECARD_LIB.TIMECARD(SCH_1):PAGE161
   U21     NC     NC     I2 @TIMECARD_LIB.TIMECARD(SCH_1):PAGE161
  AA15 FPGA_IO_FT_USBDET_RST_N @TIMECARD_LIB.TIMECARD(SCH_1):FPGA_IO_FT_USBDET_RST_N     I2 @TIMECARD_LIB.TIMECARD(SCH_1):PAGE161
   T21     NC     NC     I2 @TIMECARD_LIB.TIMECARD(SCH_1):PAGE161
  AA14     NC     NC     I2 @TIMECARD_LIB.TIMECARD(SCH_1):PAGE161
   R19     NC     NC     I2 @TIMECARD_LIB.TIMECARD(SCH_1):PAGE161
   Y13     NC     NC     I2 @TIMECARD_LIB.TIMECARD(SCH_1):PAGE161
   P19     NC     NC     I2 @TIMECARD_LIB.TIMECARD(SCH_1):PAGE161
   T20     NC     NC     I2 @TIMECARD_LIB.TIMECARD(SCH_1):PAGE161
   Y14 FPGA_IN_GPSTP2_OUT @TIMECARD_LIB.TIMECARD(SCH_1):FPGA_IN_GPSTP2_OUT     I2 @TIMECARD_LIB.TIMECARD(SCH_1):PAGE161
   W14 FPGA_IN_GPSTP1_OUT @TIMECARD_LIB.TIMECARD(SCH_1):FPGA_IN_GPSTP1_OUT     I2 @TIMECARD_LIB.TIMECARD(SCH_1):PAGE161
   T19 FPGA_FCS_B @TIMECARD_LIB.TIMECARD(SCH_1):FPGA_FCS_B     I2 @TIMECARD_LIB.TIMECARD(SCH_1):PAGE161
  AB12     NC     NC     I2 @TIMECARD_LIB.TIMECARD(SCH_1):PAGE161
   W22     NC     NC     I2 @TIMECARD_LIB.TIMECARD(SCH_1):PAGE161
  AB11     NC     NC     I2 @TIMECARD_LIB.TIMECARD(SCH_1):PAGE161
   W21     NC     NC     I2 @TIMECARD_LIB.TIMECARD(SCH_1):PAGE161
  AB10 FPGA_IN_MAC_ALARM_OUT_N @TIMECARD_LIB.TIMECARD(SCH_1):FPGA_IN_MAC_ALARM_OUT_N     I2 @TIMECARD_LIB.TIMECARD(SCH_1):PAGE161
  AA21 ANT1_IN @TIMECARD_LIB.TIMECARD(SCH_1):ANT1_IN     I2 @TIMECARD_LIB.TIMECARD(SCH_1):PAGE161
   AA9 FPGA_IN_MAC_BITEOUT @TIMECARD_LIB.TIMECARD(SCH_1):FPGA_IN_MAC_BITE OUT     I2 @TIMECARD_LIB.TIMECARD(SCH_1):PAGE161
  AA20 ANT2_IN @TIMECARD_LIB.TIMECARD(SCH_1):ANT2_IN     I2 @TIMECARD_LIB.TIMECARD(SCH_1):PAGE161
  AA11     NC     NC     I2 @TIMECARD_LIB.TIMECARD(SCH_1):PAGE161
   Y22     NC     NC     I2 @TIMECARD_LIB.TIMECARD(SCH_1):PAGE161
  AA10     NC     NC     I2 @TIMECARD_LIB.TIMECARD(SCH_1):PAGE161
   Y21     NC     NC     I2 @TIMECARD_LIB.TIMECARD(SCH_1):PAGE161
   W10 ANT2_OUT @TIMECARD_LIB.TIMECARD(SCH_1):ANT2_OUT     I2 @TIMECARD_LIB.TIMECARD(SCH_1):PAGE161
  AB22     NC     NC     I2 @TIMECARD_LIB.TIMECARD(SCH_1):PAGE161
   V10 ANT1_OUT @TIMECARD_LIB.TIMECARD(SCH_1):ANT1_OUT     I2 @TIMECARD_LIB.TIMECARD(SCH_1):PAGE161
  AB21     NC     NC     I2 @TIMECARD_LIB.TIMECARD(SCH_1):PAGE161
   Y12 ANT4_IN @TIMECARD_LIB.TIMECARD(SCH_1):ANT4_IN     I2 @TIMECARD_LIB.TIMECARD(SCH_1):PAGE161
   V20     NC     NC     I2 @TIMECARD_LIB.TIMECARD(SCH_1):PAGE161
   Y11 ANT3_IN @TIMECARD_LIB.TIMECARD(SCH_1):ANT3_IN     I2 @TIMECARD_LIB.TIMECARD(SCH_1):PAGE161
   U20     NC     NC     I2 @TIMECARD_LIB.TIMECARD(SCH_1):PAGE161
   W12 ANT4_OUT @TIMECARD_LIB.TIMECARD(SCH_1):ANT4_OUT     I2 @TIMECARD_LIB.TIMECARD(SCH_1):PAGE161
   W20 FPGA_M_RGB_LED_I2C_SCL @TIMECARD_LIB.TIMECARD(SCH_1):FPGA_M_RGB_LED_I2C_SCL     I2 @TIMECARD_LIB.TIMECARD(SCH_1):PAGE161
   W11 ANT3_OUT @TIMECARD_LIB.TIMECARD(SCH_1):ANT3_OUT     I2 @TIMECARD_LIB.TIMECARD(SCH_1):PAGE161
   W19 FPGA_M_RGB_LED_I2C_SDA @TIMECARD_LIB.TIMECARD(SCH_1):FPGA_M_RGB_LED_I2C_SDA     I2 @TIMECARD_LIB.TIMECARD(SCH_1):PAGE161
   V14     NC     NC     I2 @TIMECARD_LIB.TIMECARD(SCH_1):PAGE161
   Y19     NC     NC     I2 @TIMECARD_LIB.TIMECARD(SCH_1):PAGE161
   V13 FPGA_IN_MAC_10MHZ_OUT @TIMECARD_LIB.TIMECARD(SCH_1):FPGA_IN_MAC_10MHZ_OUT     I2 @TIMECARD_LIB.TIMECARD(SCH_1):PAGE161
   Y18 FPGA_OUT_RGB_LED_SHUTDOWN_N @TIMECARD_LIB.TIMECARD(SCH_1):FPGA_OUT_RGB_LED_SHUTDOWN_N     I2 @TIMECARD_LIB.TIMECARD(SCH_1):PAGE161
   V15 FPGA_OUT_MACUSBPOWER_EN @TIMECARD_LIB.TIMECARD(SCH_1):FPGA_OUT_MACUSBPOWER_EN     I2 @TIMECARD_LIB.TIMECARD(SCH_1):PAGE161
   V19     NC     NC     I2 @TIMECARD_LIB.TIMECARD(SCH_1):PAGE161
   U15     NC     NC     I2 @TIMECARD_LIB.TIMECARD(SCH_1):PAGE161
   V18     NC     NC     I2 @TIMECARD_LIB.TIMECARD(SCH_1):PAGE161
   T15     NC     NC     I2 @TIMECARD_LIB.TIMECARD(SCH_1):PAGE161
  AB20     NC     NC     I2 @TIMECARD_LIB.TIMECARD(SCH_1):PAGE161
   T14     NC     NC     I2 @TIMECARD_LIB.TIMECARD(SCH_1):PAGE161
  AA19     NC     NC     I2 @TIMECARD_LIB.TIMECARD(SCH_1):PAGE161
   W16     NC     NC     I2 @TIMECARD_LIB.TIMECARD(SCH_1):PAGE161
   W17     NC     NC     I2 @TIMECARD_LIB.TIMECARD(SCH_1):PAGE161
   W15     NC     NC     I2 @TIMECARD_LIB.TIMECARD(SCH_1):PAGE161
   V17     NC     NC     I2 @TIMECARD_LIB.TIMECARD(SCH_1):PAGE161
   U16 FPGA_OUT_PCA9546_RST_N @TIMECARD_LIB.TIMECARD(SCH_1):FPGA_OUT_PCA9546_RST_N     I2 @TIMECARD_LIB.TIMECARD(SCH_1):PAGE161
  AB18 UART_MAC_TX_FPGA_RX @TIMECARD_LIB.TIMECARD(SCH_1):UART_MAC_TX_FPGA_RX     I2 @TIMECARD_LIB.TIMECARD(SCH_1):PAGE161
   T16 FPGA_PCA9546_I2C_SDA @TIMECARD_LIB.TIMECARD(SCH_1):FPGA_PCA9546_I2C_SDA     I2 @TIMECARD_LIB.TIMECARD(SCH_1):PAGE161
  AA18 UART_MAC_RX_FPGA_TX @TIMECARD_LIB.TIMECARD(SCH_1):UART_MAC_RX_FPGA_TX     I2 @TIMECARD_LIB.TIMECARD(SCH_1):PAGE161
   U18     NC     NC     I2 @TIMECARD_LIB.TIMECARD(SCH_1):PAGE161
   U17     NC     NC     I2 @TIMECARD_LIB.TIMECARD(SCH_1):PAGE161
   R14 MAC_USB_DM @TIMECARD_LIB.TIMECARD(SCH_1):MAC_USB_DM     I2 @TIMECARD_LIB.TIMECARD(SCH_1):PAGE161
   P14 MAC_USB_DP @TIMECARD_LIB.TIMECARD(SCH_1):MAC_USB_DP     I2 @TIMECARD_LIB.TIMECARD(SCH_1):PAGE161
   T18     NC     NC     I2 @TIMECARD_LIB.TIMECARD(SCH_1):PAGE161
   R18     NC     NC     I2 @TIMECARD_LIB.TIMECARD(SCH_1):PAGE161
   P17     NC     NC     I2 @TIMECARD_LIB.TIMECARD(SCH_1):PAGE161
   N17 FPGA_PCA9546_I2C_SCL @TIMECARD_LIB.TIMECARD(SCH_1):FPGA_PCA9546_I2C_SCL     I2 @TIMECARD_LIB.TIMECARD(SCH_1):PAGE161
   R16     NC     NC     I2 @TIMECARD_LIB.TIMECARD(SCH_1):PAGE161
   P15 UART_FT4232_RX_FPGA_TX @TIMECARD_LIB.TIMECARD(SCH_1):UART_FT4232_RX_FPGA_TX     I2 @TIMECARD_LIB.TIMECARD(SCH_1):PAGE161
   N14     NC     NC     I2 @TIMECARD_LIB.TIMECARD(SCH_1):PAGE161
   N13     NC     NC     I2 @TIMECARD_LIB.TIMECARD(SCH_1):PAGE161
   R17     NC     NC     I2 @TIMECARD_LIB.TIMECARD(SCH_1):PAGE161
   P16 UART_FT4232_TX_FPGA_RX @TIMECARD_LIB.TIMECARD(SCH_1):UART_FT4232_TX_FPGA_RX     I2 @TIMECARD_LIB.TIMECARD(SCH_1):PAGE161
   J16     NC     NC   I228 @TIMECARD_LIB.TIMECARD(SCH_1):PAGE162
   F15     NC     NC   I228 @TIMECARD_LIB.TIMECARD(SCH_1):PAGE162
   M17     NC     NC   I228 @TIMECARD_LIB.TIMECARD(SCH_1):PAGE162
   F21     NC     NC   I228 @TIMECARD_LIB.TIMECARD(SCH_1):PAGE162
   F14 FPGA_OUT_SMA1_LED_GREEN_N @TIMECARD_LIB.TIMECARD(SCH_1):FPGA_OUT_SMA1_LED_GREEN_N   I228 @TIMECARD_LIB.TIMECARD(SCH_1):PAGE162
   G13 FPGA_OUT_MUX2_SEL @TIMECARD_LIB.TIMECARD(SCH_1):FPGA_OUT_MUX2_SEL   I228 @TIMECARD_LIB.TIMECARD(SCH_1):PAGE162
   F13 FPGA_OUT_SMA1_LED_BLUE_N @TIMECARD_LIB.TIMECARD(SCH_1):FPGA_OUT_SMA1_LED_BLUE_N   I228 @TIMECARD_LIB.TIMECARD(SCH_1):PAGE162
   H13 FPGA_OUT_MUX1_SEL @TIMECARD_LIB.TIMECARD(SCH_1):FPGA_OUT_MUX1_SEL   I228 @TIMECARD_LIB.TIMECARD(SCH_1):PAGE162
   E17     NC     NC   I228 @TIMECARD_LIB.TIMECARD(SCH_1):PAGE162
   G16     NC     NC   I228 @TIMECARD_LIB.TIMECARD(SCH_1):PAGE162
   F16 FPGA_OUT_SMA1_LED_RED_N @TIMECARD_LIB.TIMECARD(SCH_1):FPGA_OUT_SMA1_LED_RED_N   I228 @TIMECARD_LIB.TIMECARD(SCH_1):PAGE162
   G15 FPGA_OUT_MUX3_SEL @TIMECARD_LIB.TIMECARD(SCH_1):FPGA_OUT_MUX3_SEL   I228 @TIMECARD_LIB.TIMECARD(SCH_1):PAGE162
   C15 FPGA_OUT_SMA2_LED_GREEN_N @TIMECARD_LIB.TIMECARD(SCH_1):FPGA_OUT_SMA2_LED_GREEN_N   I228 @TIMECARD_LIB.TIMECARD(SCH_1):PAGE162
   H14 SMA4_SIG_OUT_BF_EN_N @TIMECARD_LIB.TIMECARD(SCH_1):SMA4_SIG_OUT_BF_EN_N   I228 @TIMECARD_LIB.TIMECARD(SCH_1):PAGE162
   C14 FPGA_OUT_SMA2_LED_BLUE_N @TIMECARD_LIB.TIMECARD(SCH_1):FPGA_OUT_SMA2_LED_BLUE_N   I228 @TIMECARD_LIB.TIMECARD(SCH_1):PAGE162
   J14 SMA4_SIG_IN_BF_EN_N @TIMECARD_LIB.TIMECARD(SCH_1):SMA4_SIG_IN_BF_EN_N   I228 @TIMECARD_LIB.TIMECARD(SCH_1):PAGE162
   G18     NC     NC   I228 @TIMECARD_LIB.TIMECARD(SCH_1):PAGE162
   E14     NC     NC   I228 @TIMECARD_LIB.TIMECARD(SCH_1):PAGE162
   G17     NC     NC   I228 @TIMECARD_LIB.TIMECARD(SCH_1):PAGE162
   E13 FPGA_OUT_SMA2_LED_RED_N @TIMECARD_LIB.TIMECARD(SCH_1):FPGA_OUT_SMA2_LED_RED_N   I228 @TIMECARD_LIB.TIMECARD(SCH_1):PAGE162
   D16     NC     NC   I228 @TIMECARD_LIB.TIMECARD(SCH_1):PAGE162
   H15 SMA3_SIG_IN_BF_EN_N @TIMECARD_LIB.TIMECARD(SCH_1):SMA3_SIG_IN_BF_EN_N   I228 @TIMECARD_LIB.TIMECARD(SCH_1):PAGE162
   E16     NC     NC   I228 @TIMECARD_LIB.TIMECARD(SCH_1):PAGE162
   J15 SMA3_SIG_OUT_BF_EN_N @TIMECARD_LIB.TIMECARD(SCH_1):SMA3_SIG_OUT_BF_EN_N   I228 @TIMECARD_LIB.TIMECARD(SCH_1):PAGE162
   H18     NC     NC   I228 @TIMECARD_LIB.TIMECARD(SCH_1):PAGE162
   D15 LED_DATOUT3 @TIMECARD_LIB.TIMECARD(SCH_1):LED_DATOUT3   I228 @TIMECARD_LIB.TIMECARD(SCH_1):PAGE162
   H17     NC     NC   I228 @TIMECARD_LIB.TIMECARD(SCH_1):PAGE162
   D14 LED_DATOUT2 @TIMECARD_LIB.TIMECARD(SCH_1):LED_DATOUT2   I228 @TIMECARD_LIB.TIMECARD(SCH_1):PAGE162
   B16     NC     NC   I228 @TIMECARD_LIB.TIMECARD(SCH_1):PAGE162
   H22 FPGA_IO_1 @TIMECARD_LIB.TIMECARD(SCH_1):FPGA_IO_1   I228 @TIMECARD_LIB.TIMECARD(SCH_1):PAGE162
   B15     NC     NC   I228 @TIMECARD_LIB.TIMECARD(SCH_1):PAGE162
   J22 FPGA_IO_0 @TIMECARD_LIB.TIMECARD(SCH_1):FPGA_IO_0   I228 @TIMECARD_LIB.TIMECARD(SCH_1):PAGE162
   B13 LED_DATOUT0 @TIMECARD_LIB.TIMECARD(SCH_1):LED_DATOUT0   I228 @TIMECARD_LIB.TIMECARD(SCH_1):PAGE162
   G20 FPGA_IO_3 @TIMECARD_LIB.TIMECARD(SCH_1):FPGA_IO_3   I228 @TIMECARD_LIB.TIMECARD(SCH_1):PAGE162
   C13 LED_DATOUT1 @TIMECARD_LIB.TIMECARD(SCH_1):LED_DATOUT1   I228 @TIMECARD_LIB.TIMECARD(SCH_1):PAGE162
   H20 FPGA_IO_2 @TIMECARD_LIB.TIMECARD(SCH_1):FPGA_IO_2   I228 @TIMECARD_LIB.TIMECARD(SCH_1):PAGE162
   A16     NC     NC   I228 @TIMECARD_LIB.TIMECARD(SCH_1):PAGE162
   K22 FPGA_IO_5 @TIMECARD_LIB.TIMECARD(SCH_1):FPGA_IO_5   I228 @TIMECARD_LIB.TIMECARD(SCH_1):PAGE162
   A15     NC     NC   I228 @TIMECARD_LIB.TIMECARD(SCH_1):PAGE162
   K21 FPGA_IO_4 @TIMECARD_LIB.TIMECARD(SCH_1):FPGA_IO_4   I228 @TIMECARD_LIB.TIMECARD(SCH_1):PAGE162
   A14 FPGA_USR_LED0 @TIMECARD_LIB.TIMECARD(SCH_1):FPGA_USR_LED0   I228 @TIMECARD_LIB.TIMECARD(SCH_1):PAGE162
   L21 FPGA_IO_7 @TIMECARD_LIB.TIMECARD(SCH_1):FPGA_IO_7   I228 @TIMECARD_LIB.TIMECARD(SCH_1):PAGE162
   A13 FPGA_USR_LED1 @TIMECARD_LIB.TIMECARD(SCH_1):FPGA_USR_LED1   I228 @TIMECARD_LIB.TIMECARD(SCH_1):PAGE162
   M21 FPGA_IO_6 @TIMECARD_LIB.TIMECARD(SCH_1):FPGA_IO_6   I228 @TIMECARD_LIB.TIMECARD(SCH_1):PAGE162
   J21     NC     NC   I228 @TIMECARD_LIB.TIMECARD(SCH_1):PAGE162
   B18     NC     NC   I228 @TIMECARD_LIB.TIMECARD(SCH_1):PAGE162
   J20 FPGA_IN_RST_DLY_N @TIMECARD_LIB.TIMECARD(SCH_1):FPGA_IN_RST_DLY_N   I228 @TIMECARD_LIB.TIMECARD(SCH_1):PAGE162
   B17     NC     NC   I228 @TIMECARD_LIB.TIMECARD(SCH_1):PAGE162
   H19 FPGA_OUT_SHT3X_RST_N @TIMECARD_LIB.TIMECARD(SCH_1):FPGA_OUT_SHT3X_RST_N   I228 @TIMECARD_LIB.TIMECARD(SCH_1):PAGE162
   C17 FPGA_OUT_SMA3_LED_GREEN_N @TIMECARD_LIB.TIMECARD(SCH_1):FPGA_OUT_SMA3_LED_GREEN_N   I228 @TIMECARD_LIB.TIMECARD(SCH_1):PAGE162
   J19 FPGA_IN_SHT3X_ALERT_N @TIMECARD_LIB.TIMECARD(SCH_1):FPGA_IN_SHT3X_ALERT_N   I228 @TIMECARD_LIB.TIMECARD(SCH_1):PAGE162
   D17 FPGA_OUT_SMA3_LED_BLUE_N @TIMECARD_LIB.TIMECARD(SCH_1):FPGA_OUT_SMA3_LED_BLUE_N   I228 @TIMECARD_LIB.TIMECARD(SCH_1):PAGE162
   K19     NC     NC   I228 @TIMECARD_LIB.TIMECARD(SCH_1):PAGE162
   C19     NC     NC   I228 @TIMECARD_LIB.TIMECARD(SCH_1):PAGE162
   K18     NC     NC   I228 @TIMECARD_LIB.TIMECARD(SCH_1):PAGE162
   C18 FPGA_OUT_SMA3_LED_RED_N @TIMECARD_LIB.TIMECARD(SCH_1):FPGA_OUT_SMA3_LED_RED_N   I228 @TIMECARD_LIB.TIMECARD(SCH_1):PAGE162
   L20     NC     NC   I228 @TIMECARD_LIB.TIMECARD(SCH_1):PAGE162
   D19 FPGA_OUT_SMA4_LED_GREEN_N @TIMECARD_LIB.TIMECARD(SCH_1):FPGA_OUT_SMA4_LED_GREEN_N   I228 @TIMECARD_LIB.TIMECARD(SCH_1):PAGE162
   L19     NC     NC   I228 @TIMECARD_LIB.TIMECARD(SCH_1):PAGE162
   E19 FPGA_OUT_SMA4_LED_BLUE_N @TIMECARD_LIB.TIMECARD(SCH_1):FPGA_OUT_SMA4_LED_BLUE_N   I228 @TIMECARD_LIB.TIMECARD(SCH_1):PAGE162
   E18     NC     NC   I228 @TIMECARD_LIB.TIMECARD(SCH_1):PAGE162
   M22 FPGA_IN_LM75B_INT2_N @TIMECARD_LIB.TIMECARD(SCH_1):FPGA_IN_LM75B_INT2_N   I228 @TIMECARD_LIB.TIMECARD(SCH_1):PAGE162
   N22 FPGA_IN_LM75B_INT1_N @TIMECARD_LIB.TIMECARD(SCH_1):FPGA_IN_LM75B_INT1_N   I228 @TIMECARD_LIB.TIMECARD(SCH_1):PAGE162
   F18 FPGA_OUT_SMA4_LED_RED_N @TIMECARD_LIB.TIMECARD(SCH_1):FPGA_OUT_SMA4_LED_RED_N   I228 @TIMECARD_LIB.TIMECARD(SCH_1):PAGE162
   A20 FPGA_OUT_GPS_LED_GREEN_N @TIMECARD_LIB.TIMECARD(SCH_1):FPGA_OUT_GPS_LED_GREEN_N   I228 @TIMECARD_LIB.TIMECARD(SCH_1):PAGE162
   L18     NC     NC   I228 @TIMECARD_LIB.TIMECARD(SCH_1):PAGE162
   B20 FPGA_OUT_GPS_LED_BLUE_N @TIMECARD_LIB.TIMECARD(SCH_1):FPGA_OUT_GPS_LED_BLUE_N   I228 @TIMECARD_LIB.TIMECARD(SCH_1):PAGE162
   M18 FPGA_IN_LM75B_INT3_N @TIMECARD_LIB.TIMECARD(SCH_1):FPGA_IN_LM75B_INT3_N   I228 @TIMECARD_LIB.TIMECARD(SCH_1):PAGE162
   A19     NC     NC   I228 @TIMECARD_LIB.TIMECARD(SCH_1):PAGE162
   N19 FPGA_BRD_REV1 @TIMECARD_LIB.TIMECARD(SCH_1):FPGA_BRD_REV1   I228 @TIMECARD_LIB.TIMECARD(SCH_1):PAGE162
   A18 FPGA_OUT_GPS_LED_RED_N @TIMECARD_LIB.TIMECARD(SCH_1):FPGA_OUT_GPS_LED_RED_N   I228 @TIMECARD_LIB.TIMECARD(SCH_1):PAGE162
   N18 FPGA_BRD_REV2 @TIMECARD_LIB.TIMECARD(SCH_1):FPGA_BRD_REV2   I228 @TIMECARD_LIB.TIMECARD(SCH_1):PAGE162
   F20     NC     NC   I228 @TIMECARD_LIB.TIMECARD(SCH_1):PAGE162
   M20     NC     NC   I228 @TIMECARD_LIB.TIMECARD(SCH_1):PAGE162
   F19     NC     NC   I228 @TIMECARD_LIB.TIMECARD(SCH_1):PAGE162
   N20 FPGA_BRD_REV0 @TIMECARD_LIB.TIMECARD(SCH_1):FPGA_BRD_REV0   I228 @TIMECARD_LIB.TIMECARD(SCH_1):PAGE162
   K14 SMA1_SIG_IN_BF_EN_N @TIMECARD_LIB.TIMECARD(SCH_1):SMA1_SIG_IN_BF_EN_N   I228 @TIMECARD_LIB.TIMECARD(SCH_1):PAGE162
   C20     NC     NC   I228 @TIMECARD_LIB.TIMECARD(SCH_1):PAGE162
   D20     NC     NC   I228 @TIMECARD_LIB.TIMECARD(SCH_1):PAGE162
   K13 SMA1_SIG_OUT_BF_EN_N @TIMECARD_LIB.TIMECARD(SCH_1):SMA1_SIG_OUT_BF_EN_N   I228 @TIMECARD_LIB.TIMECARD(SCH_1):PAGE162
   B22 IO_L20N_16 @TIMECARD_LIB.TIMECARD(SCH_1):IO_L20N_16   I228 @TIMECARD_LIB.TIMECARD(SCH_1):PAGE162
   L13 SMA2_SIG_IN_BF_EN_N @TIMECARD_LIB.TIMECARD(SCH_1):SMA2_SIG_IN_BF_EN_N   I228 @TIMECARD_LIB.TIMECARD(SCH_1):PAGE162
   C22 IO_L20P_16 @TIMECARD_LIB.TIMECARD(SCH_1):IO_L20P_16   I228 @TIMECARD_LIB.TIMECARD(SCH_1):PAGE162
   M13 SMA2_SIG_OUT_BF_EN_N @TIMECARD_LIB.TIMECARD(SCH_1):SMA2_SIG_OUT_BF_EN_N   I228 @TIMECARD_LIB.TIMECARD(SCH_1):PAGE162
   A21 IO_L21N_16 @TIMECARD_LIB.TIMECARD(SCH_1):IO_L21N_16   I228 @TIMECARD_LIB.TIMECARD(SCH_1):PAGE162
   J17 FPGA_OUT_BNO080_RST_N @TIMECARD_LIB.TIMECARD(SCH_1):FPGA_OUT_BNO080_RST_N   I228 @TIMECARD_LIB.TIMECARD(SCH_1):PAGE162
   K17     NC     NC   I228 @TIMECARD_LIB.TIMECARD(SCH_1):PAGE162
   B21 IO_L21P_16 @TIMECARD_LIB.TIMECARD(SCH_1):IO_L21P_16   I228 @TIMECARD_LIB.TIMECARD(SCH_1):PAGE162
   D22 IO_L22N_16 @TIMECARD_LIB.TIMECARD(SCH_1):IO_L22N_16   I228 @TIMECARD_LIB.TIMECARD(SCH_1):PAGE162
   L15 FPGA_OUT_BNO080_BOOT_N @TIMECARD_LIB.TIMECARD(SCH_1):FPGA_OUT_BNO080_BOOT_N   I228 @TIMECARD_LIB.TIMECARD(SCH_1):PAGE162
   E22 IO_L22P_16 @TIMECARD_LIB.TIMECARD(SCH_1):IO_L22P_16   I228 @TIMECARD_LIB.TIMECARD(SCH_1):PAGE162
   L14 FPGA_IN_BNO080_INT_N @TIMECARD_LIB.TIMECARD(SCH_1):FPGA_IN_BNO080_INT_N   I228 @TIMECARD_LIB.TIMECARD(SCH_1):PAGE162
   D21 IO_L23N_16 @TIMECARD_LIB.TIMECARD(SCH_1):IO_L23N_16   I228 @TIMECARD_LIB.TIMECARD(SCH_1):PAGE162
   K16 FPGA_OUT_I2C_BUFFER_EN @TIMECARD_LIB.TIMECARD(SCH_1):FPGA_OUT_I2C_BUFFER_EN   I228 @TIMECARD_LIB.TIMECARD(SCH_1):PAGE162
   E21 IO_L23P_16 @TIMECARD_LIB.TIMECARD(SCH_1):IO_L23P_16   I228 @TIMECARD_LIB.TIMECARD(SCH_1):PAGE162
   L16     NC     NC   I228 @TIMECARD_LIB.TIMECARD(SCH_1):PAGE162
   G22 IO_L24N_16 @TIMECARD_LIB.TIMECARD(SCH_1):IO_L24N_16   I228 @TIMECARD_LIB.TIMECARD(SCH_1):PAGE162
   M16 RSVD_DBG_USB_MUX_SEL @TIMECARD_LIB.TIMECARD(SCH_1):RSVD_DBG_USB_MUX_SEL   I228 @TIMECARD_LIB.TIMECARD(SCH_1):PAGE162
   G21 IO_L24P_16 @TIMECARD_LIB.TIMECARD(SCH_1):IO_L24P_16   I228 @TIMECARD_LIB.TIMECARD(SCH_1):PAGE162
   M15 FPGA_IN_MAC_USB_OC_N @TIMECARD_LIB.TIMECARD(SCH_1):FPGA_IN_MAC_USB_OC_N   I228 @TIMECARD_LIB.TIMECARD(SCH_1):PAGE162
    T3     NC     NC     I1 @TIMECARD_LIB.TIMECARD(SCH_1):PAGE163
    F4     NC     NC     I1 @TIMECARD_LIB.TIMECARD(SCH_1):PAGE163
    U7     NC     NC     I1 @TIMECARD_LIB.TIMECARD(SCH_1):PAGE163
    L6     NC     NC     I1 @TIMECARD_LIB.TIMECARD(SCH_1):PAGE163
    U1     NC     NC     I1 @TIMECARD_LIB.TIMECARD(SCH_1):PAGE163
    A1     NC     NC     I1 @TIMECARD_LIB.TIMECARD(SCH_1):PAGE163
    T1     NC     NC     I1 @TIMECARD_LIB.TIMECARD(SCH_1):PAGE163
    B1     NC     NC     I1 @TIMECARD_LIB.TIMECARD(SCH_1):PAGE163
    V2     NC     NC     I1 @TIMECARD_LIB.TIMECARD(SCH_1):PAGE163
    B2     NC     NC     I1 @TIMECARD_LIB.TIMECARD(SCH_1):PAGE163
    U2     NC     NC     I1 @TIMECARD_LIB.TIMECARD(SCH_1):PAGE163
    C2     NC     NC     I1 @TIMECARD_LIB.TIMECARD(SCH_1):PAGE163
    R2     NC     NC     I1 @TIMECARD_LIB.TIMECARD(SCH_1):PAGE163
    D1     NC     NC     I1 @TIMECARD_LIB.TIMECARD(SCH_1):PAGE163
    R3     NC     NC     I1 @TIMECARD_LIB.TIMECARD(SCH_1):PAGE163
    E1     NC     NC     I1 @TIMECARD_LIB.TIMECARD(SCH_1):PAGE163
    Y2     NC     NC     I1 @TIMECARD_LIB.TIMECARD(SCH_1):PAGE163
    D2     NC     NC     I1 @TIMECARD_LIB.TIMECARD(SCH_1):PAGE163
    W2     NC     NC     I1 @TIMECARD_LIB.TIMECARD(SCH_1):PAGE163
    E2     NC     NC     I1 @TIMECARD_LIB.TIMECARD(SCH_1):PAGE163
    Y1 FPGA_IN_MAC_PPS_OUTN @TIMECARD_LIB.TIMECARD(SCH_1):FPGA_IN_MAC_PPS_OUTN     I1 @TIMECARD_LIB.TIMECARD(SCH_1):PAGE163
    F1     NC     NC     I1 @TIMECARD_LIB.TIMECARD(SCH_1):PAGE163
    W1 FPGA_IN_MAC_PPS_OUTP @TIMECARD_LIB.TIMECARD(SCH_1):FPGA_IN_MAC_PPS_OUTP     I1 @TIMECARD_LIB.TIMECARD(SCH_1):PAGE163
    G1     NC     NC     I1 @TIMECARD_LIB.TIMECARD(SCH_1):PAGE163
    V3     NC     NC     I1 @TIMECARD_LIB.TIMECARD(SCH_1):PAGE163
    E3     NC     NC     I1 @TIMECARD_LIB.TIMECARD(SCH_1):PAGE163
    U3     NC     NC     I1 @TIMECARD_LIB.TIMECARD(SCH_1):PAGE163
    F3     NC     NC     I1 @TIMECARD_LIB.TIMECARD(SCH_1):PAGE163
   AB1     NC     NC     I1 @TIMECARD_LIB.TIMECARD(SCH_1):PAGE163
    J1     NC     NC     I1 @TIMECARD_LIB.TIMECARD(SCH_1):PAGE163
   AA1     NC     NC     I1 @TIMECARD_LIB.TIMECARD(SCH_1):PAGE163
    K1     NC     NC     I1 @TIMECARD_LIB.TIMECARD(SCH_1):PAGE163
   AB2 FPGA_OUT_MAC_PPS_IN0N @TIMECARD_LIB.TIMECARD(SCH_1):FPGA_OUT_MAC_PPS_IN0N     I1 @TIMECARD_LIB.TIMECARD(SCH_1):PAGE163
    G2     NC     NC     I1 @TIMECARD_LIB.TIMECARD(SCH_1):PAGE163
   AB3 FPGA_OUT_MAC_PPS_IN0P @TIMECARD_LIB.TIMECARD(SCH_1):FPGA_OUT_MAC_PPS_IN0P     I1 @TIMECARD_LIB.TIMECARD(SCH_1):PAGE163
    H2     NC     NC     I1 @TIMECARD_LIB.TIMECARD(SCH_1):PAGE163
   AA3     NC     NC     I1 @TIMECARD_LIB.TIMECARD(SCH_1):PAGE163
    J2     NC     NC     I1 @TIMECARD_LIB.TIMECARD(SCH_1):PAGE163
    Y3     NC     NC     I1 @TIMECARD_LIB.TIMECARD(SCH_1):PAGE163
    K2     NC     NC     I1 @TIMECARD_LIB.TIMECARD(SCH_1):PAGE163
   AB5 FPGA_OUT_MAC_PPS_IN1N @TIMECARD_LIB.TIMECARD(SCH_1):FPGA_OUT_MAC_PPS_IN1N     I1 @TIMECARD_LIB.TIMECARD(SCH_1):PAGE163
    H5     NC     NC     I1 @TIMECARD_LIB.TIMECARD(SCH_1):PAGE163
   AA5 FPGA_OUT_MAC_PPS_IN1P @TIMECARD_LIB.TIMECARD(SCH_1):FPGA_OUT_MAC_PPS_IN1P     I1 @TIMECARD_LIB.TIMECARD(SCH_1):PAGE163
    J5     NC     NC     I1 @TIMECARD_LIB.TIMECARD(SCH_1):PAGE163
   AA4     NC     NC     I1 @TIMECARD_LIB.TIMECARD(SCH_1):PAGE163
    G3     NC     NC     I1 @TIMECARD_LIB.TIMECARD(SCH_1):PAGE163
    Y4     NC     NC     I1 @TIMECARD_LIB.TIMECARD(SCH_1):PAGE163
    H3     NC     NC     I1 @TIMECARD_LIB.TIMECARD(SCH_1):PAGE163
    W4     NC     NC     I1 @TIMECARD_LIB.TIMECARD(SCH_1):PAGE163
    G4     NC     NC     I1 @TIMECARD_LIB.TIMECARD(SCH_1):PAGE163
    V4     NC     NC     I1 @TIMECARD_LIB.TIMECARD(SCH_1):PAGE163
    H4     NC     NC     I1 @TIMECARD_LIB.TIMECARD(SCH_1):PAGE163
    T4 MHZ200CLKN_CLKIN @TIMECARD_LIB.TIMECARD(SCH_1):MHZ200CLKN_CLKIN     I1 @TIMECARD_LIB.TIMECARD(SCH_1):PAGE163
    J4     NC     NC     I1 @TIMECARD_LIB.TIMECARD(SCH_1):PAGE163
    R4 MHZ200CLKP_CLKIN @TIMECARD_LIB.TIMECARD(SCH_1):MHZ200CLKP_CLKIN     I1 @TIMECARD_LIB.TIMECARD(SCH_1):PAGE163
    K4     NC     NC     I1 @TIMECARD_LIB.TIMECARD(SCH_1):PAGE163
    U5     NC     NC     I1 @TIMECARD_LIB.TIMECARD(SCH_1):PAGE163
    K3     NC     NC     I1 @TIMECARD_LIB.TIMECARD(SCH_1):PAGE163
    T5     NC     NC     I1 @TIMECARD_LIB.TIMECARD(SCH_1):PAGE163
    L3     NC     NC     I1 @TIMECARD_LIB.TIMECARD(SCH_1):PAGE163
    W5     NC     NC     I1 @TIMECARD_LIB.TIMECARD(SCH_1):PAGE163
    L1     NC     NC     I1 @TIMECARD_LIB.TIMECARD(SCH_1):PAGE163
    W6     NC     NC     I1 @TIMECARD_LIB.TIMECARD(SCH_1):PAGE163
    M1     NC     NC     I1 @TIMECARD_LIB.TIMECARD(SCH_1):PAGE163
    V5     NC     NC     I1 @TIMECARD_LIB.TIMECARD(SCH_1):PAGE163
    M2     NC     NC     I1 @TIMECARD_LIB.TIMECARD(SCH_1):PAGE163
    U6     NC     NC     I1 @TIMECARD_LIB.TIMECARD(SCH_1):PAGE163
    M3     NC     NC     I1 @TIMECARD_LIB.TIMECARD(SCH_1):PAGE163
    T6     NC     NC     I1 @TIMECARD_LIB.TIMECARD(SCH_1):PAGE163
    J6     NC     NC     I1 @TIMECARD_LIB.TIMECARD(SCH_1):PAGE163
    R6     NC     NC     I1 @TIMECARD_LIB.TIMECARD(SCH_1):PAGE163
    K6     NC     NC     I1 @TIMECARD_LIB.TIMECARD(SCH_1):PAGE163
   AA6     NC     NC     I1 @TIMECARD_LIB.TIMECARD(SCH_1):PAGE163
    L4     NC     NC     I1 @TIMECARD_LIB.TIMECARD(SCH_1):PAGE163
    Y6     NC     NC     I1 @TIMECARD_LIB.TIMECARD(SCH_1):PAGE163
    L5     NC     NC     I1 @TIMECARD_LIB.TIMECARD(SCH_1):PAGE163
    W7     NC     NC     I1 @TIMECARD_LIB.TIMECARD(SCH_1):PAGE163
    N3     NC     NC     I1 @TIMECARD_LIB.TIMECARD(SCH_1):PAGE163
    V7     NC     NC     I1 @TIMECARD_LIB.TIMECARD(SCH_1):PAGE163
    N4     NC     NC     I1 @TIMECARD_LIB.TIMECARD(SCH_1):PAGE163
   AB6 IO_L20N_34 @TIMECARD_LIB.TIMECARD(SCH_1):IO_L20N_34     I1 @TIMECARD_LIB.TIMECARD(SCH_1):PAGE163
    P1 IO_L20N_35 @TIMECARD_LIB.TIMECARD(SCH_1):IO_L20N_35     I1 @TIMECARD_LIB.TIMECARD(SCH_1):PAGE163
   AB7 IO_L20P_34 @TIMECARD_LIB.TIMECARD(SCH_1):IO_L20P_34     I1 @TIMECARD_LIB.TIMECARD(SCH_1):PAGE163
    R1 IO_L20P_35 @TIMECARD_LIB.TIMECARD(SCH_1):IO_L20P_35     I1 @TIMECARD_LIB.TIMECARD(SCH_1):PAGE163
    V8 IO_L21N_34 @TIMECARD_LIB.TIMECARD(SCH_1):IO_L21N_34     I1 @TIMECARD_LIB.TIMECARD(SCH_1):PAGE163
    P4 IO_L21N_35 @TIMECARD_LIB.TIMECARD(SCH_1):IO_L21N_35     I1 @TIMECARD_LIB.TIMECARD(SCH_1):PAGE163
    V9 IO_L21P_34 @TIMECARD_LIB.TIMECARD(SCH_1):IO_L21P_34     I1 @TIMECARD_LIB.TIMECARD(SCH_1):PAGE163
    P5 IO_L21P_35 @TIMECARD_LIB.TIMECARD(SCH_1):IO_L21P_35     I1 @TIMECARD_LIB.TIMECARD(SCH_1):PAGE163
   AB8 IO_L22N_34 @TIMECARD_LIB.TIMECARD(SCH_1):IO_L22N_34     I1 @TIMECARD_LIB.TIMECARD(SCH_1):PAGE163
    N2 IO_L22N_35 @TIMECARD_LIB.TIMECARD(SCH_1):IO_L22N_35     I1 @TIMECARD_LIB.TIMECARD(SCH_1):PAGE163
   AA8 IO_L22P_34 @TIMECARD_LIB.TIMECARD(SCH_1):IO_L22P_34     I1 @TIMECARD_LIB.TIMECARD(SCH_1):PAGE163
    P2 IO_L22P_35 @TIMECARD_LIB.TIMECARD(SCH_1):IO_L22P_35     I1 @TIMECARD_LIB.TIMECARD(SCH_1):PAGE163
    Y7 IO_L23N_34 @TIMECARD_LIB.TIMECARD(SCH_1):IO_L23N_34     I1 @TIMECARD_LIB.TIMECARD(SCH_1):PAGE163
    M5 IO_L23N_35 @TIMECARD_LIB.TIMECARD(SCH_1):IO_L23N_35     I1 @TIMECARD_LIB.TIMECARD(SCH_1):PAGE163
    Y8 IO_L23P_34 @TIMECARD_LIB.TIMECARD(SCH_1):IO_L23P_34     I1 @TIMECARD_LIB.TIMECARD(SCH_1):PAGE163
    M6 IO_L23P_35 @TIMECARD_LIB.TIMECARD(SCH_1):IO_L23P_35     I1 @TIMECARD_LIB.TIMECARD(SCH_1):PAGE163
    Y9 IO_L24N_34 @TIMECARD_LIB.TIMECARD(SCH_1):IO_L24N_34     I1 @TIMECARD_LIB.TIMECARD(SCH_1):PAGE163
    N5 IO_L24N_35 @TIMECARD_LIB.TIMECARD(SCH_1):IO_L24N_35     I1 @TIMECARD_LIB.TIMECARD(SCH_1):PAGE163
    W9 IO_L24P_34 @TIMECARD_LIB.TIMECARD(SCH_1):IO_L24P_34     I1 @TIMECARD_LIB.TIMECARD(SCH_1):PAGE163
    P6 IO_L24P_35 @TIMECARD_LIB.TIMECARD(SCH_1):IO_L24P_35     I1 @TIMECARD_LIB.TIMECARD(SCH_1):PAGE163
    K9     SG @TIMECARD_LIB.TIMECARD(SCH_1):SG   I138 @TIMECARD_LIB.TIMECARD(SCH_1):PAGE164
   A11     SG @TIMECARD_LIB.TIMECARD(SCH_1):SG   I138 @TIMECARD_LIB.TIMECARD(SCH_1):PAGE164
   A12     SG @TIMECARD_LIB.TIMECARD(SCH_1):SG   I138 @TIMECARD_LIB.TIMECARD(SCH_1):PAGE164
    A2     SG @TIMECARD_LIB.TIMECARD(SCH_1):SG   I138 @TIMECARD_LIB.TIMECARD(SCH_1):PAGE164
   A22     SG @TIMECARD_LIB.TIMECARD(SCH_1):SG   I138 @TIMECARD_LIB.TIMECARD(SCH_1):PAGE164
    A3     SG @TIMECARD_LIB.TIMECARD(SCH_1):SG   I138 @TIMECARD_LIB.TIMECARD(SCH_1):PAGE164
    A5     SG @TIMECARD_LIB.TIMECARD(SCH_1):SG   I138 @TIMECARD_LIB.TIMECARD(SCH_1):PAGE164
    A7     SG @TIMECARD_LIB.TIMECARD(SCH_1):SG   I138 @TIMECARD_LIB.TIMECARD(SCH_1):PAGE164
    A9     SG @TIMECARD_LIB.TIMECARD(SCH_1):SG   I138 @TIMECARD_LIB.TIMECARD(SCH_1):PAGE164
  AA12     SG @TIMECARD_LIB.TIMECARD(SCH_1):SG   I138 @TIMECARD_LIB.TIMECARD(SCH_1):PAGE164
   AA2     SG @TIMECARD_LIB.TIMECARD(SCH_1):SG   I138 @TIMECARD_LIB.TIMECARD(SCH_1):PAGE164
  AA22     SG @TIMECARD_LIB.TIMECARD(SCH_1):SG   I138 @TIMECARD_LIB.TIMECARD(SCH_1):PAGE164
  AB19     SG @TIMECARD_LIB.TIMECARD(SCH_1):SG   I138 @TIMECARD_LIB.TIMECARD(SCH_1):PAGE164
   AB9     SG @TIMECARD_LIB.TIMECARD(SCH_1):SG   I138 @TIMECARD_LIB.TIMECARD(SCH_1):PAGE164
   B12     SG @TIMECARD_LIB.TIMECARD(SCH_1):SG   I138 @TIMECARD_LIB.TIMECARD(SCH_1):PAGE164
   B19     SG @TIMECARD_LIB.TIMECARD(SCH_1):SG   I138 @TIMECARD_LIB.TIMECARD(SCH_1):PAGE164
    B3     SG @TIMECARD_LIB.TIMECARD(SCH_1):SG   I138 @TIMECARD_LIB.TIMECARD(SCH_1):PAGE164
   C10     SG @TIMECARD_LIB.TIMECARD(SCH_1):SG   I138 @TIMECARD_LIB.TIMECARD(SCH_1):PAGE164
   C12     SG @TIMECARD_LIB.TIMECARD(SCH_1):SG   I138 @TIMECARD_LIB.TIMECARD(SCH_1):PAGE164
   C16     SG @TIMECARD_LIB.TIMECARD(SCH_1):SG   I138 @TIMECARD_LIB.TIMECARD(SCH_1):PAGE164
    C3     SG @TIMECARD_LIB.TIMECARD(SCH_1):SG   I138 @TIMECARD_LIB.TIMECARD(SCH_1):PAGE164
    C6     SG @TIMECARD_LIB.TIMECARD(SCH_1):SG   I138 @TIMECARD_LIB.TIMECARD(SCH_1):PAGE164
   D12     SG @TIMECARD_LIB.TIMECARD(SCH_1):SG   I138 @TIMECARD_LIB.TIMECARD(SCH_1):PAGE164
   D13     SG @TIMECARD_LIB.TIMECARD(SCH_1):SG   I138 @TIMECARD_LIB.TIMECARD(SCH_1):PAGE164
    D3     SG @TIMECARD_LIB.TIMECARD(SCH_1):SG   I138 @TIMECARD_LIB.TIMECARD(SCH_1):PAGE164
    D4     SG @TIMECARD_LIB.TIMECARD(SCH_1):SG   I138 @TIMECARD_LIB.TIMECARD(SCH_1):PAGE164
    D8     SG @TIMECARD_LIB.TIMECARD(SCH_1):SG   I138 @TIMECARD_LIB.TIMECARD(SCH_1):PAGE164
   E11     SG @TIMECARD_LIB.TIMECARD(SCH_1):SG   I138 @TIMECARD_LIB.TIMECARD(SCH_1):PAGE164
   E20     SG @TIMECARD_LIB.TIMECARD(SCH_1):SG   I138 @TIMECARD_LIB.TIMECARD(SCH_1):PAGE164
    E4     SG @TIMECARD_LIB.TIMECARD(SCH_1):SG   I138 @TIMECARD_LIB.TIMECARD(SCH_1):PAGE164
    E5     SG @TIMECARD_LIB.TIMECARD(SCH_1):SG   I138 @TIMECARD_LIB.TIMECARD(SCH_1):PAGE164
    E7     SG @TIMECARD_LIB.TIMECARD(SCH_1):SG   I138 @TIMECARD_LIB.TIMECARD(SCH_1):PAGE164
    E9     SG @TIMECARD_LIB.TIMECARD(SCH_1):SG   I138 @TIMECARD_LIB.TIMECARD(SCH_1):PAGE164
   F11     SG @TIMECARD_LIB.TIMECARD(SCH_1):SG   I138 @TIMECARD_LIB.TIMECARD(SCH_1):PAGE164
   F17     SG @TIMECARD_LIB.TIMECARD(SCH_1):SG   I138 @TIMECARD_LIB.TIMECARD(SCH_1):PAGE164
    F5     SG @TIMECARD_LIB.TIMECARD(SCH_1):SG   I138 @TIMECARD_LIB.TIMECARD(SCH_1):PAGE164
   G10     SG @TIMECARD_LIB.TIMECARD(SCH_1):SG   I138 @TIMECARD_LIB.TIMECARD(SCH_1):PAGE164
   G12     SG @TIMECARD_LIB.TIMECARD(SCH_1):SG   I138 @TIMECARD_LIB.TIMECARD(SCH_1):PAGE164
   G14     SG @TIMECARD_LIB.TIMECARD(SCH_1):SG   I138 @TIMECARD_LIB.TIMECARD(SCH_1):PAGE164
    G5     SG @TIMECARD_LIB.TIMECARD(SCH_1):SG   I138 @TIMECARD_LIB.TIMECARD(SCH_1):PAGE164
    G6     SG @TIMECARD_LIB.TIMECARD(SCH_1):SG   I138 @TIMECARD_LIB.TIMECARD(SCH_1):PAGE164
    G7     SG @TIMECARD_LIB.TIMECARD(SCH_1):SG   I138 @TIMECARD_LIB.TIMECARD(SCH_1):PAGE164
    G8     SG @TIMECARD_LIB.TIMECARD(SCH_1):SG   I138 @TIMECARD_LIB.TIMECARD(SCH_1):PAGE164
    G9     SG @TIMECARD_LIB.TIMECARD(SCH_1):SG   I138 @TIMECARD_LIB.TIMECARD(SCH_1):PAGE164
    H1     SG @TIMECARD_LIB.TIMECARD(SCH_1):SG   I138 @TIMECARD_LIB.TIMECARD(SCH_1):PAGE164
   H11     SG @TIMECARD_LIB.TIMECARD(SCH_1):SG   I138 @TIMECARD_LIB.TIMECARD(SCH_1):PAGE164
   H21     SG @TIMECARD_LIB.TIMECARD(SCH_1):SG   I138 @TIMECARD_LIB.TIMECARD(SCH_1):PAGE164
    H7     SG @TIMECARD_LIB.TIMECARD(SCH_1):SG   I138 @TIMECARD_LIB.TIMECARD(SCH_1):PAGE164
    H9     SG @TIMECARD_LIB.TIMECARD(SCH_1):SG   I138 @TIMECARD_LIB.TIMECARD(SCH_1):PAGE164
   J10     SG @TIMECARD_LIB.TIMECARD(SCH_1):SG   I138 @TIMECARD_LIB.TIMECARD(SCH_1):PAGE164
   J12     SG @TIMECARD_LIB.TIMECARD(SCH_1):SG   I138 @TIMECARD_LIB.TIMECARD(SCH_1):PAGE164
   J18     SG @TIMECARD_LIB.TIMECARD(SCH_1):SG   I138 @TIMECARD_LIB.TIMECARD(SCH_1):PAGE164
    J8     SG @TIMECARD_LIB.TIMECARD(SCH_1):SG   I138 @TIMECARD_LIB.TIMECARD(SCH_1):PAGE164
   K11     SG @TIMECARD_LIB.TIMECARD(SCH_1):SG   I138 @TIMECARD_LIB.TIMECARD(SCH_1):PAGE164
   K15     SG @TIMECARD_LIB.TIMECARD(SCH_1):SG   I138 @TIMECARD_LIB.TIMECARD(SCH_1):PAGE164
    K5     SG @TIMECARD_LIB.TIMECARD(SCH_1):SG   I138 @TIMECARD_LIB.TIMECARD(SCH_1):PAGE164
    K7     SG @TIMECARD_LIB.TIMECARD(SCH_1):SG   I138 @TIMECARD_LIB.TIMECARD(SCH_1):PAGE164
    L2     SG @TIMECARD_LIB.TIMECARD(SCH_1):SG   I138 @TIMECARD_LIB.TIMECARD(SCH_1):PAGE164
   L22     SG @TIMECARD_LIB.TIMECARD(SCH_1):SG   I138 @TIMECARD_LIB.TIMECARD(SCH_1):PAGE164
    L8     SG @TIMECARD_LIB.TIMECARD(SCH_1):SG   I138 @TIMECARD_LIB.TIMECARD(SCH_1):PAGE164
   M11     SG @TIMECARD_LIB.TIMECARD(SCH_1):SG   I138 @TIMECARD_LIB.TIMECARD(SCH_1):PAGE164
   M19     SG @TIMECARD_LIB.TIMECARD(SCH_1):SG   I138 @TIMECARD_LIB.TIMECARD(SCH_1):PAGE164
    M7     SG @TIMECARD_LIB.TIMECARD(SCH_1):SG   I138 @TIMECARD_LIB.TIMECARD(SCH_1):PAGE164
   N16     SG @TIMECARD_LIB.TIMECARD(SCH_1):SG   I138 @TIMECARD_LIB.TIMECARD(SCH_1):PAGE164
    N6     SG @TIMECARD_LIB.TIMECARD(SCH_1):SG   I138 @TIMECARD_LIB.TIMECARD(SCH_1):PAGE164
    N8     SG @TIMECARD_LIB.TIMECARD(SCH_1):SG   I138 @TIMECARD_LIB.TIMECARD(SCH_1):PAGE164
   P11     SG @TIMECARD_LIB.TIMECARD(SCH_1):SG   I138 @TIMECARD_LIB.TIMECARD(SCH_1):PAGE164
   P13     SG @TIMECARD_LIB.TIMECARD(SCH_1):SG   I138 @TIMECARD_LIB.TIMECARD(SCH_1):PAGE164
    P3     SG @TIMECARD_LIB.TIMECARD(SCH_1):SG   I138 @TIMECARD_LIB.TIMECARD(SCH_1):PAGE164
    P7     SG @TIMECARD_LIB.TIMECARD(SCH_1):SG   I138 @TIMECARD_LIB.TIMECARD(SCH_1):PAGE164
    P9     SG @TIMECARD_LIB.TIMECARD(SCH_1):SG   I138 @TIMECARD_LIB.TIMECARD(SCH_1):PAGE164
   R10     SG @TIMECARD_LIB.TIMECARD(SCH_1):SG   I138 @TIMECARD_LIB.TIMECARD(SCH_1):PAGE164
   R12     SG @TIMECARD_LIB.TIMECARD(SCH_1):SG   I138 @TIMECARD_LIB.TIMECARD(SCH_1):PAGE164
   R20     SG @TIMECARD_LIB.TIMECARD(SCH_1):SG   I138 @TIMECARD_LIB.TIMECARD(SCH_1):PAGE164
    R8     SG @TIMECARD_LIB.TIMECARD(SCH_1):SG   I138 @TIMECARD_LIB.TIMECARD(SCH_1):PAGE164
   T11     SG @TIMECARD_LIB.TIMECARD(SCH_1):SG   I138 @TIMECARD_LIB.TIMECARD(SCH_1):PAGE164
   T17     SG @TIMECARD_LIB.TIMECARD(SCH_1):SG   I138 @TIMECARD_LIB.TIMECARD(SCH_1):PAGE164
    T7     SG @TIMECARD_LIB.TIMECARD(SCH_1):SG   I138 @TIMECARD_LIB.TIMECARD(SCH_1):PAGE164
    T9     SG @TIMECARD_LIB.TIMECARD(SCH_1):SG   I138 @TIMECARD_LIB.TIMECARD(SCH_1):PAGE164
   U14     SG @TIMECARD_LIB.TIMECARD(SCH_1):SG   I138 @TIMECARD_LIB.TIMECARD(SCH_1):PAGE164
    U4     SG @TIMECARD_LIB.TIMECARD(SCH_1):SG   I138 @TIMECARD_LIB.TIMECARD(SCH_1):PAGE164
    V1     SG @TIMECARD_LIB.TIMECARD(SCH_1):SG   I138 @TIMECARD_LIB.TIMECARD(SCH_1):PAGE164
   V11     SG @TIMECARD_LIB.TIMECARD(SCH_1):SG   I138 @TIMECARD_LIB.TIMECARD(SCH_1):PAGE164
   V21     SG @TIMECARD_LIB.TIMECARD(SCH_1):SG   I138 @TIMECARD_LIB.TIMECARD(SCH_1):PAGE164
   W18     SG @TIMECARD_LIB.TIMECARD(SCH_1):SG   I138 @TIMECARD_LIB.TIMECARD(SCH_1):PAGE164
    W8     SG @TIMECARD_LIB.TIMECARD(SCH_1):SG   I138 @TIMECARD_LIB.TIMECARD(SCH_1):PAGE164
   Y15     SG @TIMECARD_LIB.TIMECARD(SCH_1):SG   I138 @TIMECARD_LIB.TIMECARD(SCH_1):PAGE164
    Y5     SG @TIMECARD_LIB.TIMECARD(SCH_1):SG   I138 @TIMECARD_LIB.TIMECARD(SCH_1):PAGE164
   D10 XP1R0V_FPGA_MGTAVCC @TIMECARD_LIB.TIMECARD(SCH_1):XP1R0V_FPGA_MGTAVCC   I138 @TIMECARD_LIB.TIMECARD(SCH_1):PAGE164
    D6 XP1R0V_FPGA_MGTAVCC @TIMECARD_LIB.TIMECARD(SCH_1):XP1R0V_FPGA_MGTAVCC   I138 @TIMECARD_LIB.TIMECARD(SCH_1):PAGE164
    E8 XP1R0V_FPGA_MGTAVCC @TIMECARD_LIB.TIMECARD(SCH_1):XP1R0V_FPGA_MGTAVCC   I138 @TIMECARD_LIB.TIMECARD(SCH_1):PAGE164
    F7 XP1R0V_FPGA_MGTAVCC @TIMECARD_LIB.TIMECARD(SCH_1):XP1R0V_FPGA_MGTAVCC   I138 @TIMECARD_LIB.TIMECARD(SCH_1):PAGE164
    F9 XP1R0V_FPGA_MGTAVCC @TIMECARD_LIB.TIMECARD(SCH_1):XP1R0V_FPGA_MGTAVCC   I138 @TIMECARD_LIB.TIMECARD(SCH_1):PAGE164
   B11 FPGA_MGTAVTT @TIMECARD_LIB.TIMECARD(SCH_1):FPGA_MGTAVTT   I138 @TIMECARD_LIB.TIMECARD(SCH_1):PAGE164
    B5 FPGA_MGTAVTT @TIMECARD_LIB.TIMECARD(SCH_1):FPGA_MGTAVTT   I138 @TIMECARD_LIB.TIMECARD(SCH_1):PAGE164
    B7 FPGA_MGTAVTT @TIMECARD_LIB.TIMECARD(SCH_1):FPGA_MGTAVTT   I138 @TIMECARD_LIB.TIMECARD(SCH_1):PAGE164
    B9 FPGA_MGTAVTT @TIMECARD_LIB.TIMECARD(SCH_1):FPGA_MGTAVTT   I138 @TIMECARD_LIB.TIMECARD(SCH_1):PAGE164
    C4 FPGA_MGTAVTT @TIMECARD_LIB.TIMECARD(SCH_1):FPGA_MGTAVTT   I138 @TIMECARD_LIB.TIMECARD(SCH_1):PAGE164
    C8 FPGA_MGTAVTT @TIMECARD_LIB.TIMECARD(SCH_1):FPGA_MGTAVTT   I138 @TIMECARD_LIB.TIMECARD(SCH_1):PAGE164
   K10 XP1R8V_FPGA_VCCAUX @TIMECARD_LIB.TIMECARD(SCH_1):XP1R8V_FPGA_VCCAUX   I138 @TIMECARD_LIB.TIMECARD(SCH_1):PAGE164
   H12 XP1R8V_FPGA_VCCAUX @TIMECARD_LIB.TIMECARD(SCH_1):XP1R8V_FPGA_VCCAUX   I138 @TIMECARD_LIB.TIMECARD(SCH_1):PAGE164
   K12 XP1R8V_FPGA_VCCAUX @TIMECARD_LIB.TIMECARD(SCH_1):XP1R8V_FPGA_VCCAUX   I138 @TIMECARD_LIB.TIMECARD(SCH_1):PAGE164
   M12 XP1R8V_FPGA_VCCAUX @TIMECARD_LIB.TIMECARD(SCH_1):XP1R8V_FPGA_VCCAUX   I138 @TIMECARD_LIB.TIMECARD(SCH_1):PAGE164
   P12 XP1R8V_FPGA_VCCAUX @TIMECARD_LIB.TIMECARD(SCH_1):XP1R8V_FPGA_VCCAUX   I138 @TIMECARD_LIB.TIMECARD(SCH_1):PAGE164
   R11 XP1R8V_FPGA_VCCAUX @TIMECARD_LIB.TIMECARD(SCH_1):XP1R8V_FPGA_VCCAUX   I138 @TIMECARD_LIB.TIMECARD(SCH_1):PAGE164
   E12 XP1R8V_FPGA_VCCAUX @TIMECARD_LIB.TIMECARD(SCH_1):XP1R8V_FPGA_VCCAUX   I138 @TIMECARD_LIB.TIMECARD(SCH_1):PAGE164
   J11 XP1R0V_FPGA_VCCINT @TIMECARD_LIB.TIMECARD(SCH_1):XP1R0V_FPGA_VCCINT   I138 @TIMECARD_LIB.TIMECARD(SCH_1):PAGE164
   L11 XP1R0V_FPGA_VCCINT @TIMECARD_LIB.TIMECARD(SCH_1):XP1R0V_FPGA_VCCINT   I138 @TIMECARD_LIB.TIMECARD(SCH_1):PAGE164
   N11 XP1R0V_FPGA_VCCINT @TIMECARD_LIB.TIMECARD(SCH_1):XP1R0V_FPGA_VCCINT   I138 @TIMECARD_LIB.TIMECARD(SCH_1):PAGE164
   H10 XP1R0V_FPGA_VCCINT @TIMECARD_LIB.TIMECARD(SCH_1):XP1R0V_FPGA_VCCINT   I138 @TIMECARD_LIB.TIMECARD(SCH_1):PAGE164
    H8 XP1R0V_FPGA_VCCINT @TIMECARD_LIB.TIMECARD(SCH_1):XP1R0V_FPGA_VCCINT   I138 @TIMECARD_LIB.TIMECARD(SCH_1):PAGE164
    J7 XP1R0V_FPGA_VCCINT @TIMECARD_LIB.TIMECARD(SCH_1):XP1R0V_FPGA_VCCINT   I138 @TIMECARD_LIB.TIMECARD(SCH_1):PAGE164
    J9 XP1R0V_FPGA_VCCINT @TIMECARD_LIB.TIMECARD(SCH_1):XP1R0V_FPGA_VCCINT   I138 @TIMECARD_LIB.TIMECARD(SCH_1):PAGE164
    K8 XP1R0V_FPGA_VCCINT @TIMECARD_LIB.TIMECARD(SCH_1):XP1R0V_FPGA_VCCINT   I138 @TIMECARD_LIB.TIMECARD(SCH_1):PAGE164
    L7 XP1R0V_FPGA_VCCINT @TIMECARD_LIB.TIMECARD(SCH_1):XP1R0V_FPGA_VCCINT   I138 @TIMECARD_LIB.TIMECARD(SCH_1):PAGE164
    M8 XP1R0V_FPGA_VCCINT @TIMECARD_LIB.TIMECARD(SCH_1):XP1R0V_FPGA_VCCINT   I138 @TIMECARD_LIB.TIMECARD(SCH_1):PAGE164
    N7 XP1R0V_FPGA_VCCINT @TIMECARD_LIB.TIMECARD(SCH_1):XP1R0V_FPGA_VCCINT   I138 @TIMECARD_LIB.TIMECARD(SCH_1):PAGE164
   P10 XP1R0V_FPGA_VCCINT @TIMECARD_LIB.TIMECARD(SCH_1):XP1R0V_FPGA_VCCINT   I138 @TIMECARD_LIB.TIMECARD(SCH_1):PAGE164
    P8 XP1R0V_FPGA_VCCINT @TIMECARD_LIB.TIMECARD(SCH_1):XP1R0V_FPGA_VCCINT   I138 @TIMECARD_LIB.TIMECARD(SCH_1):PAGE164
    R7 XP1R0V_FPGA_VCCINT @TIMECARD_LIB.TIMECARD(SCH_1):XP1R0V_FPGA_VCCINT   I138 @TIMECARD_LIB.TIMECARD(SCH_1):PAGE164
    R9 XP1R0V_FPGA_VCCINT @TIMECARD_LIB.TIMECARD(SCH_1):XP1R0V_FPGA_VCCINT   I138 @TIMECARD_LIB.TIMECARD(SCH_1):PAGE164
   T10 XP1R0V_FPGA_VCCINT @TIMECARD_LIB.TIMECARD(SCH_1):XP1R0V_FPGA_VCCINT   I138 @TIMECARD_LIB.TIMECARD(SCH_1):PAGE164
    T8 XP1R0V_FPGA_VCCINT @TIMECARD_LIB.TIMECARD(SCH_1):XP1R0V_FPGA_VCCINT   I138 @TIMECARD_LIB.TIMECARD(SCH_1):PAGE164
   F12 XP3R3V_FPGA @TIMECARD_LIB.TIMECARD(SCH_1):XP3R3V_FPGA   I138 @TIMECARD_LIB.TIMECARD(SCH_1):PAGE164
   T12 XP3R3V_FPGA @TIMECARD_LIB.TIMECARD(SCH_1):XP3R3V_FPGA   I138 @TIMECARD_LIB.TIMECARD(SCH_1):PAGE164
  AA17 XP3R3V_FPGA @TIMECARD_LIB.TIMECARD(SCH_1):XP3R3V_FPGA   I138 @TIMECARD_LIB.TIMECARD(SCH_1):PAGE164
  AB14 XP3R3V_FPGA @TIMECARD_LIB.TIMECARD(SCH_1):XP3R3V_FPGA   I138 @TIMECARD_LIB.TIMECARD(SCH_1):PAGE164
   V16 XP3R3V_FPGA @TIMECARD_LIB.TIMECARD(SCH_1):XP3R3V_FPGA   I138 @TIMECARD_LIB.TIMECARD(SCH_1):PAGE164
   W13 XP3R3V_FPGA @TIMECARD_LIB.TIMECARD(SCH_1):XP3R3V_FPGA   I138 @TIMECARD_LIB.TIMECARD(SCH_1):PAGE164
   Y10 XP3R3V_FPGA @TIMECARD_LIB.TIMECARD(SCH_1):XP3R3V_FPGA   I138 @TIMECARD_LIB.TIMECARD(SCH_1):PAGE164
   M14 XP3R3V_FPGA @TIMECARD_LIB.TIMECARD(SCH_1):XP3R3V_FPGA   I138 @TIMECARD_LIB.TIMECARD(SCH_1):PAGE164
   P18 XP3R3V_FPGA @TIMECARD_LIB.TIMECARD(SCH_1):XP3R3V_FPGA   I138 @TIMECARD_LIB.TIMECARD(SCH_1):PAGE164
   R15 XP3R3V_FPGA @TIMECARD_LIB.TIMECARD(SCH_1):XP3R3V_FPGA   I138 @TIMECARD_LIB.TIMECARD(SCH_1):PAGE164
   T22 XP3R3V_FPGA @TIMECARD_LIB.TIMECARD(SCH_1):XP3R3V_FPGA   I138 @TIMECARD_LIB.TIMECARD(SCH_1):PAGE164
   U19 XP3R3V_FPGA @TIMECARD_LIB.TIMECARD(SCH_1):XP3R3V_FPGA   I138 @TIMECARD_LIB.TIMECARD(SCH_1):PAGE164
   Y20 XP3R3V_FPGA @TIMECARD_LIB.TIMECARD(SCH_1):XP3R3V_FPGA   I138 @TIMECARD_LIB.TIMECARD(SCH_1):PAGE164
   G19 XP3R3V_FPGA @TIMECARD_LIB.TIMECARD(SCH_1):XP3R3V_FPGA   I138 @TIMECARD_LIB.TIMECARD(SCH_1):PAGE164
   H16 XP3R3V_FPGA @TIMECARD_LIB.TIMECARD(SCH_1):XP3R3V_FPGA   I138 @TIMECARD_LIB.TIMECARD(SCH_1):PAGE164
   J13 XP3R3V_FPGA @TIMECARD_LIB.TIMECARD(SCH_1):XP3R3V_FPGA   I138 @TIMECARD_LIB.TIMECARD(SCH_1):PAGE164
   K20 XP3R3V_FPGA @TIMECARD_LIB.TIMECARD(SCH_1):XP3R3V_FPGA   I138 @TIMECARD_LIB.TIMECARD(SCH_1):PAGE164
   L17 XP3R3V_FPGA @TIMECARD_LIB.TIMECARD(SCH_1):XP3R3V_FPGA   I138 @TIMECARD_LIB.TIMECARD(SCH_1):PAGE164
   N21 XP3R3V_FPGA @TIMECARD_LIB.TIMECARD(SCH_1):XP3R3V_FPGA   I138 @TIMECARD_LIB.TIMECARD(SCH_1):PAGE164
   A17 XP3R3V_FPGA @TIMECARD_LIB.TIMECARD(SCH_1):XP3R3V_FPGA   I138 @TIMECARD_LIB.TIMECARD(SCH_1):PAGE164
   B14 XP3R3V_FPGA @TIMECARD_LIB.TIMECARD(SCH_1):XP3R3V_FPGA   I138 @TIMECARD_LIB.TIMECARD(SCH_1):PAGE164
   C21 XP3R3V_FPGA @TIMECARD_LIB.TIMECARD(SCH_1):XP3R3V_FPGA   I138 @TIMECARD_LIB.TIMECARD(SCH_1):PAGE164
   D18 XP3R3V_FPGA @TIMECARD_LIB.TIMECARD(SCH_1):XP3R3V_FPGA   I138 @TIMECARD_LIB.TIMECARD(SCH_1):PAGE164
   E15 XP3R3V_FPGA @TIMECARD_LIB.TIMECARD(SCH_1):XP3R3V_FPGA   I138 @TIMECARD_LIB.TIMECARD(SCH_1):PAGE164
   F22 XP3R3V_FPGA @TIMECARD_LIB.TIMECARD(SCH_1):XP3R3V_FPGA   I138 @TIMECARD_LIB.TIMECARD(SCH_1):PAGE164
   AA7 XP2R5V_FPGA @TIMECARD_LIB.TIMECARD(SCH_1):XP2R5V_FPGA   I138 @TIMECARD_LIB.TIMECARD(SCH_1):PAGE164
   AB4 XP2R5V_FPGA @TIMECARD_LIB.TIMECARD(SCH_1):XP2R5V_FPGA   I138 @TIMECARD_LIB.TIMECARD(SCH_1):PAGE164
    R5 XP2R5V_FPGA @TIMECARD_LIB.TIMECARD(SCH_1):XP2R5V_FPGA   I138 @TIMECARD_LIB.TIMECARD(SCH_1):PAGE164
    T2 XP2R5V_FPGA @TIMECARD_LIB.TIMECARD(SCH_1):XP2R5V_FPGA   I138 @TIMECARD_LIB.TIMECARD(SCH_1):PAGE164
    V6 XP2R5V_FPGA @TIMECARD_LIB.TIMECARD(SCH_1):XP2R5V_FPGA   I138 @TIMECARD_LIB.TIMECARD(SCH_1):PAGE164
    W3 XP2R5V_FPGA @TIMECARD_LIB.TIMECARD(SCH_1):XP2R5V_FPGA   I138 @TIMECARD_LIB.TIMECARD(SCH_1):PAGE164
    C1 XP2R5V_FPGA @TIMECARD_LIB.TIMECARD(SCH_1):XP2R5V_FPGA   I138 @TIMECARD_LIB.TIMECARD(SCH_1):PAGE164
    F2 XP2R5V_FPGA @TIMECARD_LIB.TIMECARD(SCH_1):XP2R5V_FPGA   I138 @TIMECARD_LIB.TIMECARD(SCH_1):PAGE164
    H6 XP2R5V_FPGA @TIMECARD_LIB.TIMECARD(SCH_1):XP2R5V_FPGA   I138 @TIMECARD_LIB.TIMECARD(SCH_1):PAGE164
    J3 XP2R5V_FPGA @TIMECARD_LIB.TIMECARD(SCH_1):XP2R5V_FPGA   I138 @TIMECARD_LIB.TIMECARD(SCH_1):PAGE164
    M4 XP2R5V_FPGA @TIMECARD_LIB.TIMECARD(SCH_1):XP2R5V_FPGA   I138 @TIMECARD_LIB.TIMECARD(SCH_1):PAGE164
    N1 XP2R5V_FPGA @TIMECARD_LIB.TIMECARD(SCH_1):XP2R5V_FPGA   I138 @TIMECARD_LIB.TIMECARD(SCH_1):PAGE164

 U25 ISL80101IRAJZ_DFN10-G222-10136A
     1 XP2R5V_FPGA @TIMECARD_LIB.TIMECARD(SCH_1):XP2R5V_FPGA   I151 @TIMECARD_LIB.TIMECARD(SCH_1):PAGE515
     2 XP2R5V_FPGA @TIMECARD_LIB.TIMECARD(SCH_1):XP2R5V_FPGA   I151 @TIMECARD_LIB.TIMECARD(SCH_1):PAGE515
     3 UNNAMED_515_ISL80101IRAJZDFN10_ @TIMECARD_LIB.TIMECARD(SCH_1):UNNAMED_515_ISL80101IRAJZDFN10_I151_SENSE   I151 @TIMECARD_LIB.TIMECARD(SCH_1):PAGE515
     4 UNNAMED_515_CAPACITOR_I138_1 @TIMECARD_LIB.TIMECARD(SCH_1):UNNAMED_515_CAPACITOR_I138_1   I151 @TIMECARD_LIB.TIMECARD(SCH_1):PAGE515
     5     SG @TIMECARD_LIB.TIMECARD(SCH_1):SG   I151 @TIMECARD_LIB.TIMECARD(SCH_1):PAGE515
     6 UNNAMED_515_CAPACITOR_I132_1 @TIMECARD_LIB.TIMECARD(SCH_1):UNNAMED_515_CAPACITOR_I132_1   I151 @TIMECARD_LIB.TIMECARD(SCH_1):PAGE515
     7 UNNAMED_515_CAPACITOR_I128_1 @TIMECARD_LIB.TIMECARD(SCH_1):UNNAMED_515_CAPACITOR_I128_1   I151 @TIMECARD_LIB.TIMECARD(SCH_1):PAGE515
     8     NC     NC   I151 @TIMECARD_LIB.TIMECARD(SCH_1):PAGE515
     9 UNNAMED_515_CAPACITOR_I130_1 @TIMECARD_LIB.TIMECARD(SCH_1):UNNAMED_515_CAPACITOR_I130_1   I151 @TIMECARD_LIB.TIMECARD(SCH_1):PAGE515
    10 UNNAMED_515_CAPACITOR_I130_1 @TIMECARD_LIB.TIMECARD(SCH_1):UNNAMED_515_CAPACITOR_I130_1   I151 @TIMECARD_LIB.TIMECARD(SCH_1):PAGE515
    11     SG @TIMECARD_LIB.TIMECARD(SCH_1):SG   I151 @TIMECARD_LIB.TIMECARD(SCH_1):PAGE515

 U26 TPS54824RNVR_VQFN18-G220-10657A
     1 XP1R0V_BT @TIMECARD_LIB.TIMECARD(SCH_1):XP1R0V_BT    I11 @TIMECARD_LIB.TIMECARD(SCH_1):PAGE523
     2 VIN_XP1R0V @TIMECARD_LIB.TIMECARD(SCH_1):VIN_XP1R0V    I11 @TIMECARD_LIB.TIMECARD(SCH_1):PAGE523
     3     SG @TIMECARD_LIB.TIMECARD(SCH_1):SG    I11 @TIMECARD_LIB.TIMECARD(SCH_1):PAGE523
     4     SG @TIMECARD_LIB.TIMECARD(SCH_1):SG    I11 @TIMECARD_LIB.TIMECARD(SCH_1):PAGE523
     5     SG @TIMECARD_LIB.TIMECARD(SCH_1):SG    I11 @TIMECARD_LIB.TIMECARD(SCH_1):PAGE523
     6 XP1R0V_SW @TIMECARD_LIB.TIMECARD(SCH_1):XP1R0V_SW    I11 @TIMECARD_LIB.TIMECARD(SCH_1):PAGE523
     7 XP1R0V_SW @TIMECARD_LIB.TIMECARD(SCH_1):XP1R0V_SW    I11 @TIMECARD_LIB.TIMECARD(SCH_1):PAGE523
     8     SG @TIMECARD_LIB.TIMECARD(SCH_1):SG    I11 @TIMECARD_LIB.TIMECARD(SCH_1):PAGE523
     9     SG @TIMECARD_LIB.TIMECARD(SCH_1):SG    I11 @TIMECARD_LIB.TIMECARD(SCH_1):PAGE523
    10     SG @TIMECARD_LIB.TIMECARD(SCH_1):SG    I11 @TIMECARD_LIB.TIMECARD(SCH_1):PAGE523
    11 VIN_XP1R0V @TIMECARD_LIB.TIMECARD(SCH_1):VIN_XP1R0V    I11 @TIMECARD_LIB.TIMECARD(SCH_1):PAGE523
    12 XP1R0V_AGND @TIMECARD_LIB.TIMECARD(SCH_1):XP1R0V_AGND    I11 @TIMECARD_LIB.TIMECARD(SCH_1):PAGE523
    13 XP1R0V_RT @TIMECARD_LIB.TIMECARD(SCH_1):XP1R0V_RT    I11 @TIMECARD_LIB.TIMECARD(SCH_1):PAGE523
    14 XP1R0V_FB_R_TO_AGND @TIMECARD_LIB.TIMECARD(SCH_1):XP1R0V_FB_R_TO_AGND    I11 @TIMECARD_LIB.TIMECARD(SCH_1):PAGE523
    15 XP1R0V_COMP @TIMECARD_LIB.TIMECARD(SCH_1):XP1R0V_COMP    I11 @TIMECARD_LIB.TIMECARD(SCH_1):PAGE523
    16 XP1R0V_SS @TIMECARD_LIB.TIMECARD(SCH_1):XP1R0V_SS    I11 @TIMECARD_LIB.TIMECARD(SCH_1):PAGE523
    17 UNNAMED_523_CAPACITOR_I7_1 @TIMECARD_LIB.TIMECARD(SCH_1):UNNAMED_523_CAPACITOR_I7_1    I11 @TIMECARD_LIB.TIMECARD(SCH_1):PAGE523
    18 XP1R0V_PG @TIMECARD_LIB.TIMECARD(SCH_1):XP1R0V_PG    I11 @TIMECARD_LIB.TIMECARD(SCH_1):PAGE523

 U27 SHT31A_DIS_B10KS_DFN8-A222-000A
     1 R_SHT3X_I2C_SDA @TIMECARD_LIB.TIMECARD(SCH_1):R_SHT3X_I2C_SDA    I44 @TIMECARD_LIB.TIMECARD(SCH_1):PAGE7
     2 SHT3X_ADDR @TIMECARD_LIB.TIMECARD(SCH_1):SHT3X_ADDR    I44 @TIMECARD_LIB.TIMECARD(SCH_1):PAGE7
     3 R_SHT3X_ALERT_N @TIMECARD_LIB.TIMECARD(SCH_1):R_SHT3X_ALERT_N    I44 @TIMECARD_LIB.TIMECARD(SCH_1):PAGE7
     4 R_SHT3X_I2C_SCL @TIMECARD_LIB.TIMECARD(SCH_1):R_SHT3X_I2C_SCL    I44 @TIMECARD_LIB.TIMECARD(SCH_1):PAGE7
     5 VDD3V3_SHT31A @TIMECARD_LIB.TIMECARD(SCH_1):VDD3V3_SHT31A    I44 @TIMECARD_LIB.TIMECARD(SCH_1):PAGE7
     6 R_SHT3X_RST_N @TIMECARD_LIB.TIMECARD(SCH_1):R_SHT3X_RST_N    I44 @TIMECARD_LIB.TIMECARD(SCH_1):PAGE7
     7     SG @TIMECARD_LIB.TIMECARD(SCH_1):SG    I44 @TIMECARD_LIB.TIMECARD(SCH_1):PAGE7
     8     SG @TIMECARD_LIB.TIMECARD(SCH_1):SG    I44 @TIMECARD_LIB.TIMECARD(SCH_1):PAGE7
     9     SG @TIMECARD_LIB.TIMECARD(SCH_1):SG    I44 @TIMECARD_LIB.TIMECARD(SCH_1):PAGE7

 U28 ICP_10100_LGA10-A222-00002-FB,A
     1 UNNAMED_8_ICP10100LGA10_I24_RES @TIMECARD_LIB.TIMECARD(SCH_1):UNNAMED_8_ICP10100LGA10_I24_RESV1    I24 @TIMECARD_LIB.TIMECARD(SCH_1):PAGE8
     2 R_ICP10100_I2C_SCL @TIMECARD_LIB.TIMECARD(SCH_1):R_ICP10100_I2C_SCL    I24 @TIMECARD_LIB.TIMECARD(SCH_1):PAGE8
     3 UNNAMED_8_ICP10100LGA10_I24_R_1 @TIMECARD_LIB.TIMECARD(SCH_1):UNNAMED_8_ICP10100LGA10_I24_RESV2    I24 @TIMECARD_LIB.TIMECARD(SCH_1):PAGE8
     4 R_ICP10100_I2C_SDA @TIMECARD_LIB.TIMECARD(SCH_1):R_ICP10100_I2C_SDA    I24 @TIMECARD_LIB.TIMECARD(SCH_1):PAGE8
     5 UNNAMED_8_ICP10100LGA10_I24_R_2 @TIMECARD_LIB.TIMECARD(SCH_1):UNNAMED_8_ICP10100LGA10_I24_RESV3    I24 @TIMECARD_LIB.TIMECARD(SCH_1):PAGE8
     6 UNNAMED_8_ICP10100LGA10_I24_R_3 @TIMECARD_LIB.TIMECARD(SCH_1):UNNAMED_8_ICP10100LGA10_I24_RESV4    I24 @TIMECARD_LIB.TIMECARD(SCH_1):PAGE8
     7 UNNAMED_8_ICP10100LGA10_I24_R_4 @TIMECARD_LIB.TIMECARD(SCH_1):UNNAMED_8_ICP10100LGA10_I24_RESV5    I24 @TIMECARD_LIB.TIMECARD(SCH_1):PAGE8
     8     SG @TIMECARD_LIB.TIMECARD(SCH_1):SG    I24 @TIMECARD_LIB.TIMECARD(SCH_1):PAGE8
     9     SG @TIMECARD_LIB.TIMECARD(SCH_1):SG    I24 @TIMECARD_LIB.TIMECARD(SCH_1):PAGE8
    10 XP1R8V_ICP10100 @TIMECARD_LIB.TIMECARD(SCH_1):XP1R8V_ICP10100    I24 @TIMECARD_LIB.TIMECARD(SCH_1):PAGE8

 U29 BNO080_LGA_28-A246-00002-FB,BNA
     4 R_BNO080_BOOT_N @TIMECARD_LIB.TIMECARD(SCH_1):R_BNO080_BOOT_N    I29 @TIMECARD_LIB.TIMECARD(SCH_1):PAGE9
     9 UNNAMED_9_BNO080LGA28_I29_CAP @TIMECARD_LIB.TIMECARD(SCH_1):UNNAMED_9_BNO080LGA28_I29_CAP    I29 @TIMECARD_LIB.TIMECARD(SCH_1):PAGE9
    10 UNNAMED_9_BNO080LGA28_I29_CLKSE @TIMECARD_LIB.TIMECARD(SCH_1):UNNAMED_9_BNO080LGA28_I29_CLKSEL0    I29 @TIMECARD_LIB.TIMECARD(SCH_1):PAGE9
    15 R_BNO080_EVN_SCL @TIMECARD_LIB.TIMECARD(SCH_1):R_BNO080_EVN_SCL    I29 @TIMECARD_LIB.TIMECARD(SCH_1):PAGE9
    16 R_BNO080_EVN_SDA @TIMECARD_LIB.TIMECARD(SCH_1):R_BNO080_EVN_SDA    I29 @TIMECARD_LIB.TIMECARD(SCH_1):PAGE9
     2     SG @TIMECARD_LIB.TIMECARD(SCH_1):SG    I29 @TIMECARD_LIB.TIMECARD(SCH_1):PAGE9
    25     SG @TIMECARD_LIB.TIMECARD(SCH_1):SG    I29 @TIMECARD_LIB.TIMECARD(SCH_1):PAGE9
    18 UNNAMED_9_BNO080LGA28_I29_HCS @TIMECARD_LIB.TIMECARD(SCH_1):UNNAMED_9_BNO080LGA28_I29_HCS    I29 @TIMECARD_LIB.TIMECARD(SCH_1):PAGE9
    14 R_BNO080_INT_N @TIMECARD_LIB.TIMECARD(SCH_1):R_BNO080_INT_N    I29 @TIMECARD_LIB.TIMECARD(SCH_1):PAGE9
    19 R_BNO080_I2C_SCL @TIMECARD_LIB.TIMECARD(SCH_1):R_BNO080_I2C_SCL    I29 @TIMECARD_LIB.TIMECARD(SCH_1):PAGE9
    20 R_BNO080_I2C_SDA @TIMECARD_LIB.TIMECARD(SCH_1):R_BNO080_I2C_SDA    I29 @TIMECARD_LIB.TIMECARD(SCH_1):PAGE9
    11 R_BNO080_RST_N @TIMECARD_LIB.TIMECARD(SCH_1):R_BNO080_RST_N    I29 @TIMECARD_LIB.TIMECARD(SCH_1):PAGE9
     6 UNNAMED_9_BNO080LGA28_I29_PS0 @TIMECARD_LIB.TIMECARD(SCH_1):UNNAMED_9_BNO080LGA28_I29_PS0    I29 @TIMECARD_LIB.TIMECARD(SCH_1):PAGE9
     5 UNNAMED_9_BNO080LGA28_I29_PS1 @TIMECARD_LIB.TIMECARD(SCH_1):UNNAMED_9_BNO080LGA28_I29_PS1    I29 @TIMECARD_LIB.TIMECARD(SCH_1):PAGE9
     1     NC     NC    I29 @TIMECARD_LIB.TIMECARD(SCH_1):PAGE9
     7     NC     NC    I29 @TIMECARD_LIB.TIMECARD(SCH_1):PAGE9
     8     NC     NC    I29 @TIMECARD_LIB.TIMECARD(SCH_1):PAGE9
    12     NC     NC    I29 @TIMECARD_LIB.TIMECARD(SCH_1):PAGE9
    13     NC     NC    I29 @TIMECARD_LIB.TIMECARD(SCH_1):PAGE9
    21     NC     NC    I29 @TIMECARD_LIB.TIMECARD(SCH_1):PAGE9
    22     NC     NC    I29 @TIMECARD_LIB.TIMECARD(SCH_1):PAGE9
    23     NC     NC    I29 @TIMECARD_LIB.TIMECARD(SCH_1):PAGE9
    24     NC     NC    I29 @TIMECARD_LIB.TIMECARD(SCH_1):PAGE9
    17 BNO080_SA0 @TIMECARD_LIB.TIMECARD(SCH_1):BNO080_SA0    I29 @TIMECARD_LIB.TIMECARD(SCH_1):PAGE9
     3 VDD_BNO085 @TIMECARD_LIB.TIMECARD(SCH_1):VDD_BNO085    I29 @TIMECARD_LIB.TIMECARD(SCH_1):PAGE9
    28 VDD_BNO085 @TIMECARD_LIB.TIMECARD(SCH_1):VDD_BNO085    I29 @TIMECARD_LIB.TIMECARD(SCH_1):PAGE9
    27 UNNAMED_9_CAPACITOR_I17_1 @TIMECARD_LIB.TIMECARD(SCH_1):UNNAMED_9_CAPACITOR_I17_1    I29 @TIMECARD_LIB.TIMECARD(SCH_1):PAGE9
    26 UNNAMED_9_BNO080LGA28_I29_XOUT3 @TIMECARD_LIB.TIMECARD(SCH_1):UNNAMED_9_BNO080LGA28_I29_XOUT32    I29 @TIMECARD_LIB.TIMECARD(SCH_1):PAGE9

 U30 TS3A5018PWR_TSSOP16-G220-10324A
     4 FT4232_TCK_SCLK @TIMECARD_LIB.TIMECARD(SCH_1):FT4232_TCK_SCLK   I425 @TIMECARD_LIB.TIMECARD(SCH_1):PAGE524
     7 FT4232_TDI_MOSI @TIMECARD_LIB.TIMECARD(SCH_1):FT4232_TDI_MOSI   I425 @TIMECARD_LIB.TIMECARD(SCH_1):PAGE524
     9 FT4232_TDO_MISO @TIMECARD_LIB.TIMECARD(SCH_1):FT4232_TDO_MISO   I425 @TIMECARD_LIB.TIMECARD(SCH_1):PAGE524
    12 FT4232_TMS_SPICS_N @TIMECARD_LIB.TIMECARD(SCH_1):FT4232_TMS_SPICS_N   I425 @TIMECARD_LIB.TIMECARD(SCH_1):PAGE524
    15 UNNAMED_524_POWERMOS3PNCHV1_I44 @TIMECARD_LIB.TIMECARD(SCH_1):UNNAMED_524_POWERMOS3PNCHV1_I445_D   I425 @TIMECARD_LIB.TIMECARD(SCH_1):PAGE524
     1 MUX1_SEL @TIMECARD_LIB.TIMECARD(SCH_1):MUX1_SEL   I425 @TIMECARD_LIB.TIMECARD(SCH_1):PAGE524
     2 FT4232_FPGA_TCK @TIMECARD_LIB.TIMECARD(SCH_1):FT4232_FPGA_TCK   I425 @TIMECARD_LIB.TIMECARD(SCH_1):PAGE524
     5 FT4232_FPGA_TDI @TIMECARD_LIB.TIMECARD(SCH_1):FT4232_FPGA_TDI   I425 @TIMECARD_LIB.TIMECARD(SCH_1):PAGE524
    11 FT4232_FPGA_TDO @TIMECARD_LIB.TIMECARD(SCH_1):FT4232_FPGA_TDO   I425 @TIMECARD_LIB.TIMECARD(SCH_1):PAGE524
    14 FT4232_FPGA_TMS @TIMECARD_LIB.TIMECARD(SCH_1):FT4232_FPGA_TMS   I425 @TIMECARD_LIB.TIMECARD(SCH_1):PAGE524
     3 FT4232_SPI_CLK @TIMECARD_LIB.TIMECARD(SCH_1):FT4232_SPI_CLK   I425 @TIMECARD_LIB.TIMECARD(SCH_1):PAGE524
     6 FT4232_SPI_MOSI @TIMECARD_LIB.TIMECARD(SCH_1):FT4232_SPI_MOSI   I425 @TIMECARD_LIB.TIMECARD(SCH_1):PAGE524
    10 FT4232_SPI_MISO @TIMECARD_LIB.TIMECARD(SCH_1):FT4232_SPI_MISO   I425 @TIMECARD_LIB.TIMECARD(SCH_1):PAGE524
    13 FT4232_SPI_CS_N @TIMECARD_LIB.TIMECARD(SCH_1):FT4232_SPI_CS_N   I425 @TIMECARD_LIB.TIMECARD(SCH_1):PAGE524
     8     SG @TIMECARD_LIB.TIMECARD(SCH_1):SG   I473 @TIMECARD_LIB.TIMECARD(SCH_1):PAGE524
    16 XP3R3V_FPGA @TIMECARD_LIB.TIMECARD(SCH_1):XP3R3V_FPGA   I473 @TIMECARD_LIB.TIMECARD(SCH_1):PAGE524

 U31 CAT93C46VI_GT3_SOIC8-G221-1007A
     1 FTDI_EE_CS @TIMECARD_LIB.TIMECARD(SCH_1):FTDI_EE_CS   I200 @TIMECARD_LIB.TIMECARD(SCH_1):PAGE524
     2 FTDI_EE_CLK @TIMECARD_LIB.TIMECARD(SCH_1):FTDI_EE_CLK   I200 @TIMECARD_LIB.TIMECARD(SCH_1):PAGE524
     3 FTDI_EE_DAT @TIMECARD_LIB.TIMECARD(SCH_1):FTDI_EE_DAT   I200 @TIMECARD_LIB.TIMECARD(SCH_1):PAGE524
     4 FTDI_EE_DO @TIMECARD_LIB.TIMECARD(SCH_1):FTDI_EE_DO   I200 @TIMECARD_LIB.TIMECARD(SCH_1):PAGE524
     6 XP3R3V_FT4232 @TIMECARD_LIB.TIMECARD(SCH_1):XP3R3V_FT4232   I200 @TIMECARD_LIB.TIMECARD(SCH_1):PAGE524
     7     NC     NC   I200 @TIMECARD_LIB.TIMECARD(SCH_1):PAGE524
     8 XP3R3V_FT4232 @TIMECARD_LIB.TIMECARD(SCH_1):XP3R3V_FT4232   I201 @TIMECARD_LIB.TIMECARD(SCH_1):PAGE524
     5     SG @TIMECARD_LIB.TIMECARD(SCH_1):SG   I201 @TIMECARD_LIB.TIMECARD(SCH_1):PAGE524

 U32 PCA9508DP_TSSOP8-G223-10278-01
     2 BF_ICP10100_I2C_SCL @TIMECARD_LIB.TIMECARD(SCH_1):BF_ICP10100_I2C_SCL    I51 @TIMECARD_LIB.TIMECARD(SCH_1):PAGE8
     3 BF_ICP10100_I2C_SDA @TIMECARD_LIB.TIMECARD(SCH_1):BF_ICP10100_I2C_SDA    I51 @TIMECARD_LIB.TIMECARD(SCH_1):PAGE8
     5 UNNAMED_8_PCA9508DPTSSOP8_I51_E @TIMECARD_LIB.TIMECARD(SCH_1):UNNAMED_8_PCA9508DPTSSOP8_I51_EN    I51 @TIMECARD_LIB.TIMECARD(SCH_1):PAGE8
     6 ICP10100_I2C_SDA @TIMECARD_LIB.TIMECARD(SCH_1):ICP10100_I2C_SDA    I51 @TIMECARD_LIB.TIMECARD(SCH_1):PAGE8
     7 ICP10100_I2C_SCL @TIMECARD_LIB.TIMECARD(SCH_1):ICP10100_I2C_SCL    I51 @TIMECARD_LIB.TIMECARD(SCH_1):PAGE8
     1 XP1R8V_ICP10100 @TIMECARD_LIB.TIMECARD(SCH_1):XP1R8V_ICP10100    I52 @TIMECARD_LIB.TIMECARD(SCH_1):PAGE8
     4     SG @TIMECARD_LIB.TIMECARD(SCH_1):SG    I52 @TIMECARD_LIB.TIMECARD(SCH_1):PAGE8
     8 XP3R3V @TIMECARD_LIB.TIMECARD(SCH_1):XP3R3V    I52 @TIMECARD_LIB.TIMECARD(SCH_1):PAGE8

 U33 IS32FL3207_QWLA3_TR_QFN29-A223A
     1 RGB_LED_SHUTDOWN_N @TIMECARD_LIB.TIMECARD(SCH_1):RGB_LED_SHUTDOWN_N   I219 @TIMECARD_LIB.TIMECARD(SCH_1):PAGE14
     2 UNNAMED_14_IS32FL3207QWLA3TRQFN @TIMECARD_LIB.TIMECARD(SCH_1):UNNAMED_14_IS32FL3207QWLA3TRQFN29_I219_AD   I219 @TIMECARD_LIB.TIMECARD(SCH_1):PAGE14
     3 XP3R3V_FPGA @TIMECARD_LIB.TIMECARD(SCH_1):XP3R3V_FPGA   I219 @TIMECARD_LIB.TIMECARD(SCH_1):PAGE14
     4     SG @TIMECARD_LIB.TIMECARD(SCH_1):SG   I219 @TIMECARD_LIB.TIMECARD(SCH_1):PAGE14
     5 UNNAMED_14_IS32FL3207QWLA3TRQ_1 @TIMECARD_LIB.TIMECARD(SCH_1):UNNAMED_14_IS32FL3207QWLA3TRQFN29_I219_ISET   I219 @TIMECARD_LIB.TIMECARD(SCH_1):PAGE14
     6 R_RGB_LED_I2C_SDA @TIMECARD_LIB.TIMECARD(SCH_1):R_RGB_LED_I2C_SDA   I219 @TIMECARD_LIB.TIMECARD(SCH_1):PAGE14
     7 R_RGB_LED_I2C_SCL @TIMECARD_LIB.TIMECARD(SCH_1):R_RGB_LED_I2C_SCL   I219 @TIMECARD_LIB.TIMECARD(SCH_1):PAGE14
     8 SMA1_LED_GREEN_N @TIMECARD_LIB.TIMECARD(SCH_1):SMA1_LED_GREEN_N   I219 @TIMECARD_LIB.TIMECARD(SCH_1):PAGE14
     9 SMA1_LED_RED_N @TIMECARD_LIB.TIMECARD(SCH_1):SMA1_LED_RED_N   I219 @TIMECARD_LIB.TIMECARD(SCH_1):PAGE14
    10 SMA1_LED_BLUE_N @TIMECARD_LIB.TIMECARD(SCH_1):SMA1_LED_BLUE_N   I219 @TIMECARD_LIB.TIMECARD(SCH_1):PAGE14
    11     SG @TIMECARD_LIB.TIMECARD(SCH_1):SG   I219 @TIMECARD_LIB.TIMECARD(SCH_1):PAGE14
    12 SMA2_LED_GREEN_N @TIMECARD_LIB.TIMECARD(SCH_1):SMA2_LED_GREEN_N   I219 @TIMECARD_LIB.TIMECARD(SCH_1):PAGE14
    13 SMA2_LED_RED_N @TIMECARD_LIB.TIMECARD(SCH_1):SMA2_LED_RED_N   I219 @TIMECARD_LIB.TIMECARD(SCH_1):PAGE14
    14 SMA2_LED_BLUE_N @TIMECARD_LIB.TIMECARD(SCH_1):SMA2_LED_BLUE_N   I219 @TIMECARD_LIB.TIMECARD(SCH_1):PAGE14
    15 SMA3_LED_GREEN_N @TIMECARD_LIB.TIMECARD(SCH_1):SMA3_LED_GREEN_N   I219 @TIMECARD_LIB.TIMECARD(SCH_1):PAGE14
    16 SMA3_LED_RED_N @TIMECARD_LIB.TIMECARD(SCH_1):SMA3_LED_RED_N   I219 @TIMECARD_LIB.TIMECARD(SCH_1):PAGE14
    17 SMA3_LED_BLUE_N @TIMECARD_LIB.TIMECARD(SCH_1):SMA3_LED_BLUE_N   I219 @TIMECARD_LIB.TIMECARD(SCH_1):PAGE14
    18     SG @TIMECARD_LIB.TIMECARD(SCH_1):SG   I219 @TIMECARD_LIB.TIMECARD(SCH_1):PAGE14
    19 SMA4_LED_GREEN_N @TIMECARD_LIB.TIMECARD(SCH_1):SMA4_LED_GREEN_N   I219 @TIMECARD_LIB.TIMECARD(SCH_1):PAGE14
    20 SMA4_LED_RED_N @TIMECARD_LIB.TIMECARD(SCH_1):SMA4_LED_RED_N   I219 @TIMECARD_LIB.TIMECARD(SCH_1):PAGE14
    21 SMA4_LED_BLUE_N @TIMECARD_LIB.TIMECARD(SCH_1):SMA4_LED_BLUE_N   I219 @TIMECARD_LIB.TIMECARD(SCH_1):PAGE14
    22 GPS_SMA_LED_GREEN_N @TIMECARD_LIB.TIMECARD(SCH_1):GPS_SMA_LED_GREEN_N   I219 @TIMECARD_LIB.TIMECARD(SCH_1):PAGE14
    23 GPS_SMA_LED_RED_N @TIMECARD_LIB.TIMECARD(SCH_1):GPS_SMA_LED_RED_N   I219 @TIMECARD_LIB.TIMECARD(SCH_1):PAGE14
    24 GPS_SMA_LED_BLUE_N @TIMECARD_LIB.TIMECARD(SCH_1):GPS_SMA_LED_BLUE_N   I219 @TIMECARD_LIB.TIMECARD(SCH_1):PAGE14
    25     SG @TIMECARD_LIB.TIMECARD(SCH_1):SG   I219 @TIMECARD_LIB.TIMECARD(SCH_1):PAGE14
    26     NC     NC   I219 @TIMECARD_LIB.TIMECARD(SCH_1):PAGE14
    27     NC     NC   I219 @TIMECARD_LIB.TIMECARD(SCH_1):PAGE14
    28     NC     NC   I219 @TIMECARD_LIB.TIMECARD(SCH_1):PAGE14
    29     SG @TIMECARD_LIB.TIMECARD(SCH_1):SG   I219 @TIMECARD_LIB.TIMECARD(SCH_1):PAGE14

 U34 TPS3808G18DBVR_SOT23_6-G222-00A
     1 FPGA_IN_RST_DLY_N @TIMECARD_LIB.TIMECARD(SCH_1):FPGA_IN_RST_DLY_N   I139 @TIMECARD_LIB.TIMECARD(SCH_1):PAGE3
     2     SG @TIMECARD_LIB.TIMECARD(SCH_1):SG   I139 @TIMECARD_LIB.TIMECARD(SCH_1):PAGE3
     3 PCIE_PERST_N @TIMECARD_LIB.TIMECARD(SCH_1):PCIE_PERST_N   I139 @TIMECARD_LIB.TIMECARD(SCH_1):PAGE3
     4 UNNAMED_3_RESISTOR_I151_2 @TIMECARD_LIB.TIMECARD(SCH_1):UNNAMED_3_RESISTOR_I151_2   I139 @TIMECARD_LIB.TIMECARD(SCH_1):PAGE3
     5 XP3R3V_FPGA @TIMECARD_LIB.TIMECARD(SCH_1):XP3R3V_FPGA   I139 @TIMECARD_LIB.TIMECARD(SCH_1):PAGE3
     6 XP3R3V_FPGA @TIMECARD_LIB.TIMECARD(SCH_1):XP3R3V_FPGA   I139 @TIMECARD_LIB.TIMECARD(SCH_1):PAGE3

 U35 LM75BDP_TSSOP8-G220-10215-01
     1 R_LM75B_2_I2C_SDA @TIMECARD_LIB.TIMECARD(SCH_1):R_LM75B_2_I2C_SDA    I59 @TIMECARD_LIB.TIMECARD(SCH_1):PAGE6
     2 LM75B_I2C_SCL @TIMECARD_LIB.TIMECARD(SCH_1):LM75B_I2C_SCL    I59 @TIMECARD_LIB.TIMECARD(SCH_1):PAGE6
     3 FPGA_IN_LM75B_INT2_N @TIMECARD_LIB.TIMECARD(SCH_1):FPGA_IN_LM75B_INT2_N    I59 @TIMECARD_LIB.TIMECARD(SCH_1):PAGE6
     5 UNNAMED_6_LM75BDPTSSOP8_I59_A2 @TIMECARD_LIB.TIMECARD(SCH_1):UNNAMED_6_LM75BDPTSSOP8_I59_A2    I59 @TIMECARD_LIB.TIMECARD(SCH_1):PAGE6
     6 UNNAMED_6_LM75BDPTSSOP8_I59_A1 @TIMECARD_LIB.TIMECARD(SCH_1):UNNAMED_6_LM75BDPTSSOP8_I59_A1    I59 @TIMECARD_LIB.TIMECARD(SCH_1):PAGE6
     7 UNNAMED_6_LM75BDPTSSOP8_I59_A0 @TIMECARD_LIB.TIMECARD(SCH_1):UNNAMED_6_LM75BDPTSSOP8_I59_A0    I59 @TIMECARD_LIB.TIMECARD(SCH_1):PAGE6
     8 XP3R3V_FPGA @TIMECARD_LIB.TIMECARD(SCH_1):XP3R3V_FPGA    I90 @TIMECARD_LIB.TIMECARD(SCH_1):PAGE6
     4     SG @TIMECARD_LIB.TIMECARD(SCH_1):SG    I90 @TIMECARD_LIB.TIMECARD(SCH_1):PAGE6

 U36 LM75BDP_TSSOP8-G220-10215-01
     1 R_LM75B_3_I2C_SDA @TIMECARD_LIB.TIMECARD(SCH_1):R_LM75B_3_I2C_SDA    I81 @TIMECARD_LIB.TIMECARD(SCH_1):PAGE6
     2 LM75B_I2C_SCL @TIMECARD_LIB.TIMECARD(SCH_1):LM75B_I2C_SCL    I81 @TIMECARD_LIB.TIMECARD(SCH_1):PAGE6
     3 FPGA_IN_LM75B_INT3_N @TIMECARD_LIB.TIMECARD(SCH_1):FPGA_IN_LM75B_INT3_N    I81 @TIMECARD_LIB.TIMECARD(SCH_1):PAGE6
     5 UNNAMED_6_LM75BDPTSSOP8_I81_A2 @TIMECARD_LIB.TIMECARD(SCH_1):UNNAMED_6_LM75BDPTSSOP8_I81_A2    I81 @TIMECARD_LIB.TIMECARD(SCH_1):PAGE6
     6 UNNAMED_6_LM75BDPTSSOP8_I81_A1 @TIMECARD_LIB.TIMECARD(SCH_1):UNNAMED_6_LM75BDPTSSOP8_I81_A1    I81 @TIMECARD_LIB.TIMECARD(SCH_1):PAGE6
     7 UNNAMED_6_LM75BDPTSSOP8_I81_A0 @TIMECARD_LIB.TIMECARD(SCH_1):UNNAMED_6_LM75BDPTSSOP8_I81_A0    I81 @TIMECARD_LIB.TIMECARD(SCH_1):PAGE6
     8 XP3R3V_FPGA @TIMECARD_LIB.TIMECARD(SCH_1):XP3R3V_FPGA    I66 @TIMECARD_LIB.TIMECARD(SCH_1):PAGE6
     4     SG @TIMECARD_LIB.TIMECARD(SCH_1):SG    I66 @TIMECARD_LIB.TIMECARD(SCH_1):PAGE6

 U37 TS3A5018PWR_TSSOP16-G220-10324A
     4 PCA9546_I2C_SDA @TIMECARD_LIB.TIMECARD(SCH_1):PCA9546_I2C_SDA   I448 @TIMECARD_LIB.TIMECARD(SCH_1):PAGE524
     7 PCA9546_I2C_SCL @TIMECARD_LIB.TIMECARD(SCH_1):PCA9546_I2C_SCL   I448 @TIMECARD_LIB.TIMECARD(SCH_1):PAGE524
     9 EEPROM_I2C_SDA @TIMECARD_LIB.TIMECARD(SCH_1):EEPROM_I2C_SDA   I448 @TIMECARD_LIB.TIMECARD(SCH_1):PAGE524
    12 EEPROM_I2C_SCL @TIMECARD_LIB.TIMECARD(SCH_1):EEPROM_I2C_SCL   I448 @TIMECARD_LIB.TIMECARD(SCH_1):PAGE524
    15 UNNAMED_524_RESISTOR_I463_2 @TIMECARD_LIB.TIMECARD(SCH_1):UNNAMED_524_RESISTOR_I463_2   I448 @TIMECARD_LIB.TIMECARD(SCH_1):PAGE524
     1 MUX3_SEL @TIMECARD_LIB.TIMECARD(SCH_1):MUX3_SEL   I448 @TIMECARD_LIB.TIMECARD(SCH_1):PAGE524
     2 FPGA_PCA9546_I2C_SDA @TIMECARD_LIB.TIMECARD(SCH_1):FPGA_PCA9546_I2C_SDA   I448 @TIMECARD_LIB.TIMECARD(SCH_1):PAGE524
     5 FPGA_PCA9546_I2C_SCL @TIMECARD_LIB.TIMECARD(SCH_1):FPGA_PCA9546_I2C_SCL   I448 @TIMECARD_LIB.TIMECARD(SCH_1):PAGE524
    11 FPGA_EEPROM_I2C_SDA @TIMECARD_LIB.TIMECARD(SCH_1):FPGA_EEPROM_I2C_SDA   I448 @TIMECARD_LIB.TIMECARD(SCH_1):PAGE524
    14 FPGA_EEPROM_I2C_SCL @TIMECARD_LIB.TIMECARD(SCH_1):FPGA_EEPROM_I2C_SCL   I448 @TIMECARD_LIB.TIMECARD(SCH_1):PAGE524
     3 FT4232_I2C_SDA @TIMECARD_LIB.TIMECARD(SCH_1):FT4232_I2C_SDA   I448 @TIMECARD_LIB.TIMECARD(SCH_1):PAGE524
     6 FT4232_I2C_SCL @TIMECARD_LIB.TIMECARD(SCH_1):FT4232_I2C_SCL   I448 @TIMECARD_LIB.TIMECARD(SCH_1):PAGE524
    10 FT4232_I2C_SDA @TIMECARD_LIB.TIMECARD(SCH_1):FT4232_I2C_SDA   I448 @TIMECARD_LIB.TIMECARD(SCH_1):PAGE524
    13 FT4232_I2C_SCL @TIMECARD_LIB.TIMECARD(SCH_1):FT4232_I2C_SCL   I448 @TIMECARD_LIB.TIMECARD(SCH_1):PAGE524
     8     SG @TIMECARD_LIB.TIMECARD(SCH_1):SG   I478 @TIMECARD_LIB.TIMECARD(SCH_1):PAGE524
    16 XP3R3V_FPGA @TIMECARD_LIB.TIMECARD(SCH_1):XP3R3V_FPGA   I478 @TIMECARD_LIB.TIMECARD(SCH_1):PAGE524

 U38 TS3A5018PWR_TSSOP16-G220-10324A
     4 FLASH_CLK @TIMECARD_LIB.TIMECARD(SCH_1):FLASH_CLK   I400 @TIMECARD_LIB.TIMECARD(SCH_1):PAGE524
     7 FLASH_DQ0_MOSI @TIMECARD_LIB.TIMECARD(SCH_1):FLASH_DQ0_MOSI   I400 @TIMECARD_LIB.TIMECARD(SCH_1):PAGE524
     9 FLASH_DQ1_MISO @TIMECARD_LIB.TIMECARD(SCH_1):FLASH_DQ1_MISO   I400 @TIMECARD_LIB.TIMECARD(SCH_1):PAGE524
    12 FLASH_CS_N @TIMECARD_LIB.TIMECARD(SCH_1):FLASH_CS_N   I400 @TIMECARD_LIB.TIMECARD(SCH_1):PAGE524
    15 UNNAMED_524_RESISTOR_I432_2 @TIMECARD_LIB.TIMECARD(SCH_1):UNNAMED_524_RESISTOR_I432_2   I400 @TIMECARD_LIB.TIMECARD(SCH_1):PAGE524
     1 MUX2_SEL @TIMECARD_LIB.TIMECARD(SCH_1):MUX2_SEL   I400 @TIMECARD_LIB.TIMECARD(SCH_1):PAGE524
     2 FPGA_FLASH_CLK @TIMECARD_LIB.TIMECARD(SCH_1):FPGA_FLASH_CLK   I400 @TIMECARD_LIB.TIMECARD(SCH_1):PAGE524
     5 FPGA_FLASH_DQ0_MOSI @TIMECARD_LIB.TIMECARD(SCH_1):FPGA_FLASH_DQ0_MOSI   I400 @TIMECARD_LIB.TIMECARD(SCH_1):PAGE524
    11 FPGA_FLASH_DQ1_MISO @TIMECARD_LIB.TIMECARD(SCH_1):FPGA_FLASH_DQ1_MISO   I400 @TIMECARD_LIB.TIMECARD(SCH_1):PAGE524
    14 FPGA_FLASH_CS_N @TIMECARD_LIB.TIMECARD(SCH_1):FPGA_FLASH_CS_N   I400 @TIMECARD_LIB.TIMECARD(SCH_1):PAGE524
     3 FT4232_SPI_CLK @TIMECARD_LIB.TIMECARD(SCH_1):FT4232_SPI_CLK   I400 @TIMECARD_LIB.TIMECARD(SCH_1):PAGE524
     6 FT4232_SPI_MOSI @TIMECARD_LIB.TIMECARD(SCH_1):FT4232_SPI_MOSI   I400 @TIMECARD_LIB.TIMECARD(SCH_1):PAGE524
    10 FT4232_SPI_MISO @TIMECARD_LIB.TIMECARD(SCH_1):FT4232_SPI_MISO   I400 @TIMECARD_LIB.TIMECARD(SCH_1):PAGE524
    13 FT4232_SPI_CS_N @TIMECARD_LIB.TIMECARD(SCH_1):FT4232_SPI_CS_N   I400 @TIMECARD_LIB.TIMECARD(SCH_1):PAGE524
     8     SG @TIMECARD_LIB.TIMECARD(SCH_1):SG   I481 @TIMECARD_LIB.TIMECARD(SCH_1):PAGE524
    16 XP3R3V_FPGA @TIMECARD_LIB.TIMECARD(SCH_1):XP3R3V_FPGA   I481 @TIMECARD_LIB.TIMECARD(SCH_1):PAGE524

 U39 NLASB3157DFT2G_SC88-G223-10187A
     1     NC     NC   I407 @TIMECARD_LIB.TIMECARD(SCH_1):PAGE524
     3 FLASH_DQ2 @TIMECARD_LIB.TIMECARD(SCH_1):FLASH_DQ2   I407 @TIMECARD_LIB.TIMECARD(SCH_1):PAGE524
     4 FPGA_FLASH_DQ2 @TIMECARD_LIB.TIMECARD(SCH_1):FPGA_FLASH_DQ2   I407 @TIMECARD_LIB.TIMECARD(SCH_1):PAGE524
     6 MUX2_SEL @TIMECARD_LIB.TIMECARD(SCH_1):MUX2_SEL   I407 @TIMECARD_LIB.TIMECARD(SCH_1):PAGE524
     2     SG @TIMECARD_LIB.TIMECARD(SCH_1):SG   I485 @TIMECARD_LIB.TIMECARD(SCH_1):PAGE524
     5 XP3R3V_FPGA @TIMECARD_LIB.TIMECARD(SCH_1):XP3R3V_FPGA   I485 @TIMECARD_LIB.TIMECARD(SCH_1):PAGE524

 U40 NLASB3157DFT2G_SC88-G223-10187A
     1     NC     NC   I408 @TIMECARD_LIB.TIMECARD(SCH_1):PAGE524
     3 FLASH_DQ3 @TIMECARD_LIB.TIMECARD(SCH_1):FLASH_DQ3   I408 @TIMECARD_LIB.TIMECARD(SCH_1):PAGE524
     4 FPGA_FLASH_DQ3 @TIMECARD_LIB.TIMECARD(SCH_1):FPGA_FLASH_DQ3   I408 @TIMECARD_LIB.TIMECARD(SCH_1):PAGE524
     6 MUX2_SEL @TIMECARD_LIB.TIMECARD(SCH_1):MUX2_SEL   I408 @TIMECARD_LIB.TIMECARD(SCH_1):PAGE524
     2     SG @TIMECARD_LIB.TIMECARD(SCH_1):SG   I491 @TIMECARD_LIB.TIMECARD(SCH_1):PAGE524
     5 XP3R3V_FPGA @TIMECARD_LIB.TIMECARD(SCH_1):XP3R3V_FPGA   I491 @TIMECARD_LIB.TIMECARD(SCH_1):PAGE524

 U41 ISL80101IRAJZ_DFN10-G222-10136A
     1 XP3R3V_FT4232 @TIMECARD_LIB.TIMECARD(SCH_1):XP3R3V_FT4232    I29 @TIMECARD_LIB.TIMECARD(SCH_1):PAGE525
     2 XP3R3V_FT4232 @TIMECARD_LIB.TIMECARD(SCH_1):XP3R3V_FT4232    I29 @TIMECARD_LIB.TIMECARD(SCH_1):PAGE525
     3 UNNAMED_525_ISL80101IRAJZDFN10_ @TIMECARD_LIB.TIMECARD(SCH_1):UNNAMED_525_ISL80101IRAJZDFN10_I29_SENSE    I29 @TIMECARD_LIB.TIMECARD(SCH_1):PAGE525
     4 XP3R3V_FT_PG @TIMECARD_LIB.TIMECARD(SCH_1):XP3R3V_FT_PG    I29 @TIMECARD_LIB.TIMECARD(SCH_1):PAGE525
     5     SG @TIMECARD_LIB.TIMECARD(SCH_1):SG    I29 @TIMECARD_LIB.TIMECARD(SCH_1):PAGE525
     6 UNNAMED_525_CAPACITOR_I18_1 @TIMECARD_LIB.TIMECARD(SCH_1):UNNAMED_525_CAPACITOR_I18_1    I29 @TIMECARD_LIB.TIMECARD(SCH_1):PAGE525
     7 UNNAMED_525_CAPACITOR_I14_1 @TIMECARD_LIB.TIMECARD(SCH_1):UNNAMED_525_CAPACITOR_I14_1    I29 @TIMECARD_LIB.TIMECARD(SCH_1):PAGE525
     8     NC     NC    I29 @TIMECARD_LIB.TIMECARD(SCH_1):PAGE525
     9 UNNAMED_525_CAPACITOR_I16_1 @TIMECARD_LIB.TIMECARD(SCH_1):UNNAMED_525_CAPACITOR_I16_1    I29 @TIMECARD_LIB.TIMECARD(SCH_1):PAGE525
    10 UNNAMED_525_CAPACITOR_I16_1 @TIMECARD_LIB.TIMECARD(SCH_1):UNNAMED_525_CAPACITOR_I16_1    I29 @TIMECARD_LIB.TIMECARD(SCH_1):PAGE525
    11     SG @TIMECARD_LIB.TIMECARD(SCH_1):SG    I29 @TIMECARD_LIB.TIMECARD(SCH_1):PAGE525

  Y1 XTAL_2-G131-10075-01
     1 UNNAMED_9_BNO080LGA28_I29_XOUT3 @TIMECARD_LIB.TIMECARD(SCH_1):UNNAMED_9_BNO080LGA28_I29_XOUT32    I16 @TIMECARD_LIB.TIMECARD(SCH_1):PAGE9
     2 UNNAMED_9_CAPACITOR_I17_1 @TIMECARD_LIB.TIMECARD(SCH_1):UNNAMED_9_CAPACITOR_I17_1    I16 @TIMECARD_LIB.TIMECARD(SCH_1):PAGE9

  Y2 XTAL_4-G131-10038-02
     1 UNNAMED_524_CAPACITOR_I7_2 @TIMECARD_LIB.TIMECARD(SCH_1):UNNAMED_524_CAPACITOR_I7_2     I8 @TIMECARD_LIB.TIMECARD(SCH_1):PAGE524
     2     SG @TIMECARD_LIB.TIMECARD(SCH_1):SG     I8 @TIMECARD_LIB.TIMECARD(SCH_1):PAGE524
     3 UNNAMED_524_CAPACITOR_I10_2 @TIMECARD_LIB.TIMECARD(SCH_1):UNNAMED_524_CAPACITOR_I10_2     I8 @TIMECARD_LIB.TIMECARD(SCH_1):PAGE524
     4     SG @TIMECARD_LIB.TIMECARD(SCH_1):SG     I8 @TIMECARD_LIB.TIMECARD(SCH_1):PAGE524

  Y3 OSC6P_V2-A130-00003-AW
     1 CLK_200M_OE @TIMECARD_LIB.TIMECARD(SCH_1):CLK_200M_OE   I144 @TIMECARD_LIB.TIMECARD(SCH_1):PAGE522
     2     NC     NC   I144 @TIMECARD_LIB.TIMECARD(SCH_1):PAGE522
     3     SG @TIMECARD_LIB.TIMECARD(SCH_1):SG   I144 @TIMECARD_LIB.TIMECARD(SCH_1):PAGE522
     4 OSC_200M_CLKP @TIMECARD_LIB.TIMECARD(SCH_1):OSC_200M_CLKP   I144 @TIMECARD_LIB.TIMECARD(SCH_1):PAGE522
     5 OSC_200M_CLKN @TIMECARD_LIB.TIMECARD(SCH_1):OSC_200M_CLKN   I144 @TIMECARD_LIB.TIMECARD(SCH_1):PAGE522
     6 VDD3V3_OSC_200M @TIMECARD_LIB.TIMECARD(SCH_1):VDD3V3_OSC_200M   I144 @TIMECARD_LIB.TIMECARD(SCH_1):PAGE522

  Y4 OSC6P_V2-A130-00004-AW
     1 CLK_125M_OE @TIMECARD_LIB.TIMECARD(SCH_1):CLK_125M_OE   I145 @TIMECARD_LIB.TIMECARD(SCH_1):PAGE522
     2     NC     NC   I145 @TIMECARD_LIB.TIMECARD(SCH_1):PAGE522
     3     SG @TIMECARD_LIB.TIMECARD(SCH_1):SG   I145 @TIMECARD_LIB.TIMECARD(SCH_1):PAGE522
     4 OSC_125M_CLKP @TIMECARD_LIB.TIMECARD(SCH_1):OSC_125M_CLKP   I145 @TIMECARD_LIB.TIMECARD(SCH_1):PAGE522
     5 OSC_125M_CLKN @TIMECARD_LIB.TIMECARD(SCH_1):OSC_125M_CLKN   I145 @TIMECARD_LIB.TIMECARD(SCH_1):PAGE522
     6 VDD3V3_OSC_125M @TIMECARD_LIB.TIMECARD(SCH_1):VDD3V3_OSC_125M   I145 @TIMECARD_LIB.TIMECARD(SCH_1):PAGE522

END GLOBAL PART CROSS REFERENCE
